G04 ================== begin FILE IDENTIFICATION RECORD ==================*
G04 Layout Name:  D:/<user>/Wistron_project/16315-1/gbr/16315-1.brd*
G04 Film Name:    DRILL*
G04 File Format:  Gerber RS274X*
G04 File Origin:  Cadence Allegro 16.5-S056*
G04 Origin Date:  Fri Jun 09 15:30:28 2017*
G04 *
G04 Layer:  MANUFACTURING/NCLEGEND-1-12*
G04 Layer:  MANUFACTURING/DRILL SIZE*
G04 Layer:  DRAWING FORMAT/LAYER_PCB_STORY*
G04 Layer:  DRAWING FORMAT/LAYER_DRILL*
G04 Layer:  BOARD GEOMETRY/PANEL_OUTLINE*
G04 *
G04 Offset:    (0.00 0.00)*
G04 Mirror:    No*
G04 Mode:      Positive*
G04 Rotation:  0*
G04 FullContactRelief:  No*
G04 UndefLineWidth:     6.00*
G04 ================== end FILE IDENTIFICATION RECORD ====================*
%FSLAX35Y35*MOIN*%
%IR0*IPPOS*OFA0.00000B0.00000*MIA0B0*SFA1.00000B1.00000*%
%AMMACRO21*
1,1,.006,.005,.005*
20,1,.006,.005,.005,.005,-.005,0.0*
1,1,.006,.005,-.005*
20,1,.006,.005,-.005,-.005,-.005,0.0*
1,1,.006,-.005,-.005*
20,1,.006,-.005,-.005,-.005,.005,0.0*
1,1,.006,-.005,.005*
20,1,.006,-.005,.005,.005,.005,0.0*
1,1,.006,.005,.005*
1,1,.006,-.00158,.00167*
20,1,.006,-.00158,.00167,-.00108,.00217,0.0*
1,1,.006,-.00108,.00217*
20,1,.006,-.00108,.00217,-.0005,.00242,0.0*
1,1,.006,-.0005,.00242*
20,1,.006,-.0005,.00242,.00017,.0025,0.0*
1,1,.006,.00017,.0025*
20,1,.006,.00017,.0025,.001,.00233,0.0*
1,1,.006,.001,.00233*
20,1,.006,.001,.00233,.00158,.00192,0.0*
1,1,.006,.00158,.00192*
20,1,.006,.00158,.00192,.00175,.00142,0.0*
1,1,.006,.00175,.00142*
20,1,.006,.00175,.00142,.00167,.00092,0.0*
1,1,.006,.00167,.00092*
20,1,.006,.00167,.00092,.00133,.0005,0.0*
1,1,.006,.00133,.0005*
20,1,.006,.00133,.0005,-.00033,-.00033,0.0*
1,1,.006,-.00033,-.00033*
20,1,.006,-.00033,-.00033,-.00108,-.00092,0.0*
1,1,.006,-.00108,-.00092*
20,1,.006,-.00108,-.00092,-.00158,-.00175,0.0*
1,1,.006,-.00158,-.00175*
20,1,.006,-.00158,-.00175,-.00175,-.0025,0.0*
1,1,.006,-.00175,-.0025*
20,1,.006,-.00175,-.0025,.00175,-.0025,0.0*
1,1,.006,.00175,-.0025*
%
%ADD21MACRO21*%
%AMMACRO20*
1,1,.006,.0005,0.0*
20,1,.006,.0005,0.0,-.0005,0.0,0.0*
1,1,.006,-.0005,0.0*
1,1,.006,0.0,.0005*
20,1,.006,0.0,.0005,0.0,-.0005,0.0*
1,1,.006,0.0,-.0005*
1,1,.006,.00025,0.0*
20,1,.006,.00025,0.0,.00025,.0005,0.0*
1,1,.006,.00025,.0005*
20,1,.006,.00025,.0005,.00015,.0004,0.0*
1,1,.006,.00015,.0004*
1,1,.006,.00015,0.0*
20,1,.006,.00015,0.0,.00035,0.0,0.0*
1,1,.006,.00035,0.0*
%
%ADD20MACRO20*%
%AMMACRO22*
1,1,.006,.01866,.00467*
20,1,.006,.01866,.00467,.028,.01167,0.0*
1,1,.006,.028,.01167*
20,1,.006,.028,.01167,.035,.02333,0.0*
1,1,.006,.035,.02333*
20,1,.006,.035,.02333,.03967,.03967,0.0*
1,1,.006,.03967,.03967*
20,1,.006,.03967,.03967,.035,.05367,0.0*
1,1,.006,.035,.05367*
20,1,.006,.035,.05367,.02567,.063,0.0*
1,1,.006,.02567,.063*
20,1,.006,.02567,.063,.00933,.07,0.0*
1,1,.006,.00933,.07*
20,1,.006,.00933,.07,-.05367,.07,0.0*
1,1,.006,-.05367,.07*
20,1,.006,-.05367,.07,-.05367,-.07,0.0*
1,1,.006,-.05367,-.07*
20,1,.006,-.05367,-.07,.02333,-.07,0.0*
1,1,.006,.02333,-.07*
20,1,.006,.02333,-.07,.03967,-.06067,0.0*
1,1,.006,.03967,-.06067*
20,1,.006,.03967,-.06067,.049,-.04667,0.0*
1,1,.006,.049,-.04667*
20,1,.006,.049,-.04667,.05367,-.03033,0.0*
1,1,.006,.05367,-.03033*
20,1,.006,.05367,-.03033,.049,-.014,0.0*
1,1,.006,.049,-.014*
20,1,.006,.049,-.014,.035,0.0,0.0*
1,1,.006,.035,0.0*
20,1,.006,.035,0.0,.01866,.00467,0.0*
1,1,.006,.01866,.00467*
20,1,.006,.01866,.00467,-.05367,.00467,0.0*
1,1,.006,-.05367,.00467*
%
%ADD22MACRO22*%
%AMMACRO11*
1,1,.006,.008,0.0*
20,1,.006,.008,0.0,0.0,-.008,0.0*
1,1,.006,0.0,-.008*
20,1,.006,0.0,-.008,-.008,0.0,0.0*
1,1,.006,-.008,0.0*
20,1,.006,-.008,0.0,0.0,.008,0.0*
1,1,.006,0.0,.008*
20,1,.006,0.0,.008,.008,0.0,0.0*
1,1,.006,.008,0.0*
1,1,.006,-.00253,-.00067*
20,1,.006,-.00253,-.00067,-.0016,.00027,0.0*
1,1,.006,-.0016,.00027*
20,1,.006,-.0016,.00027,-.0008,.0008,0.0*
1,1,.006,-.0008,.0008*
20,1,.006,-.0008,.0008,.00027,.00107,0.0*
1,1,.006,.00027,.00107*
20,1,.006,.00027,.00107,.0012,.0008,0.0*
1,1,.006,.0012,.0008*
20,1,.006,.0012,.0008,.00187,.00027,0.0*
1,1,.006,.00187,.00027*
20,1,.006,.00187,.00027,.0024,-.00053,0.0*
1,1,.006,.0024,-.00053*
20,1,.006,.0024,-.00053,.00253,-.00147,0.0*
1,1,.006,.00253,-.00147*
20,1,.006,.00253,-.00147,.0024,-.00227,0.0*
1,1,.006,.0024,-.00227*
20,1,.006,.0024,-.00227,.00187,-.00307,0.0*
1,1,.006,.00187,-.00307*
20,1,.006,.00187,-.00307,.00107,-.00373,0.0*
1,1,.006,.00107,-.00373*
20,1,.006,.00107,-.00373,.00013,-.004,0.0*
1,1,.006,.00013,-.004*
20,1,.006,.00013,-.004,-.00093,-.00373,0.0*
1,1,.006,-.00093,-.00373*
20,1,.006,-.00093,-.00373,-.00187,-.00293,0.0*
1,1,.006,-.00187,-.00293*
20,1,.006,-.00187,-.00293,-.0024,-.00173,0.0*
1,1,.006,-.0024,-.00173*
20,1,.006,-.0024,-.00173,-.00253,-.0004,0.0*
1,1,.006,-.00253,-.0004*
20,1,.006,-.00253,-.0004,-.00227,.00133,0.0*
1,1,.006,-.00227,.00133*
20,1,.006,-.00227,.00133,-.00187,.00227,0.0*
1,1,.006,-.00187,.00227*
20,1,.006,-.00187,.00227,-.0012,.0032,0.0*
1,1,.006,-.0012,.0032*
20,1,.006,-.0012,.0032,-.00027,.00387,0.0*
1,1,.006,-.00027,.00387*
20,1,.006,-.00027,.00387,.00067,.004,0.0*
1,1,.006,.00067,.004*
20,1,.006,.00067,.004,.0016,.00373,0.0*
1,1,.006,.0016,.00373*
20,1,.006,.0016,.00373,.00227,.00307,0.0*
1,1,.006,.00227,.00307*
%
%ADD11MACRO11*%
%AMMACRO23*
1,1,.006,-.0481,-.0555*
20,1,.006,-.0481,-.0555,-.0481,.0555,0.0*
1,1,.006,-.0481,.0555*
20,1,.006,-.0481,.0555,0.0,-.037,0.0*
1,1,.006,0.0,-.037*
20,1,.006,0.0,-.037,.0481,.0555,0.0*
1,1,.006,.0481,.0555*
20,1,.006,.0481,.0555,.0481,-.0555,0.0*
1,1,.006,.0481,-.0555*
%
%ADD23MACRO23*%
%AMMACRO24*
1,1,.006,.002935,-.007085*
20,1,.006,.002935,-.007085,-.002935,-.007085,0.0*
1,1,.006,-.002935,-.007085*
20,1,.006,-.002935,-.007085,-.007085,-.002935,0.0*
1,1,.006,-.007085,-.002935*
20,1,.006,-.007085,-.002935,-.007085,.002935,0.0*
1,1,.006,-.007085,.002935*
20,1,.006,-.007085,.002935,-.002935,.007085,0.0*
1,1,.006,-.002935,.007085*
20,1,.006,-.002935,.007085,.002935,.007085,0.0*
1,1,.006,.002935,.007085*
20,1,.006,.002935,.007085,.007085,.002935,0.0*
1,1,.006,.007085,.002935*
20,1,.006,.007085,.002935,.007085,-.002935,0.0*
1,1,.006,.007085,-.002935*
20,1,.006,.007085,-.002935,.002935,-.007085,0.0*
1,1,.006,.002935,-.007085*
1,1,.006,-.0026,-.00248*
20,1,.006,-.0026,-.00248,-.00189,-.00307,0.0*
1,1,.006,-.00189,-.00307*
20,1,.006,-.00189,-.00307,-.00106,-.00342,0.0*
1,1,.006,-.00106,-.00342*
20,1,.006,-.00106,-.00342,0.0,-.00354,0.0*
1,1,.006,0.0,-.00354*
20,1,.006,0.0,-.00354,.00106,-.0033,0.0*
1,1,.006,.00106,-.0033*
20,1,.006,.00106,-.0033,.00189,-.00283,0.0*
1,1,.006,.00189,-.00283*
20,1,.006,.00189,-.00283,.00248,-.00201,0.0*
1,1,.006,.00248,-.00201*
20,1,.006,.00248,-.00201,.0026,-.00106,0.0*
1,1,.006,.0026,-.00106*
20,1,.006,.0026,-.00106,.00236,-.00012,0.0*
1,1,.006,.00236,-.00012*
20,1,.006,.00236,-.00012,.00177,.00047,0.0*
1,1,.006,.00177,.00047*
20,1,.006,.00177,.00047,.00094,.00094,0.0*
1,1,.006,.00094,.00094*
20,1,.006,.00094,.00094,.00012,.00106,0.0*
1,1,.006,.00012,.00106*
20,1,.006,.00012,.00106,-.00071,.00094,0.0*
1,1,.006,-.00071,.00094*
20,1,.006,-.00071,.00094,-.00177,.00047,0.0*
1,1,.006,-.00177,.00047*
20,1,.006,-.00177,.00047,-.00142,.00354,0.0*
1,1,.006,-.00142,.00354*
20,1,.006,-.00142,.00354,.00177,.00354,0.0*
1,1,.006,.00177,.00354*
%
%ADD24MACRO24*%
%AMMACRO16*
1,1,.006,.075,-.1125*
20,1,.006,.075,-.1125,-.075,-.1125,0.0*
1,1,.006,-.075,-.1125*
20,1,.006,-.075,-.1125,-.075,.1125,0.0*
1,1,.006,-.075,.1125*
20,1,.006,-.075,.1125,.075,.1125,0.0*
1,1,.006,.075,.1125*
1,1,.006,.015,.00375*
20,1,.006,.015,.00375,-.075,.00375,0.0*
1,1,.006,-.075,.00375*
%
%ADD16MACRO16*%
%AMMACRO36*
1,1,.006,-.0575,-.069*
20,1,.006,-.0575,-.069,0.0,.069,0.0*
1,1,.006,0.0,.069*
20,1,.006,0.0,.069,.0575,-.069,0.0*
1,1,.006,.0575,-.069*
1,1,.006,.0368,-.0207*
20,1,.006,.0368,-.0207,-.0368,-.0207,0.0*
1,1,.006,-.0368,-.0207*
%
%ADD36MACRO36*%
%AMMACRO19*
1,1,.006,.0053,0.0*
20,1,.006,.0053,0.0,.02297,0.0,0.0*
1,1,.006,.02297,0.0*
20,1,.006,.02297,0.0,.02297,-.0159,0.0*
1,1,.006,.02297,-.0159*
20,1,.006,.02297,-.0159,.01767,-.0212,0.0*
1,1,.006,.01767,-.0212*
20,1,.006,.01767,-.0212,.01148,-.02473,0.0*
1,1,.006,.01148,-.02473*
20,1,.006,.01148,-.02473,.00265,-.0265,0.0*
1,1,.006,.00265,-.0265*
20,1,.006,.00265,-.0265,-.00618,-.02473,0.0*
1,1,.006,-.00618,-.02473*
20,1,.006,-.00618,-.02473,-.01237,-.0212,0.0*
1,1,.006,-.01237,-.0212*
20,1,.006,-.01237,-.0212,-.01767,-.0159,0.0*
1,1,.006,-.01767,-.0159*
20,1,.006,-.01767,-.0159,-.0212,-.00972,0.0*
1,1,.006,-.0212,-.00972*
20,1,.006,-.0212,-.00972,-.02297,-.00265,0.0*
1,1,.006,-.02297,-.00265*
20,1,.006,-.02297,-.00265,-.02297,.00353,0.0*
1,1,.006,-.02297,.00353*
20,1,.006,-.02297,.00353,-.0212,.00883,0.0*
1,1,.006,-.0212,.00883*
20,1,.006,-.0212,.00883,-.01767,.01502,0.0*
1,1,.006,-.01767,.01502*
20,1,.006,-.01767,.01502,-.01237,.02032,0.0*
1,1,.006,-.01237,.02032*
20,1,.006,-.01237,.02032,-.00707,.02385,0.0*
1,1,.006,-.00707,.02385*
20,1,.006,-.00707,.02385,0.0,.0265,0.0*
1,1,.006,0.0,.0265*
20,1,.006,0.0,.0265,.00618,.0265,0.0*
1,1,.006,.00618,.0265*
20,1,.006,.00618,.0265,.01325,.02473,0.0*
1,1,.006,.01325,.02473*
20,1,.006,.01325,.02473,.01855,.0212,0.0*
1,1,.006,.01855,.0212*
%
%ADD19MACRO19*%
%AMMACRO10*
1,1,.006,.06087,.06916*
20,1,.006,.06087,.06916,.04426,.07747,0.0*
1,1,.006,.04426,.07747*
20,1,.006,.04426,.07747,.0249,.083,0.0*
1,1,.006,.0249,.083*
20,1,.006,.0249,.083,.00277,.083,0.0*
1,1,.006,.00277,.083*
20,1,.006,.00277,.083,-.02214,.0747,0.0*
1,1,.006,-.02214,.0747*
20,1,.006,-.02214,.0747,-.0415,.06087,0.0*
1,1,.006,-.0415,.06087*
20,1,.006,-.0415,.06087,-.05533,.04426,0.0*
1,1,.006,-.05533,.04426*
20,1,.006,-.05533,.04426,-.0664,.0166,0.0*
1,1,.006,-.0664,.0166*
20,1,.006,-.0664,.0166,-.06917,-.0083,0.0*
1,1,.006,-.06917,-.0083*
20,1,.006,-.06917,-.0083,-.06363,-.0332,0.0*
1,1,.006,-.06363,-.0332*
20,1,.006,-.06363,-.0332,-.05533,-.0498,0.0*
1,1,.006,-.05533,-.0498*
20,1,.006,-.05533,-.0498,-.03873,-.0664,0.0*
1,1,.006,-.03873,-.0664*
20,1,.006,-.03873,-.0664,-.01937,-.07747,0.0*
1,1,.006,-.01937,-.07747*
20,1,.006,-.01937,-.07747,0.0,-.083,0.0*
1,1,.006,0.0,-.083*
20,1,.006,0.0,-.083,.01937,-.083,0.0*
1,1,.006,.01937,-.083*
20,1,.006,.01937,-.083,.03873,-.07747,0.0*
1,1,.006,.03873,-.07747*
20,1,.006,.03873,-.07747,.05533,-.06917,0.0*
1,1,.006,.05533,-.06917*
20,1,.006,.05533,-.06917,.06917,-.05811,0.0*
1,1,.006,.06917,-.05811*
%
%ADD10MACRO10*%
%AMMACRO28*
1,1,.006,-.15486,-.202*
20,1,.006,-.15486,-.202,-.15486,.202,0.0*
1,1,.006,-.15486,.202*
20,1,.006,-.15486,.202,.15486,-.202,0.0*
1,1,.006,.15486,-.202*
20,1,.006,.15486,-.202,.15486,.202,0.0*
1,1,.006,.15486,.202*
%
%ADD28MACRO28*%
%AMMACRO18*
1,1,.006,-.01172,-.0185*
20,1,.006,-.01172,-.0185,-.01172,.0185,0.0*
1,1,.006,-.01172,.0185*
20,1,.006,-.01172,.0185,.01172,.0185,0.0*
1,1,.006,.01172,.0185*
1,1,.006,.00308,.00062*
20,1,.006,.00308,.00062,-.01172,.00062,0.0*
1,1,.006,-.01172,.00062*
%
%ADD18MACRO18*%
%AMMACRO14*
1,1,.006,-.0616,-.084*
20,1,.006,-.0616,-.084,-.0616,.084,0.0*
1,1,.006,-.0616,.084*
20,1,.006,-.0616,.084,-.0056,.084,0.0*
1,1,.006,-.0056,.084*
20,1,.006,-.0056,.084,.0168,.0756,0.0*
1,1,.006,.0168,.0756*
20,1,.006,.0168,.0756,.0336,.0644,0.0*
1,1,.006,.0336,.0644*
20,1,.006,.0336,.0644,.0476,.0476,0.0*
1,1,.006,.0476,.0476*
20,1,.006,.0476,.0476,.0588,.028,0.0*
1,1,.006,.0588,.028*
20,1,.006,.0588,.028,.0616,0.0,0.0*
1,1,.006,.0616,0.0*
20,1,.006,.0616,0.0,.0588,-.028,0.0*
1,1,.006,.0588,-.028*
20,1,.006,.0588,-.028,.0476,-.0476,0.0*
1,1,.006,.0476,-.0476*
20,1,.006,.0476,-.0476,.0336,-.0644,0.0*
1,1,.006,.0336,-.0644*
20,1,.006,.0336,-.0644,.0168,-.0756,0.0*
1,1,.006,.0168,-.0756*
20,1,.006,.0168,-.0756,-.0056,-.084,0.0*
1,1,.006,-.0056,-.084*
20,1,.006,-.0056,-.084,-.0616,-.084,0.0*
1,1,.006,-.0616,-.084*
%
%ADD14MACRO14*%
%AMMACRO30*
1,1,.006,-.031,-.0279*
20,1,.006,-.031,-.0279,-.02325,-.0372,0.0*
1,1,.006,-.02325,-.0372*
20,1,.006,-.02325,-.0372,-.01395,-.0434,0.0*
1,1,.006,-.01395,-.0434*
20,1,.006,-.01395,-.0434,-.0031,-.0465,0.0*
1,1,.006,-.0031,-.0465*
20,1,.006,-.0031,-.0465,.0093,-.0434,0.0*
1,1,.006,.0093,-.0434*
20,1,.006,.0093,-.0434,.0186,-.0372,0.0*
1,1,.006,.0186,-.0372*
20,1,.006,.0186,-.0372,.0279,-.0279,0.0*
1,1,.006,.0279,-.0279*
20,1,.006,.0279,-.0279,.031,-.0155,0.0*
1,1,.006,.031,-.0155*
20,1,.006,.031,-.0155,.031,.0465,0.0*
1,1,.006,.031,.0465*
%
%ADD30MACRO30*%
%AMMACRO15*
1,1,.006,-.0301,-.043*
20,1,.006,-.0301,-.043,-.0301,.043,0.0*
1,1,.006,-.0301,.043*
1,1,.006,.0301,.043*
20,1,.006,.0301,.043,.0301,-.043,0.0*
1,1,.006,.0301,-.043*
1,1,.006,.0301,0.0*
20,1,.006,.0301,0.0,-.0301,0.0,0.0*
1,1,.006,-.0301,0.0*
%
%ADD15MACRO15*%
%AMMACRO26*
1,1,.006,-.03447,-.047*
20,1,.006,-.03447,-.047,-.03447,.047,0.0*
1,1,.006,-.03447,.047*
1,1,.006,.02507,.047*
20,1,.006,.02507,.047,-.03447,-.01097,0.0*
1,1,.006,-.03447,-.01097*
1,1,.006,.03447,-.047*
20,1,.006,.03447,-.047,-.00783,.01566,0.0*
1,1,.006,-.00783,.01566*
%
%ADD26MACRO26*%
%AMMACRO17*
1,1,.006,-.0174,.0435*
20,1,.006,-.0174,.0435,.0174,.0435,0.0*
1,1,.006,.0174,.0435*
1,1,.006,0.0,.0435*
20,1,.006,0.0,.0435,0.0,-.0435,0.0*
1,1,.006,0.0,-.0435*
1,1,.006,-.0174,-.0435*
20,1,.006,-.0174,-.0435,.0174,-.0435,0.0*
1,1,.006,.0174,-.0435*
%
%ADD17MACRO17*%
%AMMACRO27*
1,1,.006,-.03233,.0485*
20,1,.006,-.03233,.0485,-.03233,-.0485,0.0*
1,1,.006,-.03233,-.0485*
20,1,.006,-.03233,-.0485,.03233,-.0485,0.0*
1,1,.006,.03233,-.0485*
%
%ADD27MACRO27*%
%AMMACRO12*
1,1,.006,.006,0.0*
20,1,.006,.006,0.0,.003,.005196,0.0*
1,1,.006,.003,.005196*
20,1,.006,.003,.005196,-.003,.005196,0.0*
1,1,.006,-.003,.005196*
20,1,.006,-.003,.005196,-.006,0.0,0.0*
1,1,.006,-.006,0.0*
20,1,.006,-.006,0.0,-.003,-.005196,0.0*
1,1,.006,-.003,-.005196*
20,1,.006,-.003,-.005196,.003,-.005196,0.0*
1,1,.006,.003,-.005196*
20,1,.006,.003,-.005196,.006,0.0,0.0*
1,1,.006,.006,0.0*
1,1,.006,-.0022,-.0018*
20,1,.006,-.0022,-.0018,-.0016,-.0025,0.0*
1,1,.006,-.0016,-.0025*
20,1,.006,-.0016,-.0025,-.0008,-.0029,0.0*
1,1,.006,-.0008,-.0029*
20,1,.006,-.0008,-.0029,.0001,-.003,0.0*
1,1,.006,.0001,-.003*
20,1,.006,.0001,-.003,.0009,-.0029,0.0*
1,1,.006,.0009,-.0029*
20,1,.006,.0009,-.0029,.0017,-.0024,0.0*
1,1,.006,.0017,-.0024*
20,1,.006,.0017,-.0024,.0022,-.0018,0.0*
1,1,.006,.0022,-.0018*
20,1,.006,.0022,-.0018,.0023,-.0012,0.0*
1,1,.006,.0023,-.0012*
20,1,.006,.0023,-.0012,.0021,-.0005,0.0*
1,1,.006,.0021,-.0005*
20,1,.006,.0021,-.0005,.0014,0.0,0.0*
1,1,.006,.0014,0.0*
20,1,.006,.0014,0.0,.0007,.0002,0.0*
1,1,.006,.0007,.0002*
20,1,.006,.0007,.0002,-.0002,.0002,0.0*
1,1,.006,-.0002,.0002*
1,1,.006,.0007,.0002*
20,1,.006,.0007,.0002,.0013,.0005,0.0*
1,1,.006,.0013,.0005*
20,1,.006,.0013,.0005,.0018,.001,0.0*
1,1,.006,.0018,.001*
20,1,.006,.0018,.001,.002,.0016,0.0*
1,1,.006,.002,.0016*
20,1,.006,.002,.0016,.0018,.0022,0.0*
1,1,.006,.0018,.0022*
20,1,.006,.0018,.0022,.0013,.0027,0.0*
1,1,.006,.0013,.0027*
20,1,.006,.0013,.0027,.0004,.003,0.0*
1,1,.006,.0004,.003*
20,1,.006,.0004,.003,-.0005,.0029,0.0*
1,1,.006,-.0005,.0029*
20,1,.006,-.0005,.0029,-.0014,.0025,0.0*
1,1,.006,-.0014,.0025*
%
%ADD12MACRO12*%
%AMMACRO13*
1,1,.006,-.083,-.0395*
20,1,.006,-.083,-.0395,-.083,.0395,0.0*
1,1,.006,-.083,.0395*
20,1,.006,-.083,.0395,-.081739,.053913,0.0*
1,1,.006,-.081739,.053913*
20,1,.006,-.081739,.053913,-.077994,.067888,0.0*
1,1,.006,-.077994,.067888*
20,1,.006,-.077994,.067888,-.07188,.081,0.0*
1,1,.006,-.07188,.081*
20,1,.006,-.07188,.081,-.063582,.092851,0.0*
1,1,.006,-.063582,.092851*
20,1,.006,-.063582,.092851,-.053351,.103082,0.0*
1,1,.006,-.053351,.103082*
20,1,.006,-.053351,.103082,-.0415,.11138,0.0*
1,1,.006,-.0415,.11138*
20,1,.006,-.0415,.11138,-.028388,.117494,0.0*
1,1,.006,-.028388,.117494*
20,1,.006,-.028388,.117494,-.014413,.121239,0.0*
1,1,.006,-.014413,.121239*
20,1,.006,-.014413,.121239,0.0,.1225,0.0*
1,1,.006,0.0,.1225*
20,1,.006,0.0,.1225,.014413,.121239,0.0*
1,1,.006,.014413,.121239*
20,1,.006,.014413,.121239,.028388,.117494,0.0*
1,1,.006,.028388,.117494*
20,1,.006,.028388,.117494,.0415,.11138,0.0*
1,1,.006,.0415,.11138*
20,1,.006,.0415,.11138,.053351,.103082,0.0*
1,1,.006,.053351,.103082*
20,1,.006,.053351,.103082,.063582,.092851,0.0*
1,1,.006,.063582,.092851*
20,1,.006,.063582,.092851,.07188,.081,0.0*
1,1,.006,.07188,.081*
20,1,.006,.07188,.081,.077994,.067888,0.0*
1,1,.006,.077994,.067888*
20,1,.006,.077994,.067888,.081739,.053913,0.0*
1,1,.006,.081739,.053913*
20,1,.006,.081739,.053913,.083,.0395,0.0*
1,1,.006,.083,.0395*
20,1,.006,.083,.0395,.083,-.0395,0.0*
1,1,.006,.083,-.0395*
20,1,.006,.083,-.0395,.081739,-.053913,0.0*
1,1,.006,.081739,-.053913*
20,1,.006,.081739,-.053913,.077994,-.067888,0.0*
1,1,.006,.077994,-.067888*
20,1,.006,.077994,-.067888,.07188,-.081,0.0*
1,1,.006,.07188,-.081*
20,1,.006,.07188,-.081,.063582,-.092851,0.0*
1,1,.006,.063582,-.092851*
20,1,.006,.063582,-.092851,.053351,-.103082,0.0*
1,1,.006,.053351,-.103082*
20,1,.006,.053351,-.103082,.0415,-.11138,0.0*
1,1,.006,.0415,-.11138*
20,1,.006,.0415,-.11138,.028388,-.117494,0.0*
1,1,.006,.028388,-.117494*
20,1,.006,.028388,-.117494,.014413,-.121239,0.0*
1,1,.006,.014413,-.121239*
20,1,.006,.014413,-.121239,0.0,-.1225,0.0*
1,1,.006,0.0,-.1225*
20,1,.006,0.0,-.1225,-.014413,-.121239,0.0*
1,1,.006,-.014413,-.121239*
20,1,.006,-.014413,-.121239,-.028388,-.117494,0.0*
1,1,.006,-.028388,-.117494*
20,1,.006,-.028388,-.117494,-.0415,-.11138,0.0*
1,1,.006,-.0415,-.11138*
20,1,.006,-.0415,-.11138,-.053351,-.103082,0.0*
1,1,.006,-.053351,-.103082*
20,1,.006,-.053351,-.103082,-.063582,-.092851,0.0*
1,1,.006,-.063582,-.092851*
20,1,.006,-.063582,-.092851,-.07188,-.081,0.0*
1,1,.006,-.07188,-.081*
20,1,.006,-.07188,-.081,-.077994,-.067888,0.0*
1,1,.006,-.077994,-.067888*
20,1,.006,-.077994,-.067888,-.081739,-.053913,0.0*
1,1,.006,-.081739,-.053913*
20,1,.006,-.081739,-.053913,-.083,-.0395,0.0*
1,1,.006,-.083,-.0395*
1,1,.006,-.0415,-.0415*
20,1,.006,-.0415,-.0415,-.05257,-.04012,0.0*
1,1,.006,-.05257,-.04012*
20,1,.006,-.05257,-.04012,-.06225,-.03458,0.0*
1,1,.006,-.06225,-.03458*
20,1,.006,-.06225,-.03458,-.07055,-.02628,0.0*
1,1,.006,-.07055,-.02628*
20,1,.006,-.07055,-.02628,-.07608,-.0166,0.0*
1,1,.006,-.07608,-.0166*
20,1,.006,-.07608,-.0166,-.07885,-.00553,0.0*
1,1,.006,-.07885,-.00553*
20,1,.006,-.07885,-.00553,-.07885,.00553,0.0*
1,1,.006,-.07885,.00553*
20,1,.006,-.07885,.00553,-.07608,.0166,0.0*
1,1,.006,-.07608,.0166*
20,1,.006,-.07608,.0166,-.07055,.02628,0.0*
1,1,.006,-.07055,.02628*
20,1,.006,-.07055,.02628,-.06225,.03458,0.0*
1,1,.006,-.06225,.03458*
20,1,.006,-.06225,.03458,-.05257,.04012,0.0*
1,1,.006,-.05257,.04012*
20,1,.006,-.05257,.04012,-.0415,.0415,0.0*
1,1,.006,-.0415,.0415*
20,1,.006,-.0415,.0415,-.03043,.04012,0.0*
1,1,.006,-.03043,.04012*
20,1,.006,-.03043,.04012,-.02075,.03458,0.0*
1,1,.006,-.02075,.03458*
20,1,.006,-.02075,.03458,-.01245,.02628,0.0*
1,1,.006,-.01245,.02628*
20,1,.006,-.01245,.02628,-.00692,.0166,0.0*
1,1,.006,-.00692,.0166*
20,1,.006,-.00692,.0166,-.00415,.00553,0.0*
1,1,.006,-.00415,.00553*
20,1,.006,-.00415,.00553,-.00415,-.00553,0.0*
1,1,.006,-.00415,-.00553*
20,1,.006,-.00415,-.00553,-.00692,-.0166,0.0*
1,1,.006,-.00692,-.0166*
20,1,.006,-.00692,-.0166,-.01245,-.02628,0.0*
1,1,.006,-.01245,-.02628*
20,1,.006,-.01245,-.02628,-.02075,-.03458,0.0*
1,1,.006,-.02075,-.03458*
20,1,.006,-.02075,-.03458,-.03043,-.04012,0.0*
1,1,.006,-.03043,-.04012*
20,1,.006,-.03043,-.04012,-.0415,-.0415,0.0*
1,1,.006,-.0415,-.0415*
1,1,.006,.05258,.00277*
20,1,.006,.05258,.00277,.05811,.00692,0.0*
1,1,.006,.05811,.00692*
20,1,.006,.05811,.00692,.06226,.01383,0.0*
1,1,.006,.06226,.01383*
20,1,.006,.06226,.01383,.06503,.02352,0.0*
1,1,.006,.06503,.02352*
20,1,.006,.06503,.02352,.06226,.03182,0.0*
1,1,.006,.06226,.03182*
20,1,.006,.06226,.03182,.05673,.03735,0.0*
1,1,.006,.05673,.03735*
20,1,.006,.05673,.03735,.04704,.0415,0.0*
1,1,.006,.04704,.0415*
20,1,.006,.04704,.0415,.00969,.0415,0.0*
1,1,.006,.00969,.0415*
20,1,.006,.00969,.0415,.00969,-.0415,0.0*
1,1,.006,.00969,-.0415*
20,1,.006,.00969,-.0415,.05534,-.0415,0.0*
1,1,.006,.05534,-.0415*
20,1,.006,.05534,-.0415,.06503,-.03597,0.0*
1,1,.006,.06503,-.03597*
20,1,.006,.06503,-.03597,.07056,-.02767,0.0*
1,1,.006,.07056,-.02767*
20,1,.006,.07056,-.02767,.07333,-.01798,0.0*
1,1,.006,.07333,-.01798*
20,1,.006,.07333,-.01798,.07056,-.0083,0.0*
1,1,.006,.07056,-.0083*
20,1,.006,.07056,-.0083,.06226,0.0,0.0*
1,1,.006,.06226,0.0*
20,1,.006,.06226,0.0,.05258,.00277,0.0*
1,1,.006,.05258,.00277*
20,1,.006,.05258,.00277,.00969,.00277,0.0*
1,1,.006,.00969,.00277*
%
%ADD13MACRO13*%
%AMMACRO31*
1,1,.006,-.0595,-.039*
20,1,.006,-.0595,-.039,-.0595,.039,0.0*
1,1,.006,-.0595,.039*
20,1,.006,-.0595,.039,-.058596,.049332,0.0*
1,1,.006,-.058596,.049332*
20,1,.006,-.058596,.049332,-.055912,.05935,0.0*
1,1,.006,-.055912,.05935*
20,1,.006,-.055912,.05935,-.051529,.06875,0.0*
1,1,.006,-.051529,.06875*
20,1,.006,-.051529,.06875,-.04558,.077246,0.0*
1,1,.006,-.04558,.077246*
20,1,.006,-.04558,.077246,-.038246,.08458,0.0*
1,1,.006,-.038246,.08458*
20,1,.006,-.038246,.08458,-.02975,.090529,0.0*
1,1,.006,-.02975,.090529*
20,1,.006,-.02975,.090529,-.02035,.094912,0.0*
1,1,.006,-.02035,.094912*
20,1,.006,-.02035,.094912,-.010332,.097596,0.0*
1,1,.006,-.010332,.097596*
20,1,.006,-.010332,.097596,0.0,.0985,0.0*
1,1,.006,0.0,.0985*
20,1,.006,0.0,.0985,.010332,.097596,0.0*
1,1,.006,.010332,.097596*
20,1,.006,.010332,.097596,.02035,.094912,0.0*
1,1,.006,.02035,.094912*
20,1,.006,.02035,.094912,.02975,.090529,0.0*
1,1,.006,.02975,.090529*
20,1,.006,.02975,.090529,.038246,.08458,0.0*
1,1,.006,.038246,.08458*
20,1,.006,.038246,.08458,.04558,.077246,0.0*
1,1,.006,.04558,.077246*
20,1,.006,.04558,.077246,.051529,.06875,0.0*
1,1,.006,.051529,.06875*
20,1,.006,.051529,.06875,.055912,.05935,0.0*
1,1,.006,.055912,.05935*
20,1,.006,.055912,.05935,.058596,.049332,0.0*
1,1,.006,.058596,.049332*
20,1,.006,.058596,.049332,.0595,.039,0.0*
1,1,.006,.0595,.039*
20,1,.006,.0595,.039,.0595,-.039,0.0*
1,1,.006,.0595,-.039*
20,1,.006,.0595,-.039,.058596,-.049332,0.0*
1,1,.006,.058596,-.049332*
20,1,.006,.058596,-.049332,.055912,-.05935,0.0*
1,1,.006,.055912,-.05935*
20,1,.006,.055912,-.05935,.051529,-.06875,0.0*
1,1,.006,.051529,-.06875*
20,1,.006,.051529,-.06875,.04558,-.077246,0.0*
1,1,.006,.04558,-.077246*
20,1,.006,.04558,-.077246,.038246,-.08458,0.0*
1,1,.006,.038246,-.08458*
20,1,.006,.038246,-.08458,.02975,-.090529,0.0*
1,1,.006,.02975,-.090529*
20,1,.006,.02975,-.090529,.02035,-.094912,0.0*
1,1,.006,.02035,-.094912*
20,1,.006,.02035,-.094912,.010332,-.097596,0.0*
1,1,.006,.010332,-.097596*
20,1,.006,.010332,-.097596,0.0,-.0985,0.0*
1,1,.006,0.0,-.0985*
20,1,.006,0.0,-.0985,-.010332,-.097596,0.0*
1,1,.006,-.010332,-.097596*
20,1,.006,-.010332,-.097596,-.02035,-.094912,0.0*
1,1,.006,-.02035,-.094912*
20,1,.006,-.02035,-.094912,-.02975,-.090529,0.0*
1,1,.006,-.02975,-.090529*
20,1,.006,-.02975,-.090529,-.038246,-.08458,0.0*
1,1,.006,-.038246,-.08458*
20,1,.006,-.038246,-.08458,-.04558,-.077246,0.0*
1,1,.006,-.04558,-.077246*
20,1,.006,-.04558,-.077246,-.051529,-.06875,0.0*
1,1,.006,-.051529,-.06875*
20,1,.006,-.051529,-.06875,-.055912,-.05935,0.0*
1,1,.006,-.055912,-.05935*
20,1,.006,-.055912,-.05935,-.058596,-.049332,0.0*
1,1,.006,-.058596,-.049332*
20,1,.006,-.058596,-.049332,-.0595,-.039,0.0*
1,1,.006,-.0595,-.039*
1,1,.006,-.02975,-.02975*
20,1,.006,-.02975,-.02975,-.03768,-.02876,0.0*
1,1,.006,-.03768,-.02876*
20,1,.006,-.03768,-.02876,-.04462,-.02479,0.0*
1,1,.006,-.04462,-.02479*
20,1,.006,-.04462,-.02479,-.05058,-.01884,0.0*
1,1,.006,-.05058,-.01884*
20,1,.006,-.05058,-.01884,-.05454,-.0119,0.0*
1,1,.006,-.05454,-.0119*
20,1,.006,-.05454,-.0119,-.05653,-.00397,0.0*
1,1,.006,-.05653,-.00397*
20,1,.006,-.05653,-.00397,-.05653,.00397,0.0*
1,1,.006,-.05653,.00397*
20,1,.006,-.05653,.00397,-.05454,.0119,0.0*
1,1,.006,-.05454,.0119*
20,1,.006,-.05454,.0119,-.05058,.01884,0.0*
1,1,.006,-.05058,.01884*
20,1,.006,-.05058,.01884,-.04462,.02479,0.0*
1,1,.006,-.04462,.02479*
20,1,.006,-.04462,.02479,-.03768,.02876,0.0*
1,1,.006,-.03768,.02876*
20,1,.006,-.03768,.02876,-.02975,.02975,0.0*
1,1,.006,-.02975,.02975*
20,1,.006,-.02975,.02975,-.02182,.02876,0.0*
1,1,.006,-.02182,.02876*
20,1,.006,-.02182,.02876,-.01488,.02479,0.0*
1,1,.006,-.01488,.02479*
20,1,.006,-.01488,.02479,-.00892,.01884,0.0*
1,1,.006,-.00892,.01884*
20,1,.006,-.00892,.01884,-.00496,.0119,0.0*
1,1,.006,-.00496,.0119*
20,1,.006,-.00496,.0119,-.00297,.00397,0.0*
1,1,.006,-.00297,.00397*
20,1,.006,-.00297,.00397,-.00297,-.00397,0.0*
1,1,.006,-.00297,-.00397*
20,1,.006,-.00297,-.00397,-.00496,-.0119,0.0*
1,1,.006,-.00496,-.0119*
20,1,.006,-.00496,-.0119,-.00892,-.01884,0.0*
1,1,.006,-.00892,-.01884*
20,1,.006,-.00892,-.01884,-.01488,-.02479,0.0*
1,1,.006,-.01488,-.02479*
20,1,.006,-.01488,-.02479,-.02182,-.02876,0.0*
1,1,.006,-.02182,-.02876*
20,1,.006,-.02182,-.02876,-.02975,-.02975,0.0*
1,1,.006,-.02975,-.02975*
1,1,.006,.00497,-.02975*
20,1,.006,.00497,-.02975,.02976,.02975,0.0*
1,1,.006,.02976,.02975*
20,1,.006,.02976,.02975,.05455,-.02975,0.0*
1,1,.006,.05455,-.02975*
1,1,.006,.04563,-.00893*
20,1,.006,.04563,-.00893,.01389,-.00893,0.0*
1,1,.006,.01389,-.00893*
%
%ADD31MACRO31*%
%AMMACRO35*
1,1,.006,0.0,.01*
20,1,.006,0.0,.01,.01,-.01,0.0*
1,1,.006,.01,-.01*
20,1,.006,.01,-.01,-.01,-.01,0.0*
1,1,.006,-.01,-.01*
20,1,.006,-.01,-.01,0.0,.01,0.0*
1,1,.006,0.0,.01*
1,1,.006,-.00033,-.005*
20,1,.006,-.00033,-.005,0.0,-.00283,0.0*
1,1,.006,0.0,-.00283*
20,1,.006,0.0,-.00283,.0005,-.001,0.0*
1,1,.006,.0005,-.001*
20,1,.006,.0005,-.001,.00117,.00067,0.0*
1,1,.006,.00117,.00067*
20,1,.006,.00117,.00067,.002,.0025,0.0*
1,1,.006,.002,.0025*
20,1,.006,.002,.0025,.00333,.005,0.0*
1,1,.006,.00333,.005*
20,1,.006,.00333,.005,-.00333,.005,0.0*
1,1,.006,-.00333,.005*
%
%ADD35MACRO35*%
%AMMACRO32*
1,1,.006,.0595,0.0*
20,1,.006,.0595,0.0,.058596,-.010332,0.0*
1,1,.006,.058596,-.010332*
20,1,.006,.058596,-.010332,.055912,-.02035,0.0*
1,1,.006,.055912,-.02035*
20,1,.006,.055912,-.02035,.051529,-.02975,0.0*
1,1,.006,.051529,-.02975*
20,1,.006,.051529,-.02975,.04558,-.038246,0.0*
1,1,.006,.04558,-.038246*
20,1,.006,.04558,-.038246,.038246,-.04558,0.0*
1,1,.006,.038246,-.04558*
20,1,.006,.038246,-.04558,.02975,-.051529,0.0*
1,1,.006,.02975,-.051529*
20,1,.006,.02975,-.051529,.02035,-.055912,0.0*
1,1,.006,.02035,-.055912*
20,1,.006,.02035,-.055912,.010332,-.058596,0.0*
1,1,.006,.010332,-.058596*
20,1,.006,.010332,-.058596,0.0,-.0595,0.0*
1,1,.006,0.0,-.0595*
20,1,.006,0.0,-.0595,-.010332,-.058596,0.0*
1,1,.006,-.010332,-.058596*
20,1,.006,-.010332,-.058596,-.02035,-.055912,0.0*
1,1,.006,-.02035,-.055912*
20,1,.006,-.02035,-.055912,-.02975,-.051529,0.0*
1,1,.006,-.02975,-.051529*
20,1,.006,-.02975,-.051529,-.038246,-.04558,0.0*
1,1,.006,-.038246,-.04558*
20,1,.006,-.038246,-.04558,-.04558,-.038246,0.0*
1,1,.006,-.04558,-.038246*
20,1,.006,-.04558,-.038246,-.051529,-.02975,0.0*
1,1,.006,-.051529,-.02975*
20,1,.006,-.051529,-.02975,-.055912,-.02035,0.0*
1,1,.006,-.055912,-.02035*
20,1,.006,-.055912,-.02035,-.058596,-.010332,0.0*
1,1,.006,-.058596,-.010332*
20,1,.006,-.058596,-.010332,-.0595,0.0,0.0*
1,1,.006,-.0595,0.0*
20,1,.006,-.0595,0.0,-.058596,.010332,0.0*
1,1,.006,-.058596,.010332*
20,1,.006,-.058596,.010332,-.055912,.02035,0.0*
1,1,.006,-.055912,.02035*
20,1,.006,-.055912,.02035,-.051529,.02975,0.0*
1,1,.006,-.051529,.02975*
20,1,.006,-.051529,.02975,-.04558,.038246,0.0*
1,1,.006,-.04558,.038246*
20,1,.006,-.04558,.038246,-.038246,.04558,0.0*
1,1,.006,-.038246,.04558*
20,1,.006,-.038246,.04558,-.02975,.051529,0.0*
1,1,.006,-.02975,.051529*
20,1,.006,-.02975,.051529,-.02035,.055912,0.0*
1,1,.006,-.02035,.055912*
20,1,.006,-.02035,.055912,-.010332,.058596,0.0*
1,1,.006,-.010332,.058596*
20,1,.006,-.010332,.058596,0.0,.0595,0.0*
1,1,.006,0.0,.0595*
20,1,.006,0.0,.0595,.010332,.058596,0.0*
1,1,.006,.010332,.058596*
20,1,.006,.010332,.058596,.02035,.055912,0.0*
1,1,.006,.02035,.055912*
20,1,.006,.02035,.055912,.02975,.051529,0.0*
1,1,.006,.02975,.051529*
20,1,.006,.02975,.051529,.038246,.04558,0.0*
1,1,.006,.038246,.04558*
20,1,.006,.038246,.04558,.04558,.038246,0.0*
1,1,.006,.04558,.038246*
20,1,.006,.04558,.038246,.051529,.02975,0.0*
1,1,.006,.051529,.02975*
20,1,.006,.051529,.02975,.055912,.02035,0.0*
1,1,.006,.055912,.02035*
20,1,.006,.055912,.02035,.058596,.010332,0.0*
1,1,.006,.058596,.010332*
20,1,.006,.058596,.010332,.0595,0.0,0.0*
1,1,.006,.0595,0.0*
1,1,.006,-.02975,-.02975*
20,1,.006,-.02975,-.02975,-.02975,.02975,0.0*
1,1,.006,-.02975,.02975*
20,1,.006,-.02975,.02975,-.04165,.01785,0.0*
1,1,.006,-.04165,.01785*
1,1,.006,-.04165,-.02975*
20,1,.006,-.04165,-.02975,-.01785,-.02975,0.0*
1,1,.006,-.01785,-.02975*
1,1,.006,.02976,-.02975*
20,1,.006,.02976,-.02975,.02976,.02975,0.0*
1,1,.006,.02976,.02975*
20,1,.006,.02976,.02975,.01786,.01785,0.0*
1,1,.006,.01786,.01785*
1,1,.006,.01786,-.02975*
20,1,.006,.01786,-.02975,.04166,-.02975,0.0*
1,1,.006,.04166,-.02975*
%
%ADD32MACRO32*%
%AMMACRO25*
1,1,.006,0.0,.007*
20,1,.006,0.0,.007,-.006062,.0035,0.0*
1,1,.006,-.006062,.0035*
20,1,.006,-.006062,.0035,-.006062,-.0035,0.0*
1,1,.006,-.006062,-.0035*
20,1,.006,-.006062,-.0035,0.0,-.007,0.0*
1,1,.006,0.0,-.007*
20,1,.006,0.0,-.007,.006062,-.0035,0.0*
1,1,.006,.006062,-.0035*
20,1,.006,.006062,-.0035,.006062,.0035,0.0*
1,1,.006,.006062,.0035*
20,1,.006,.006062,.0035,0.0,.007,0.0*
1,1,.006,0.0,.007*
1,1,.006,.0014,-.0035*
20,1,.006,.0014,-.0035,.0014,.0035,0.0*
1,1,.006,.0014,.0035*
20,1,.006,.0014,.0035,-.00292,-.00152,0.0*
1,1,.006,-.00292,-.00152*
20,1,.006,-.00292,-.00152,.00292,-.00152,0.0*
1,1,.006,.00292,-.00152*
%
%ADD25MACRO25*%
%AMMACRO34*
1,1,.006,-.0035,.0105*
20,1,.006,-.0035,.0105,.0035,.0105,0.0*
1,1,.006,.0035,.0105*
20,1,.006,.0035,.0105,.005323,.01034,0.0*
1,1,.006,.005323,.01034*
20,1,.006,.005323,.01034,.007091,.009867,0.0*
1,1,.006,.007091,.009867*
20,1,.006,.007091,.009867,.00875,.009093,0.0*
1,1,.006,.00875,.009093*
20,1,.006,.00875,.009093,.010249,.008043,0.0*
1,1,.006,.010249,.008043*
20,1,.006,.010249,.008043,.011543,.006749,0.0*
1,1,.006,.011543,.006749*
20,1,.006,.011543,.006749,.012593,.00525,0.0*
1,1,.006,.012593,.00525*
20,1,.006,.012593,.00525,.013367,.003591,0.0*
1,1,.006,.013367,.003591*
20,1,.006,.013367,.003591,.01384,.001823,0.0*
1,1,.006,.01384,.001823*
20,1,.006,.01384,.001823,.014,0.0,0.0*
1,1,.006,.014,0.0*
20,1,.006,.014,0.0,.01384,-.001823,0.0*
1,1,.006,.01384,-.001823*
20,1,.006,.01384,-.001823,.013367,-.003591,0.0*
1,1,.006,.013367,-.003591*
20,1,.006,.013367,-.003591,.012593,-.00525,0.0*
1,1,.006,.012593,-.00525*
20,1,.006,.012593,-.00525,.011543,-.006749,0.0*
1,1,.006,.011543,-.006749*
20,1,.006,.011543,-.006749,.010249,-.008043,0.0*
1,1,.006,.010249,-.008043*
20,1,.006,.010249,-.008043,.00875,-.009093,0.0*
1,1,.006,.00875,-.009093*
20,1,.006,.00875,-.009093,.007091,-.009867,0.0*
1,1,.006,.007091,-.009867*
20,1,.006,.007091,-.009867,.005323,-.01034,0.0*
1,1,.006,.005323,-.01034*
20,1,.006,.005323,-.01034,.0035,-.0105,0.0*
1,1,.006,.0035,-.0105*
20,1,.006,.0035,-.0105,-.0035,-.0105,0.0*
1,1,.006,-.0035,-.0105*
20,1,.006,-.0035,-.0105,-.005323,-.01034,0.0*
1,1,.006,-.005323,-.01034*
20,1,.006,-.005323,-.01034,-.007091,-.009867,0.0*
1,1,.006,-.007091,-.009867*
20,1,.006,-.007091,-.009867,-.00875,-.009093,0.0*
1,1,.006,-.00875,-.009093*
20,1,.006,-.00875,-.009093,-.010249,-.008043,0.0*
1,1,.006,-.010249,-.008043*
20,1,.006,-.010249,-.008043,-.011543,-.006749,0.0*
1,1,.006,-.011543,-.006749*
20,1,.006,-.011543,-.006749,-.012593,-.00525,0.0*
1,1,.006,-.012593,-.00525*
20,1,.006,-.012593,-.00525,-.013367,-.003591,0.0*
1,1,.006,-.013367,-.003591*
20,1,.006,-.013367,-.003591,-.01384,-.001823,0.0*
1,1,.006,-.01384,-.001823*
20,1,.006,-.01384,-.001823,-.014,0.0,0.0*
1,1,.006,-.014,0.0*
20,1,.006,-.014,0.0,-.01384,.001823,0.0*
1,1,.006,-.01384,.001823*
20,1,.006,-.01384,.001823,-.013367,.003591,0.0*
1,1,.006,-.013367,.003591*
20,1,.006,-.013367,.003591,-.012593,.00525,0.0*
1,1,.006,-.012593,.00525*
20,1,.006,-.012593,.00525,-.011543,.006749,0.0*
1,1,.006,-.011543,.006749*
20,1,.006,-.011543,.006749,-.010249,.008043,0.0*
1,1,.006,-.010249,.008043*
20,1,.006,-.010249,.008043,-.00875,.009093,0.0*
1,1,.006,-.00875,.009093*
20,1,.006,-.00875,.009093,-.007091,.009867,0.0*
1,1,.006,-.007091,.009867*
20,1,.006,-.007091,.009867,-.005323,.01034,0.0*
1,1,.006,-.005323,.01034*
20,1,.006,-.005323,.01034,-.0035,.0105,0.0*
1,1,.006,-.0035,.0105*
1,1,.006,0.0,-.00525*
20,1,.006,0.0,-.00525,.00122,-.00508,0.0*
1,1,.006,.00122,-.00508*
20,1,.006,.00122,-.00508,.00262,-.00455,0.0*
1,1,.006,.00262,-.00455*
20,1,.006,.00262,-.00455,.0035,-.00368,0.0*
1,1,.006,.0035,-.00368*
20,1,.006,.0035,-.00368,.00385,-.00245,0.0*
1,1,.006,.00385,-.00245*
20,1,.006,.00385,-.00245,.0035,-.00123,0.0*
1,1,.006,.0035,-.00123*
20,1,.006,.0035,-.00123,.00245,-.00018,0.0*
1,1,.006,.00245,-.00018*
20,1,.006,.00245,-.00018,.00087,.00035,0.0*
1,1,.006,.00087,.00035*
20,1,.006,.00087,.00035,-.00087,.00035,0.0*
1,1,.006,-.00087,.00035*
20,1,.006,-.00087,.00035,-.00193,.0007,0.0*
1,1,.006,-.00193,.0007*
20,1,.006,-.00193,.0007,-.0028,.00157,0.0*
1,1,.006,-.0028,.00157*
20,1,.006,-.0028,.00157,-.00315,.0028,0.0*
1,1,.006,-.00315,.0028*
20,1,.006,-.00315,.0028,-.00262,.00402,0.0*
1,1,.006,-.00262,.00402*
20,1,.006,-.00262,.00402,-.0014,.0049,0.0*
1,1,.006,-.0014,.0049*
20,1,.006,-.0014,.0049,0.0,.00525,0.0*
1,1,.006,0.0,.00525*
20,1,.006,0.0,.00525,.0014,.0049,0.0*
1,1,.006,.0014,.0049*
20,1,.006,.0014,.0049,.00262,.00402,0.0*
1,1,.006,.00262,.00402*
20,1,.006,.00262,.00402,.00315,.0028,0.0*
1,1,.006,.00315,.0028*
20,1,.006,.00315,.0028,.0028,.00157,0.0*
1,1,.006,.0028,.00157*
20,1,.006,.0028,.00157,.00193,.0007,0.0*
1,1,.006,.00193,.0007*
20,1,.006,.00193,.0007,.00087,.00035,0.0*
1,1,.006,.00087,.00035*
20,1,.006,.00087,.00035,-.00087,.00035,0.0*
1,1,.006,-.00087,.00035*
20,1,.006,-.00087,.00035,-.00245,-.00018,0.0*
1,1,.006,-.00245,-.00018*
20,1,.006,-.00245,-.00018,-.0035,-.00123,0.0*
1,1,.006,-.0035,-.00123*
20,1,.006,-.0035,-.00123,-.00385,-.00245,0.0*
1,1,.006,-.00385,-.00245*
20,1,.006,-.00385,-.00245,-.0035,-.00368,0.0*
1,1,.006,-.0035,-.00368*
20,1,.006,-.0035,-.00368,-.00262,-.00455,0.0*
1,1,.006,-.00262,-.00455*
20,1,.006,-.00262,-.00455,-.00122,-.00508,0.0*
1,1,.006,-.00122,-.00508*
20,1,.006,-.00122,-.00508,0.0,-.00525,0.0*
1,1,.006,0.0,-.00525*
%
%ADD34MACRO34*%
%AMMACRO33*
1,1,.006,.014565,.010925*
20,1,.006,.014565,.010925,.014565,-.010925,0.0*
1,1,.006,.014565,-.010925*
20,1,.006,.014565,-.010925,-.014565,-.010925,0.0*
1,1,.006,-.014565,-.010925*
20,1,.006,-.014565,-.010925,-.014565,.010925,0.0*
1,1,.006,-.014565,.010925*
20,1,.006,-.014565,.010925,.014565,.010925,0.0*
1,1,.006,.014565,.010925*
1,1,.006,-.00546,-.00546*
20,1,.006,-.00546,-.00546,-.00546,.00546,0.0*
1,1,.006,-.00546,.00546*
20,1,.006,-.00546,.00546,-.00764,.00328,0.0*
1,1,.006,-.00764,.00328*
1,1,.006,-.00764,-.00546*
20,1,.006,-.00764,-.00546,-.00328,-.00546,0.0*
1,1,.006,-.00328,-.00546*
1,1,.006,.00547,.00546*
20,1,.006,.00547,.00546,.00401,.0051,0.0*
1,1,.006,.00401,.0051*
20,1,.006,.00401,.0051,.00292,.00419,0.0*
1,1,.006,.00292,.00419*
20,1,.006,.00292,.00419,.00219,.00309,0.0*
1,1,.006,.00219,.00309*
20,1,.006,.00219,.00309,.00165,.00164,0.0*
1,1,.006,.00165,.00164*
20,1,.006,.00165,.00164,.00147,0.0,0.0*
1,1,.006,.00147,0.0*
20,1,.006,.00147,0.0,.00165,-.00164,0.0*
1,1,.006,.00165,-.00164*
20,1,.006,.00165,-.00164,.00219,-.00309,0.0*
1,1,.006,.00219,-.00309*
20,1,.006,.00219,-.00309,.00292,-.00419,0.0*
1,1,.006,.00292,-.00419*
20,1,.006,.00292,-.00419,.00401,-.0051,0.0*
1,1,.006,.00401,-.0051*
20,1,.006,.00401,-.0051,.00547,-.00546,0.0*
1,1,.006,.00547,-.00546*
20,1,.006,.00547,-.00546,.00693,-.0051,0.0*
1,1,.006,.00693,-.0051*
20,1,.006,.00693,-.0051,.00802,-.00419,0.0*
1,1,.006,.00802,-.00419*
20,1,.006,.00802,-.00419,.00875,-.00309,0.0*
1,1,.006,.00875,-.00309*
20,1,.006,.00875,-.00309,.00929,-.00164,0.0*
1,1,.006,.00929,-.00164*
20,1,.006,.00929,-.00164,.00947,0.0,0.0*
1,1,.006,.00947,0.0*
20,1,.006,.00947,0.0,.00929,.00164,0.0*
1,1,.006,.00929,.00164*
20,1,.006,.00929,.00164,.00875,.00309,0.0*
1,1,.006,.00875,.00309*
20,1,.006,.00875,.00309,.00802,.00419,0.0*
1,1,.006,.00802,.00419*
20,1,.006,.00802,.00419,.00693,.0051,0.0*
1,1,.006,.00693,.0051*
20,1,.006,.00693,.0051,.00547,.00546,0.0*
1,1,.006,.00547,.00546*
%
%ADD33MACRO33*%
%AMMACRO29*
1,1,.006,-.010625,.003545*
20,1,.006,-.010625,.003545,-.010464,.00539,0.0*
1,1,.006,-.010464,.00539*
20,1,.006,-.010464,.00539,-.009984,.007179,0.0*
1,1,.006,-.009984,.007179*
20,1,.006,-.009984,.007179,-.009202,.008857,0.0*
1,1,.006,-.009202,.008857*
20,1,.006,-.009202,.008857,-.008139,.010375,0.0*
1,1,.006,-.008139,.010375*
20,1,.006,-.008139,.010375,-.00683,.011684,0.0*
1,1,.006,-.00683,.011684*
20,1,.006,-.00683,.011684,-.005313,.012747,0.0*
1,1,.006,-.005313,.012747*
20,1,.006,-.005313,.012747,-.003634,.013529,0.0*
1,1,.006,-.003634,.013529*
20,1,.006,-.003634,.013529,-.001845,.014009,0.0*
1,1,.006,-.001845,.014009*
20,1,.006,-.001845,.014009,0.0,.01417,0.0*
1,1,.006,0.0,.01417*
20,1,.006,0.0,.01417,.001845,.014009,0.0*
1,1,.006,.001845,.014009*
20,1,.006,.001845,.014009,.003634,.013529,0.0*
1,1,.006,.003634,.013529*
20,1,.006,.003634,.013529,.005312,.012747,0.0*
1,1,.006,.005312,.012747*
20,1,.006,.005312,.012747,.00683,.011684,0.0*
1,1,.006,.00683,.011684*
20,1,.006,.00683,.011684,.008139,.010375,0.0*
1,1,.006,.008139,.010375*
20,1,.006,.008139,.010375,.009202,.008858,0.0*
1,1,.006,.009202,.008858*
20,1,.006,.009202,.008858,.009984,.007179,0.0*
1,1,.006,.009984,.007179*
20,1,.006,.009984,.007179,.010464,.00539,0.0*
1,1,.006,.010464,.00539*
20,1,.006,.010464,.00539,.010625,.003545,0.0*
1,1,.006,.010625,.003545*
20,1,.006,.010625,.003545,.010625,-.003545,0.0*
1,1,.006,.010625,-.003545*
20,1,.006,.010625,-.003545,.010464,-.00539,0.0*
1,1,.006,.010464,-.00539*
20,1,.006,.010464,-.00539,.009984,-.007179,0.0*
1,1,.006,.009984,-.007179*
20,1,.006,.009984,-.007179,.009202,-.008857,0.0*
1,1,.006,.009202,-.008857*
20,1,.006,.009202,-.008857,.008139,-.010375,0.0*
1,1,.006,.008139,-.010375*
20,1,.006,.008139,-.010375,.00683,-.011684,0.0*
1,1,.006,.00683,-.011684*
20,1,.006,.00683,-.011684,.005313,-.012747,0.0*
1,1,.006,.005313,-.012747*
20,1,.006,.005313,-.012747,.003634,-.013529,0.0*
1,1,.006,.003634,-.013529*
20,1,.006,.003634,-.013529,.001845,-.014009,0.0*
1,1,.006,.001845,-.014009*
20,1,.006,.001845,-.014009,0.0,-.01417,0.0*
1,1,.006,0.0,-.01417*
20,1,.006,0.0,-.01417,-.001845,-.014009,0.0*
1,1,.006,-.001845,-.014009*
20,1,.006,-.001845,-.014009,-.003634,-.013529,0.0*
1,1,.006,-.003634,-.013529*
20,1,.006,-.003634,-.013529,-.005312,-.012747,0.0*
1,1,.006,-.005312,-.012747*
20,1,.006,-.005312,-.012747,-.00683,-.011684,0.0*
1,1,.006,-.00683,-.011684*
20,1,.006,-.00683,-.011684,-.008139,-.010375,0.0*
1,1,.006,-.008139,-.010375*
20,1,.006,-.008139,-.010375,-.009202,-.008858,0.0*
1,1,.006,-.009202,-.008858*
20,1,.006,-.009202,-.008858,-.009984,-.007179,0.0*
1,1,.006,-.009984,-.007179*
20,1,.006,-.009984,-.007179,-.010464,-.00539,0.0*
1,1,.006,-.010464,-.00539*
20,1,.006,-.010464,-.00539,-.010625,-.003545,0.0*
1,1,.006,-.010625,-.003545*
20,1,.006,-.010625,-.003545,-.010625,.003545,0.0*
1,1,.006,-.010625,.003545*
1,1,.006,-.00301,-.00407*
20,1,.006,-.00301,-.00407,-.00177,-.00496,0.0*
1,1,.006,-.00177,-.00496*
20,1,.006,-.00177,-.00496,-.00035,-.00531,0.0*
1,1,.006,-.00035,-.00531*
20,1,.006,-.00035,-.00531,.00106,-.00496,0.0*
1,1,.006,.00106,-.00496*
20,1,.006,.00106,-.00496,.0023,-.00389,0.0*
1,1,.006,.0023,-.00389*
20,1,.006,.0023,-.00389,.00319,-.0023,0.0*
1,1,.006,.00319,-.0023*
20,1,.006,.00319,-.0023,.00354,-.00071,0.0*
1,1,.006,.00354,-.00071*
20,1,.006,.00354,-.00071,.00354,.00124,0.0*
1,1,.006,.00354,.00124*
20,1,.006,.00354,.00124,.00319,.00283,0.0*
1,1,.006,.00319,.00283*
20,1,.006,.00319,.00283,.0023,.00425,0.0*
1,1,.006,.0023,.00425*
20,1,.006,.0023,.00425,.00124,.00496,0.0*
1,1,.006,.00124,.00496*
20,1,.006,.00124,.00496,0.0,.00531,0.0*
1,1,.006,0.0,.00531*
20,1,.006,0.0,.00531,-.00142,.00496,0.0*
1,1,.006,-.00142,.00496*
20,1,.006,-.00142,.00496,-.00248,.00425,0.0*
1,1,.006,-.00248,.00425*
20,1,.006,-.00248,.00425,-.00319,.00319,0.0*
1,1,.006,-.00319,.00319*
20,1,.006,-.00319,.00319,-.00354,.00177,0.0*
1,1,.006,-.00354,.00177*
20,1,.006,-.00354,.00177,-.00319,.00053,0.0*
1,1,.006,-.00319,.00053*
20,1,.006,-.00319,.00053,-.0023,-.00071,0.0*
1,1,.006,-.0023,-.00071*
20,1,.006,-.0023,-.00071,-.00124,-.00142,0.0*
1,1,.006,-.00124,-.00142*
20,1,.006,-.00124,-.00142,0.0,-.00159,0.0*
1,1,.006,0.0,-.00159*
20,1,.006,0.0,-.00159,.00142,-.00124,0.0*
1,1,.006,.00142,-.00124*
20,1,.006,.00142,-.00124,.00248,-.00035,0.0*
1,1,.006,.00248,-.00035*
20,1,.006,.00248,-.00035,.00354,.00124,0.0*
1,1,.006,.00354,.00124*
%
%ADD29MACRO29*%
%ADD37C,.02*%
%ADD38C,.006*%
G75*
%LPD*%
G75*
G54D10*
X15157Y21653D03*
X904921Y564960D03*
X1894685Y21654D03*
X2432929Y729366D03*
G54D11*
X24508Y5500D03*
X5500Y61492D03*
Y56492D03*
Y51492D03*
Y46492D03*
Y41492D03*
Y66492D03*
Y81492D03*
Y76492D03*
Y96492D03*
Y91492D03*
Y86492D03*
Y71492D03*
Y101492D03*
Y111492D03*
Y116492D03*
Y106492D03*
Y126492D03*
Y121492D03*
Y141492D03*
Y151492D03*
Y161492D03*
Y156492D03*
Y146492D03*
Y131492D03*
Y136492D03*
Y181492D03*
Y191492D03*
Y201492D03*
Y211492D03*
Y171492D03*
Y206492D03*
Y196492D03*
Y176492D03*
Y166492D03*
Y186492D03*
Y231492D03*
Y241492D03*
Y251492D03*
Y261492D03*
Y221492D03*
Y256492D03*
Y246492D03*
Y226492D03*
Y216492D03*
Y236492D03*
Y281492D03*
Y291492D03*
Y301492D03*
Y271492D03*
Y306492D03*
Y296492D03*
Y286492D03*
Y276492D03*
Y266492D03*
Y331492D03*
Y341492D03*
Y351492D03*
Y311492D03*
Y321492D03*
Y356492D03*
Y346492D03*
Y336492D03*
Y326492D03*
Y316492D03*
Y381492D03*
Y391492D03*
Y401492D03*
Y361492D03*
Y371492D03*
Y406492D03*
Y396492D03*
Y386492D03*
Y376492D03*
Y366492D03*
Y451492D03*
Y441492D03*
Y431492D03*
Y421492D03*
Y411492D03*
Y416492D03*
Y436492D03*
Y446492D03*
Y426492D03*
Y501492D03*
Y456492D03*
Y496492D03*
Y531492D03*
Y551492D03*
Y541492D03*
Y521492D03*
Y511492D03*
Y536492D03*
Y546492D03*
Y506492D03*
Y516492D03*
Y526492D03*
Y581492D03*
Y591492D03*
Y571492D03*
Y561492D03*
Y586492D03*
Y596492D03*
Y556492D03*
Y566492D03*
Y576492D03*
Y631492D03*
Y641492D03*
Y621492D03*
Y611492D03*
Y601492D03*
Y636492D03*
Y646492D03*
Y606492D03*
Y616492D03*
Y626492D03*
Y681492D03*
Y691492D03*
Y671492D03*
Y661492D03*
Y651492D03*
Y686492D03*
Y696492D03*
Y656492D03*
Y666492D03*
Y676492D03*
Y731492D03*
Y741492D03*
Y721492D03*
Y711492D03*
Y701492D03*
Y736492D03*
Y706492D03*
Y716492D03*
Y726492D03*
Y781492D03*
Y791492D03*
Y771492D03*
Y761492D03*
Y751492D03*
Y786492D03*
Y746492D03*
Y756492D03*
Y766492D03*
Y776492D03*
Y831492D03*
Y841492D03*
Y821492D03*
Y811492D03*
Y801492D03*
Y836492D03*
Y796492D03*
Y806492D03*
Y816492D03*
Y826492D03*
Y881492D03*
Y871492D03*
Y861492D03*
Y851492D03*
Y886492D03*
Y846492D03*
Y856492D03*
Y866492D03*
Y876492D03*
Y931492D03*
Y921492D03*
Y911492D03*
Y901492D03*
Y891492D03*
Y936492D03*
Y896492D03*
Y906492D03*
Y916492D03*
Y926492D03*
Y976492D03*
Y981492D03*
Y986492D03*
Y966492D03*
Y956492D03*
Y961492D03*
Y971492D03*
Y951492D03*
Y941492D03*
Y946492D03*
Y991492D03*
Y996492D03*
Y1001492D03*
Y1006492D03*
Y1026492D03*
Y1016492D03*
Y1011492D03*
Y1021492D03*
Y1031492D03*
Y1036492D03*
Y1066492D03*
Y1056492D03*
Y1046492D03*
Y1041492D03*
Y1051492D03*
Y1061492D03*
Y1071492D03*
Y1081492D03*
Y1076492D03*
Y1121492D03*
Y1131492D03*
Y1111492D03*
Y1101492D03*
Y1091492D03*
Y1086492D03*
Y1096492D03*
Y1106492D03*
Y1116492D03*
Y1126492D03*
Y1171492D03*
Y1161492D03*
Y1151492D03*
Y1141492D03*
Y1136492D03*
Y1146492D03*
Y1156492D03*
Y1166492D03*
Y1176492D03*
Y1221492D03*
Y1211492D03*
Y1201492D03*
Y1191492D03*
Y1181492D03*
Y1186492D03*
Y1196492D03*
Y1206492D03*
Y1216492D03*
Y1226492D03*
Y1271492D03*
Y1261492D03*
Y1251492D03*
Y1241492D03*
Y1231492D03*
Y1236492D03*
Y1246492D03*
Y1256492D03*
Y1266492D03*
Y1276492D03*
Y1321492D03*
Y1311492D03*
Y1301492D03*
Y1291492D03*
Y1281492D03*
Y1286492D03*
Y1296492D03*
Y1306492D03*
Y1316492D03*
X8983Y1368303D03*
X13983D03*
X18983D03*
X23983D03*
X5500Y1361492D03*
Y1351492D03*
Y1341492D03*
Y1331492D03*
Y1336492D03*
Y1346492D03*
Y1356492D03*
Y1326492D03*
X29508Y5500D03*
X39508D03*
X34508D03*
X44508D03*
X64508D03*
X69508D03*
X54508D03*
X49508D03*
X59508D03*
X28983Y1368303D03*
X33983D03*
X38983D03*
X43983D03*
X48983D03*
X53983D03*
X58983D03*
X63983D03*
X68983D03*
X114508Y5500D03*
X119508D03*
X104508D03*
X94508D03*
X84508D03*
X74508D03*
X79508D03*
X89508D03*
X99508D03*
X109508D03*
X119763Y550725D03*
Y546225D03*
Y555225D03*
X83100Y984800D03*
X78600D03*
X83100Y980300D03*
X78600D03*
Y989300D03*
X83100D03*
X73983Y1368303D03*
X78983D03*
X83983D03*
X88983D03*
X93983D03*
X98983D03*
X107374Y1369303D03*
X112374D03*
X117374D03*
X134508Y5500D03*
X124508D03*
X129508D03*
X169508D03*
X159508D03*
X149508D03*
X139508D03*
X154508D03*
X164508D03*
X144508D03*
X124263Y546225D03*
Y550725D03*
Y555225D03*
X141978Y958572D03*
X142006Y978425D03*
X122374Y1369303D03*
X127374D03*
X132374D03*
X137374D03*
X142374D03*
X147374D03*
X152374D03*
X157374D03*
X162374D03*
X167374D03*
X209508Y5500D03*
X199508D03*
X189508D03*
X179508D03*
X204508D03*
X214508D03*
X174508D03*
X184508D03*
X194508D03*
X209863Y566625D03*
X199102Y969717D03*
Y974717D03*
X183584Y974789D03*
Y969789D03*
X199392Y985113D03*
X183551Y984789D03*
X212063Y976725D03*
X203063D03*
X207563D03*
X216563D03*
X212063Y981725D03*
X216563D03*
X207563D03*
X203063D03*
X199392Y990113D03*
X183551Y989789D03*
X172374Y1369303D03*
X177374D03*
X182374D03*
X187374D03*
X192374D03*
X197374D03*
X202374D03*
X207374D03*
X212374D03*
X217374D03*
X259508Y5500D03*
X249508D03*
X239508D03*
X229508D03*
X219508D03*
X224508D03*
X234508D03*
X244508D03*
X254508D03*
X264508D03*
X250650Y556997D03*
Y561997D03*
X265545Y556794D03*
Y561794D03*
X250661Y572936D03*
Y577936D03*
X265590Y572801D03*
Y577801D03*
X225563Y976725D03*
X221063D03*
X225563Y981725D03*
X221063D03*
X222374Y1369303D03*
X227374D03*
X232374D03*
X237374D03*
X242374D03*
X247374D03*
X252374D03*
X257374D03*
X262374D03*
X309508Y5500D03*
X299508D03*
X289508D03*
X279508D03*
X269508D03*
X304508D03*
X314508D03*
X274508D03*
X284508D03*
X294508D03*
X269763Y569725D03*
X287763D03*
X292263D03*
X274263D03*
X283263D03*
X278763D03*
X283263Y564725D03*
X287763D03*
X292263D03*
X274263D03*
X269763D03*
X278763D03*
X267374Y1369303D03*
X272374D03*
X277374D03*
X282374D03*
X287374D03*
X292374D03*
X297374D03*
X302374D03*
X307374D03*
X312374D03*
X359508Y5500D03*
X349508D03*
X339508D03*
X329508D03*
X319508D03*
X324508D03*
X334508D03*
X344508D03*
X354508D03*
X333983Y1368303D03*
X338983D03*
X343983D03*
X348983D03*
X353983D03*
X358983D03*
X363983D03*
X317374Y1369303D03*
X322374D03*
X327374D03*
X395075Y18639D03*
Y13639D03*
X389508Y5500D03*
X379508D03*
X369508D03*
X364508D03*
X374508D03*
X384508D03*
X394508D03*
X395075Y43639D03*
Y38639D03*
Y33639D03*
Y28639D03*
Y23639D03*
X399000Y62000D03*
X396000Y55500D03*
X396075Y50248D03*
X368983Y1368303D03*
X373983D03*
X378983D03*
X383983D03*
X388983D03*
X393983D03*
X398983D03*
X403983D03*
X408983D03*
X413983D03*
X418983D03*
X423983D03*
X428983D03*
X433983D03*
X438983D03*
X443983D03*
X448983D03*
X453983D03*
X458983D03*
X463983D03*
X468983D03*
X473983D03*
X478983D03*
X483983D03*
X488983D03*
X493983D03*
X498983D03*
X503983D03*
X508983D03*
X517374Y1369303D03*
X522374D03*
X527374D03*
X532374D03*
X537374D03*
X542374D03*
X547374D03*
X552374D03*
X557374D03*
X597051Y7699D03*
Y12699D03*
Y17699D03*
X604146Y5500D03*
X597051Y22699D03*
Y27699D03*
Y32699D03*
Y37699D03*
Y42699D03*
X589000Y64000D03*
X594000Y61500D03*
X596000Y56500D03*
X596051Y51090D03*
X567374Y1369303D03*
X572374D03*
X577374D03*
X582374D03*
X587374D03*
X592374D03*
X597374D03*
X602374D03*
X562374D03*
X609146Y5500D03*
X619146D03*
X614146D03*
X629146D03*
X639146D03*
X649146D03*
X654146D03*
X644146D03*
X634146D03*
X624146D03*
X637592Y593186D03*
X641792D03*
Y597386D03*
X637592D03*
X633392Y593186D03*
Y597386D03*
X629192Y593186D03*
Y597386D03*
X641792Y605786D03*
Y601586D03*
X637592D03*
Y605786D03*
X633392D03*
Y601586D03*
X629192D03*
Y605786D03*
X617374Y1369303D03*
X622374D03*
X627374D03*
X632374D03*
X637374D03*
X642374D03*
X647374D03*
X652374D03*
X607374D03*
X612374D03*
X679146Y5500D03*
X689146D03*
X694146D03*
X684146D03*
X659146D03*
X669146D03*
X664146D03*
X674146D03*
X699146D03*
X675913Y586555D03*
Y592955D03*
Y598155D03*
X672082Y582834D03*
X666882D03*
X661682D03*
X656482D03*
X695413Y600755D03*
X699613D03*
X669482Y613934D03*
Y609734D03*
X665282D03*
Y613934D03*
X661082D03*
Y609734D03*
X656882Y613934D03*
Y609734D03*
X675913Y603355D03*
X695413Y604955D03*
X691213Y613355D03*
X695413D03*
X699613D03*
X691213Y609155D03*
X695413D03*
X699613Y604955D03*
Y609155D03*
X702483Y945989D03*
X667374Y1369303D03*
X672374D03*
X677374D03*
X682374D03*
X687374D03*
X692374D03*
X697374D03*
X702374D03*
X657374D03*
X662374D03*
X749146Y5500D03*
X709146D03*
X719146D03*
X729146D03*
X739146D03*
X744146D03*
X734146D03*
X724146D03*
X714146D03*
X704146D03*
X703813Y592355D03*
Y596555D03*
Y600755D03*
X704399Y626799D03*
Y618399D03*
Y622599D03*
X703813Y613355D03*
Y609155D03*
Y604955D03*
X721552Y951317D03*
X725852Y951067D03*
X747374Y1369303D03*
X742374D03*
X717374D03*
X722374D03*
X727374D03*
X732374D03*
X737374D03*
X707374D03*
X712374D03*
X795969Y-1374D03*
X759146Y5500D03*
X769146D03*
X774146D03*
X764146D03*
X754146D03*
X779146D03*
X755500Y1374500D03*
X752500Y1370500D03*
X757287Y1380873D03*
Y1385873D03*
Y1390873D03*
Y1395873D03*
Y1400873D03*
Y1405873D03*
Y1410873D03*
Y1415873D03*
Y1420873D03*
Y1425873D03*
Y1430873D03*
Y1435873D03*
Y1440873D03*
Y1445873D03*
X766156Y1462004D03*
X771156D03*
X790500Y1466500D03*
X786000Y1463500D03*
X756287Y1459264D03*
Y1454264D03*
X779547Y1463004D03*
X792902Y1477964D03*
Y1487964D03*
Y1497964D03*
Y1507964D03*
Y1517964D03*
Y1512964D03*
Y1472964D03*
Y1482964D03*
Y1492964D03*
Y1502964D03*
Y1562964D03*
Y1527964D03*
Y1537964D03*
Y1547964D03*
Y1557964D03*
Y1567964D03*
Y1522964D03*
Y1532964D03*
Y1542964D03*
Y1552964D03*
Y1612964D03*
Y1602964D03*
Y1592964D03*
Y1582964D03*
Y1572964D03*
Y1577964D03*
Y1587964D03*
Y1597964D03*
Y1607964D03*
X797902Y1652964D03*
X792902D03*
Y1642964D03*
Y1632964D03*
Y1622964D03*
Y1627964D03*
Y1637964D03*
Y1647964D03*
Y1617964D03*
X872642Y-140575D03*
Y-135575D03*
Y-130575D03*
Y-125575D03*
X890264Y-147256D03*
X880264D03*
X875264D03*
X885264D03*
X895264D03*
X872642Y-80575D03*
Y-120575D03*
Y-115575D03*
Y-110575D03*
Y-105575D03*
Y-100575D03*
Y-95575D03*
Y-90575D03*
Y-85575D03*
Y-30575D03*
Y-35575D03*
Y-40575D03*
Y-45575D03*
Y-50575D03*
Y-55575D03*
Y-60575D03*
Y-65575D03*
Y-70575D03*
Y-75575D03*
Y-20575D03*
Y-25575D03*
X940264Y-147256D03*
X930264D03*
X925264D03*
X935264D03*
X920264D03*
X910264D03*
X900264D03*
X905264D03*
X915264D03*
X960264D03*
X950264D03*
X955264D03*
X965264D03*
X945264D03*
X990264D03*
X980264D03*
X970264D03*
X975264D03*
X985264D03*
X1010264D03*
X1000264D03*
X1005264D03*
X1015264D03*
X995264D03*
X1040264D03*
X1030264D03*
X1020264D03*
X1025264D03*
X1035264D03*
X1060264D03*
X1050264D03*
X1055264D03*
X1065264D03*
X1045264D03*
X1080264D03*
X1070264D03*
X1075264D03*
X1085264D03*
X1078098Y1652768D03*
X1073098D03*
X1083098D03*
X1088098D03*
X1110264Y-147256D03*
X1100264D03*
X1090264D03*
X1105264D03*
X1095264D03*
X1130264D03*
X1120264D03*
X1115264D03*
X1125264D03*
X1135264D03*
X1093098Y1652768D03*
X1133098D03*
X1123098D03*
X1113098D03*
X1103098D03*
X1108098D03*
X1118098D03*
X1128098D03*
X1098098D03*
X1170264Y-147256D03*
X1155264D03*
X1175602Y-137594D03*
Y-127594D03*
X1160264Y-147256D03*
X1150264D03*
X1140264D03*
X1145264D03*
X1175602Y-132594D03*
Y-142594D03*
X1165264Y-147256D03*
X1175602Y-117594D03*
Y-107594D03*
Y-97594D03*
Y-87594D03*
Y-77594D03*
Y-82594D03*
Y-92594D03*
Y-102594D03*
Y-112594D03*
Y-122594D03*
Y-67594D03*
Y-57594D03*
Y-47594D03*
Y-37594D03*
Y-32594D03*
Y-42594D03*
Y-52594D03*
Y-62594D03*
Y-72594D03*
Y-17594D03*
Y-27594D03*
X1180500Y4000D03*
X1176500Y-500D03*
X1175602Y-22594D03*
Y-12594D03*
Y-7594D03*
X1162000Y1371500D03*
X1169783Y1369303D03*
X1179783D03*
X1174783D03*
X1184783D03*
X1158673Y1417067D03*
Y1407067D03*
Y1397067D03*
Y1387067D03*
Y1377067D03*
Y1412067D03*
Y1402067D03*
Y1392067D03*
Y1382067D03*
Y1422067D03*
Y1442067D03*
Y1452067D03*
X1158500Y1468500D03*
X1158673Y1457067D03*
Y1447067D03*
Y1437067D03*
Y1427067D03*
Y1462067D03*
Y1432067D03*
X1161000Y1474500D03*
X1166673Y1477941D03*
X1171673D03*
X1181673D03*
X1176673D03*
X1143098Y1652768D03*
X1183098D03*
X1173098D03*
X1163098D03*
X1153098D03*
X1158098D03*
X1168098D03*
X1178098D03*
X1138098D03*
X1148098D03*
X1191382Y5500D03*
X1196382D03*
X1186382D03*
X1201382D03*
X1211382D03*
X1221382D03*
X1231382D03*
X1226382D03*
X1216382D03*
X1206382D03*
X1199783Y1369303D03*
X1209783D03*
X1219783D03*
X1229783D03*
X1189783D03*
X1224783D03*
X1214783D03*
X1204783D03*
X1194783D03*
X1191673Y1477941D03*
X1201673D03*
X1214972Y1482642D03*
Y1517642D03*
Y1487642D03*
Y1497642D03*
Y1507642D03*
Y1512642D03*
Y1502642D03*
Y1492642D03*
X1206673Y1477941D03*
X1196673D03*
X1186673D03*
X1211673D03*
X1214972Y1567642D03*
Y1527642D03*
Y1537642D03*
Y1547642D03*
Y1557642D03*
Y1562642D03*
Y1552642D03*
Y1542642D03*
Y1532642D03*
Y1522642D03*
Y1577642D03*
Y1587642D03*
Y1597642D03*
Y1607642D03*
Y1612642D03*
Y1602642D03*
Y1592642D03*
Y1582642D03*
Y1572642D03*
Y1617642D03*
Y1627642D03*
Y1637642D03*
X1213098Y1652768D03*
X1193098D03*
X1203098D03*
X1208098D03*
X1214972Y1642642D03*
Y1632642D03*
X1188098Y1652768D03*
X1198098D03*
X1214972Y1622642D03*
Y1647642D03*
X1251382Y5500D03*
X1261382D03*
X1271382D03*
X1281382D03*
X1276382D03*
X1266382D03*
X1256382D03*
X1241382D03*
X1246382D03*
X1236382D03*
X1249783Y1369303D03*
X1259783D03*
X1269783D03*
X1279783D03*
X1239783D03*
X1274783D03*
X1264783D03*
X1254783D03*
X1234783D03*
X1244783D03*
X1301382Y5500D03*
X1311382D03*
X1296382D03*
X1316382D03*
X1306382D03*
X1291382D03*
X1286382D03*
X1326382D03*
X1321382D03*
X1299783Y1369303D03*
X1309783D03*
X1319783D03*
X1329783D03*
X1289783D03*
X1324783D03*
X1314783D03*
X1304783D03*
X1294783D03*
X1284783D03*
X1363579Y19821D03*
Y14821D03*
Y9821D03*
X1351382Y5500D03*
X1356382D03*
X1346382D03*
X1336382D03*
X1341382D03*
X1331382D03*
X1363579Y44821D03*
Y39821D03*
Y34821D03*
Y29821D03*
Y24821D03*
X1374000Y64500D03*
X1363579Y51618D03*
X1370200Y550500D03*
X1366000D03*
X1378100Y530200D03*
Y534400D03*
X1365500Y538600D03*
X1369700D03*
X1365500Y534400D03*
X1369700D03*
X1373900D03*
X1365500Y530200D03*
X1369700D03*
X1373900D03*
X1375900Y568500D03*
X1366000Y563100D03*
X1370200D03*
Y554700D03*
X1366000D03*
X1370200Y558900D03*
X1366000D03*
X1373700Y582900D03*
X1369500D03*
X1377900Y587100D03*
Y591300D03*
Y595500D03*
X1373700D03*
Y591300D03*
Y587100D03*
X1369500Y595500D03*
Y591300D03*
Y587100D03*
X1377900Y599700D03*
X1373700D03*
X1369500D03*
X1349783Y1369303D03*
X1359783D03*
X1369783D03*
X1339783D03*
X1374783D03*
X1364783D03*
X1354783D03*
X1344783D03*
X1334783D03*
X1396500Y549500D03*
X1386500Y534400D03*
Y530200D03*
X1382300D03*
Y534400D03*
X1396500Y559900D03*
Y554700D03*
Y565100D03*
X1393000Y568500D03*
X1387300D03*
X1381600D03*
X1382100Y587100D03*
X1386300D03*
X1399783Y1369303D03*
X1409783D03*
X1419783D03*
X1379783D03*
X1389783D03*
X1404783D03*
X1414783D03*
X1424783D03*
X1394783D03*
X1384783D03*
X1434441Y590424D03*
X1434581Y586136D03*
X1449783Y1369303D03*
X1459783D03*
X1469783D03*
X1429783D03*
X1439783D03*
X1444783D03*
X1454783D03*
X1464783D03*
X1474783D03*
X1434783D03*
X1499783D03*
X1509783D03*
X1519783D03*
X1479783D03*
X1489783D03*
X1494783D03*
X1484783D03*
X1504783D03*
X1514783D03*
X1565555Y16517D03*
X1568030Y5500D03*
X1565555Y21517D03*
Y26517D03*
Y31517D03*
Y36517D03*
Y41517D03*
X1557000Y64500D03*
X1561500Y62000D03*
X1564000Y57500D03*
X1564555Y52124D03*
X1549783Y1369303D03*
X1559783D03*
X1569783D03*
X1529783D03*
X1539783D03*
X1524783D03*
X1534783D03*
X1544783D03*
X1554783D03*
X1564783D03*
X1603030Y5500D03*
X1613030D03*
X1573030D03*
X1583030D03*
X1593030D03*
X1618030D03*
X1608030D03*
X1598030D03*
X1588030D03*
X1578030D03*
X1614783Y1369303D03*
X1604783D03*
X1599783D03*
X1609783D03*
X1619783D03*
X1579783D03*
X1589783D03*
X1574783D03*
X1584783D03*
X1594783D03*
X1653030Y5500D03*
X1663030D03*
X1623030D03*
X1633030D03*
X1643030D03*
X1668030D03*
X1658030D03*
X1648030D03*
X1638030D03*
X1628030D03*
X1664783Y1369303D03*
X1654783D03*
X1644783D03*
X1634783D03*
X1624783D03*
X1649783D03*
X1659783D03*
X1629783D03*
X1639783D03*
X1703030Y5500D03*
X1713030D03*
X1673030D03*
X1683030D03*
X1693030D03*
X1718030D03*
X1708030D03*
X1698030D03*
X1688030D03*
X1678030D03*
X1697261Y1004347D03*
X1692761D03*
Y999847D03*
Y995347D03*
X1697261D03*
Y999847D03*
X1714783Y1369303D03*
X1704783D03*
X1694783D03*
X1684783D03*
X1674783D03*
X1699783D03*
X1709783D03*
X1669783D03*
X1679783D03*
X1689783D03*
X1753030Y5500D03*
X1763030D03*
X1723030D03*
X1733030D03*
X1743030D03*
X1758030D03*
X1748030D03*
X1738030D03*
X1728030D03*
X1764783Y1369303D03*
X1754783D03*
X1744783D03*
X1734783D03*
X1724783D03*
X1749783D03*
X1759783D03*
X1719783D03*
X1729783D03*
X1739783D03*
X1778030Y5500D03*
X1793030D03*
X1803030D03*
X1813030D03*
X1808030D03*
X1798030D03*
X1783030D03*
X1788030D03*
X1773030D03*
X1768030D03*
X1783806Y989468D03*
X1804783Y1369303D03*
X1794783D03*
X1784783D03*
X1774783D03*
X1799783D03*
X1809783D03*
X1769783D03*
X1779783D03*
X1789783D03*
X1843030Y5500D03*
X1853030D03*
X1863030D03*
X1838030D03*
X1858030D03*
X1848030D03*
X1823030D03*
X1833030D03*
X1828030D03*
X1818030D03*
X1862652Y846508D03*
X1850263Y964540D03*
X1850370Y960239D03*
X1845870D03*
X1845763Y964540D03*
Y956040D03*
X1850263D03*
X1825741Y969210D03*
Y974210D03*
X1840683Y969318D03*
Y974318D03*
X1825744Y986011D03*
X1840578Y985885D03*
X1844863Y983125D03*
X1853863D03*
X1858363D03*
X1849363D03*
X1862863D03*
X1853863Y978125D03*
X1844863D03*
X1849363D03*
X1862863D03*
X1858363D03*
X1825744Y991011D03*
X1840578Y990885D03*
X1854783Y1369303D03*
X1844783D03*
X1834783D03*
X1824783D03*
X1814783D03*
X1849783D03*
X1859783D03*
X1819783D03*
X1829783D03*
X1839783D03*
X1878030Y5500D03*
X1883030D03*
X1873030D03*
X1868030D03*
X1909030D03*
X1888030D03*
X1873099Y817150D03*
X1878099D03*
X1873099Y821650D03*
X1878099D03*
X1873099Y826150D03*
X1878099D03*
X1877512Y831377D03*
X1882512D03*
X1865202Y831559D03*
X1873012Y831377D03*
X1878099Y812650D03*
X1873099D03*
X1878099Y808150D03*
X1873099D03*
X1878099Y803650D03*
X1873099D03*
X1878373Y846472D03*
X1883373D03*
X1867652Y846508D03*
X1867363Y983125D03*
Y978125D03*
X1904783Y1369303D03*
X1894783D03*
X1884783D03*
X1874783D03*
X1864783D03*
X1899783D03*
X1909783D03*
X1869783D03*
X1879783D03*
X1889783D03*
X1929343Y16525D03*
Y11525D03*
Y6525D03*
X1914030Y5500D03*
X1919030D03*
X1924030D03*
X1929343Y46525D03*
Y41525D03*
Y36525D03*
Y31525D03*
Y26525D03*
Y21525D03*
Y66525D03*
Y61525D03*
Y56525D03*
Y51525D03*
Y116525D03*
Y111525D03*
Y106525D03*
Y101525D03*
Y96525D03*
Y91525D03*
Y86525D03*
Y81525D03*
Y76525D03*
Y71525D03*
Y121525D03*
Y126525D03*
Y136525D03*
Y146525D03*
Y156525D03*
Y161525D03*
Y151525D03*
Y141525D03*
Y131525D03*
Y176525D03*
Y186525D03*
Y196525D03*
Y206525D03*
Y166525D03*
Y211525D03*
Y201525D03*
Y191525D03*
Y181525D03*
Y171525D03*
Y226525D03*
Y236525D03*
Y246525D03*
Y256525D03*
Y216525D03*
Y261525D03*
Y251525D03*
Y241525D03*
Y231525D03*
Y221525D03*
Y276525D03*
Y286525D03*
Y296525D03*
Y306525D03*
Y266525D03*
Y301525D03*
Y291525D03*
Y281525D03*
Y271525D03*
Y326525D03*
Y336525D03*
Y346525D03*
Y356525D03*
Y316525D03*
Y351525D03*
Y341525D03*
Y331525D03*
Y321525D03*
Y311525D03*
Y376525D03*
Y386525D03*
Y396525D03*
Y406525D03*
Y366525D03*
Y401525D03*
Y391525D03*
Y381525D03*
Y371525D03*
Y361525D03*
Y426525D03*
Y436525D03*
Y446525D03*
Y416525D03*
Y451525D03*
Y441525D03*
Y431525D03*
Y421525D03*
Y411525D03*
Y476525D03*
Y486525D03*
Y496525D03*
Y456525D03*
Y466525D03*
Y501525D03*
Y491525D03*
Y481525D03*
Y471525D03*
Y461525D03*
Y526525D03*
Y536525D03*
Y546525D03*
Y506525D03*
Y516525D03*
Y551525D03*
Y541525D03*
Y531525D03*
Y521525D03*
Y511525D03*
Y576525D03*
Y586525D03*
Y596525D03*
Y556525D03*
Y566525D03*
Y591525D03*
Y581525D03*
Y571525D03*
Y561525D03*
Y626525D03*
Y636525D03*
Y646525D03*
Y606525D03*
Y616525D03*
Y641525D03*
Y631525D03*
Y621525D03*
Y611525D03*
Y601525D03*
Y676525D03*
Y686525D03*
Y696525D03*
Y656525D03*
Y666525D03*
Y691525D03*
Y681525D03*
Y671525D03*
Y661525D03*
Y651525D03*
Y726525D03*
Y736525D03*
Y706525D03*
Y716525D03*
Y741525D03*
Y731525D03*
Y721525D03*
Y711525D03*
Y701525D03*
Y776525D03*
Y786525D03*
Y746525D03*
Y756525D03*
Y766525D03*
Y791525D03*
Y781525D03*
Y771525D03*
Y761525D03*
Y751525D03*
Y826525D03*
Y836525D03*
Y796525D03*
Y806525D03*
Y816525D03*
Y841525D03*
Y831525D03*
Y821525D03*
Y811525D03*
Y801525D03*
Y876525D03*
Y886525D03*
Y846525D03*
Y856525D03*
Y866525D03*
Y881525D03*
Y871525D03*
Y861525D03*
Y851525D03*
Y926525D03*
Y896525D03*
Y906525D03*
Y916525D03*
Y931525D03*
Y921525D03*
Y911525D03*
Y901525D03*
Y891525D03*
Y936525D03*
Y973863D03*
Y978863D03*
Y983863D03*
Y951525D03*
Y956525D03*
Y961525D03*
Y966525D03*
Y946525D03*
Y941525D03*
Y988863D03*
Y993863D03*
Y998863D03*
Y1003863D03*
Y1008863D03*
Y1033863D03*
Y1028863D03*
Y1023863D03*
Y1018863D03*
Y1013863D03*
Y1073863D03*
Y1083863D03*
Y1043863D03*
Y1053863D03*
Y1063863D03*
Y1078863D03*
Y1068863D03*
Y1058863D03*
Y1048863D03*
Y1038863D03*
Y1123863D03*
Y1093863D03*
Y1103863D03*
Y1113863D03*
Y1128863D03*
Y1118863D03*
Y1108863D03*
Y1098863D03*
Y1088863D03*
Y1173863D03*
Y1133863D03*
Y1143863D03*
Y1153863D03*
Y1163863D03*
Y1178863D03*
Y1168863D03*
Y1158863D03*
Y1148863D03*
Y1138863D03*
Y1223863D03*
Y1183863D03*
Y1193863D03*
Y1203863D03*
Y1213863D03*
Y1228863D03*
Y1218863D03*
Y1208863D03*
Y1198863D03*
Y1188863D03*
Y1273863D03*
Y1233863D03*
Y1243863D03*
Y1253863D03*
Y1263863D03*
Y1268863D03*
Y1258863D03*
Y1248863D03*
Y1238863D03*
Y1323863D03*
Y1283863D03*
Y1293863D03*
Y1303863D03*
Y1313863D03*
Y1318863D03*
Y1308863D03*
Y1298863D03*
Y1288863D03*
Y1278863D03*
Y1333863D03*
Y1343863D03*
Y1353863D03*
X1924783Y1369303D03*
X1914783D03*
X1919783D03*
X1929343Y1358863D03*
Y1348863D03*
Y1338863D03*
Y1328863D03*
Y1363863D03*
X2432929Y1214166D03*
G54D20*
X131201Y365354D03*
X131200Y818110D03*
X131201Y1270866D03*
X379232Y365354D03*
Y818110D03*
Y1270866D03*
X627263Y365354D03*
Y818110D03*
Y1270866D03*
X796457Y251203D03*
Y723644D03*
X944882Y-70078D03*
X961418Y1075613D03*
Y1418132D03*
X1181890Y544117D03*
X1181870Y957480D03*
X1181890Y1548054D03*
X1301870Y365354D03*
Y818110D03*
Y1270866D03*
X1549901Y365354D03*
Y818110D03*
Y1270866D03*
X1797933Y365354D03*
Y818110D03*
Y1270866D03*
X2432929Y1517166D03*
G54D12*
X20000Y60000D03*
Y80000D03*
Y100000D03*
Y120000D03*
Y140000D03*
Y160000D03*
Y180000D03*
Y200000D03*
Y220000D03*
Y240000D03*
Y260000D03*
Y280000D03*
Y300000D03*
Y320000D03*
Y340000D03*
Y360000D03*
Y380000D03*
Y400000D03*
Y420000D03*
Y440000D03*
X15000Y930000D03*
Y920000D03*
X25000Y930000D03*
Y920000D03*
X15000Y980000D03*
Y970000D03*
Y960000D03*
Y950000D03*
Y940000D03*
X25000D03*
Y950000D03*
Y960000D03*
Y970000D03*
Y980000D03*
X15000Y1030000D03*
Y1020000D03*
Y1010000D03*
Y1000000D03*
Y990000D03*
X25000D03*
Y1000000D03*
Y1010000D03*
Y1020000D03*
Y1040000D03*
Y1080000D03*
Y1070000D03*
Y1060000D03*
Y1050000D03*
Y1090000D03*
X19712Y1176350D03*
X25000Y1190400D03*
X17500Y1270000D03*
Y1260000D03*
Y1250000D03*
Y1240000D03*
Y1290000D03*
Y1280000D03*
Y1300000D03*
Y1310000D03*
Y1320000D03*
Y1360000D03*
Y1350000D03*
Y1330000D03*
Y1340000D03*
X60000Y20000D03*
Y40000D03*
X40000D03*
X60000Y60000D03*
X40000D03*
Y80000D03*
X60000D03*
Y100000D03*
X40000D03*
X60000Y120000D03*
X40000D03*
Y140000D03*
X60000D03*
Y160000D03*
X40000D03*
X38500Y202000D03*
X64487Y212761D03*
Y201761D03*
X53087Y179561D03*
X56000Y237000D03*
X73437Y247161D03*
X49437Y254661D03*
X73437Y234661D03*
X49937Y219661D03*
X54437D03*
X58937D03*
X62000Y276500D03*
X40000Y280000D03*
Y300000D03*
X60000D03*
Y320000D03*
X40000D03*
X60000Y340000D03*
X40000D03*
Y360000D03*
X35000Y446500D03*
X50500Y545500D03*
X58346Y516473D03*
X54088Y512336D03*
X39853Y512373D03*
X44111Y516510D03*
X47607Y527511D03*
X61834Y527515D03*
X72500Y508600D03*
X67500D03*
X40000Y560000D03*
Y580000D03*
Y600000D03*
Y620000D03*
X39000Y646000D03*
X53087Y632317D03*
X30697Y679553D03*
X73437Y687417D03*
X64487Y665417D03*
X31043Y689115D03*
X30676Y663764D03*
X58937Y672417D03*
X54437D03*
X49937D03*
X64487Y654417D03*
X27143Y663071D03*
X27510Y688422D03*
X49500Y729000D03*
X49437Y707417D03*
X73437Y699917D03*
X31064Y704904D03*
X69500Y777000D03*
X51000Y755500D03*
X38500Y800500D03*
X39000Y834500D03*
X49000Y811000D03*
X51000Y846000D03*
X40000Y930000D03*
Y920000D03*
Y970000D03*
Y960000D03*
Y950000D03*
Y940000D03*
X58175Y981325D03*
X67500Y961355D03*
X72500D03*
X50000Y1030000D03*
X70000Y1020000D03*
X40000Y1000000D03*
Y990000D03*
X50000Y1060000D03*
X47000Y1107500D03*
X64487Y1118173D03*
X30256Y1116731D03*
X30670Y1132472D03*
X58937Y1125173D03*
X54437D03*
X49937D03*
X64487Y1107173D03*
X53027Y1085073D03*
X39325Y1131400D03*
X26723Y1116038D03*
X30644Y1157871D03*
X49437Y1160173D03*
X73437Y1140173D03*
Y1152673D03*
X30623Y1142082D03*
X36848Y1173600D03*
X27090Y1141389D03*
X52000Y1186000D03*
X71500Y1205000D03*
X31500Y1224000D03*
X39425Y1226200D03*
X30000Y1190400D03*
X37225Y1230100D03*
X45800Y1306100D03*
X37500Y1360000D03*
X27500D03*
X45518Y1336366D03*
X41381Y1335567D03*
X80000Y80000D03*
X100000D03*
X120000D03*
Y100000D03*
X100000D03*
X80000D03*
X120000Y120000D03*
X100000D03*
X80000D03*
X86500Y157500D03*
X80000Y140000D03*
X118437Y141870D03*
X78500Y169500D03*
X111437Y195492D03*
X106937Y198543D03*
Y207992D03*
X111437Y165492D03*
Y180492D03*
X74937Y187461D03*
X92287Y194661D03*
X86637Y194861D03*
X95437Y176661D03*
Y181161D03*
X73937Y201661D03*
X78937D03*
X83937D03*
X88937D03*
X82000Y219000D03*
X111437Y245492D03*
Y235492D03*
X106937Y217441D03*
X111437Y265492D03*
Y275492D03*
X89237Y276861D03*
X95437Y300161D03*
X96000Y336500D03*
X80000Y320000D03*
Y340000D03*
X118437Y314114D03*
X89000Y403500D03*
X100000Y420000D03*
X120000Y440000D03*
X100000D03*
Y460000D03*
X120000D03*
Y480000D03*
X100000D03*
X120000Y500000D03*
X100000D03*
X104500Y515500D03*
X120500Y524000D03*
X86500Y522000D03*
X100000Y541500D03*
X87000Y541000D03*
X89000Y557500D03*
X108500Y572000D03*
X88000Y577500D03*
X118753Y594626D03*
X88000Y602500D03*
X111437Y648248D03*
Y633248D03*
Y618248D03*
X92287Y647417D03*
X86637Y647617D03*
X74937Y640217D03*
X85146Y621637D03*
X95437Y633917D03*
X81500Y672000D03*
X106937Y670197D03*
X111437Y688248D03*
X106937Y660748D03*
Y651299D03*
X88937Y654417D03*
X83937D03*
X78937D03*
X73937D03*
X111437Y728248D03*
Y718248D03*
Y698248D03*
X89237Y729617D03*
X75500Y757500D03*
X94000Y789000D03*
X118437Y766870D03*
X95437Y752917D03*
X89500Y802500D03*
X90000Y858000D03*
X100000Y880000D03*
Y900000D03*
X120000D03*
Y920000D03*
X100000D03*
X120000Y940000D03*
X111800Y987200D03*
Y983200D03*
X115800Y979200D03*
X119800Y971200D03*
Y975200D03*
Y979200D03*
X115800Y975200D03*
X119800Y987200D03*
Y983200D03*
X115800Y971200D03*
Y983200D03*
Y987200D03*
X119163Y959625D03*
X100000Y940000D03*
X101403Y981195D03*
X97063Y973225D03*
X98563Y977225D03*
X120000Y1025000D03*
X85000Y1020000D03*
X121914Y1003491D03*
X114100Y1002600D03*
X99700Y991400D03*
X108063Y991925D03*
X114300Y992362D03*
X104230Y992209D03*
X74000Y1074000D03*
X85000Y1060000D03*
X111437Y1071004D03*
X118437Y1047382D03*
X95537Y1082173D03*
X81000Y1124500D03*
X106937Y1122953D03*
Y1113504D03*
Y1104055D03*
X111437Y1101004D03*
Y1086004D03*
X92287Y1100173D03*
X86637Y1100373D03*
X74937Y1092973D03*
X95537Y1086673D03*
X73937Y1107173D03*
X78937D03*
X83937D03*
X88937D03*
X111437Y1171004D03*
Y1151004D03*
Y1141004D03*
X118437Y1219626D03*
X111437Y1181004D03*
X89237Y1182373D03*
X95437Y1205673D03*
X98500Y1241000D03*
X90000Y1252500D03*
X86000Y1282000D03*
X93000Y1319000D03*
X160000Y20000D03*
Y60000D03*
Y40000D03*
X140000D03*
Y60000D03*
X160000Y100000D03*
Y80000D03*
X140000D03*
Y100000D03*
X160000Y140000D03*
X140000D03*
X160000Y120000D03*
X140000D03*
X156500Y170500D03*
X130500Y211500D03*
X160500Y190000D03*
X160000Y180000D03*
X129000Y259000D03*
X142687Y237161D03*
Y248100D03*
X128000Y288500D03*
X160000Y280000D03*
X140000Y300000D03*
X160000D03*
X145437Y265561D03*
X140000Y320000D03*
X160000D03*
X140000Y440000D03*
Y460000D03*
Y480000D03*
Y500000D03*
X142500Y515500D03*
X150000Y526500D03*
X164107Y512331D03*
X168365Y516368D03*
X135000Y588000D03*
X153263Y568725D03*
X146263D03*
X144263Y573225D03*
X138763Y568725D03*
X148763Y576225D03*
X166400Y579400D03*
X168103Y569195D03*
X163763Y561225D03*
X165263Y565225D03*
X167000Y613000D03*
X147500Y605500D03*
X142687Y689917D03*
X135200Y738400D03*
X153705Y744831D03*
X153714Y720741D03*
X153757Y710653D03*
X140372Y732370D03*
X150253Y709713D03*
X145437Y717617D03*
X142687Y700767D03*
X140364Y749807D03*
X160000Y880000D03*
Y900000D03*
X140000Y920000D03*
X160000D03*
Y940000D03*
X140000D03*
X137163Y987125D03*
X130463Y983925D03*
X156000Y1032000D03*
X133063Y1012725D03*
X137063Y993725D03*
X145363Y997741D03*
X131110Y993257D03*
X134000Y1064000D03*
X153000Y1105000D03*
X132000Y1117000D03*
X148400Y1086900D03*
X142687Y1142673D03*
X154363Y1161725D03*
X153716Y1174793D03*
X145437Y1165673D03*
X150862Y1152723D03*
X142687Y1153523D03*
X170000Y1190500D03*
X153824Y1197248D03*
X153932Y1182940D03*
X148300Y1228800D03*
X148311Y1182767D03*
X135422Y1190937D03*
X140422D03*
X163500Y1345200D03*
X200000Y20000D03*
X180000D03*
X200000Y40000D03*
X180000D03*
X200000Y60000D03*
X180000D03*
Y80000D03*
X200000D03*
Y100000D03*
X180000D03*
Y120000D03*
X200000D03*
Y140000D03*
X180000D03*
X216500Y194756D03*
X210849Y194861D03*
X199149Y187461D03*
X188699Y212561D03*
Y200561D03*
X177399Y179661D03*
X198149Y201661D03*
X203149D03*
X208149D03*
X213149D03*
X206000Y219000D03*
X180500Y237000D03*
X197649Y234661D03*
X173649Y254661D03*
X197649Y247161D03*
X174149Y219661D03*
X178649D03*
X183149D03*
X180000Y300000D03*
X213449Y276861D03*
X180000Y320000D03*
Y340000D03*
X200000D03*
X178342Y512294D03*
X182600Y516331D03*
X171861Y527469D03*
X186088Y527473D03*
X196712Y508600D03*
X191712D03*
X210263Y546725D03*
X188614Y591491D03*
X182500Y559200D03*
Y571200D03*
Y575200D03*
X178500D03*
Y571200D03*
X182500Y567200D03*
X186500Y559200D03*
Y563200D03*
Y567200D03*
X182500Y563200D03*
X186500Y575200D03*
Y571200D03*
X180800Y590600D03*
X207313Y598113D03*
X203763Y581725D03*
X212063Y585741D03*
X197810Y581257D03*
X174763Y579925D03*
X203863Y575125D03*
X181000Y580362D03*
X170930Y580209D03*
X197163Y571925D03*
X210000Y644000D03*
X216499Y636917D03*
X199149Y631217D03*
X210849Y638617D03*
X185149Y617949D03*
X199763Y600725D03*
X206000Y672000D03*
X197649Y687417D03*
X210000Y650000D03*
X182259Y672559D03*
X177759D03*
X173259D03*
X198149Y654417D03*
X203149D03*
X208149D03*
X213149D03*
X213449Y729617D03*
X173649Y707417D03*
X197649Y699917D03*
X180000Y860000D03*
Y880000D03*
Y920000D03*
Y900000D03*
X199900Y923200D03*
X188706Y941328D03*
X194206D03*
X184017Y951112D03*
Y945612D03*
X198463Y945525D03*
Y951025D03*
X216712Y961155D03*
X184295Y1009469D03*
Y1014969D03*
X198741Y1014882D03*
Y1009382D03*
X188552Y1019166D03*
X215563Y1001225D03*
X203563D03*
X207563D03*
X211563D03*
X194052Y1019166D03*
X211000Y1065000D03*
X203500Y1124500D03*
X216499Y1100173D03*
X210849Y1100373D03*
X199149Y1092973D03*
X188399Y1113873D03*
Y1102873D03*
X183149Y1125173D03*
X178649D03*
X174149D03*
X177105Y1094839D03*
X195100Y1096800D03*
X198149Y1107173D03*
X203149D03*
X208149D03*
X213149D03*
X175000Y1143000D03*
X173649Y1160173D03*
X193423Y1140945D03*
X197649Y1152673D03*
X213449Y1182373D03*
X181000Y1261000D03*
X190000Y1320000D03*
X200000D03*
X210000D03*
Y1300000D03*
Y1310000D03*
X200000D03*
X190000D03*
X260000Y20000D03*
X220000D03*
X240000D03*
X260000Y60000D03*
Y40000D03*
X240000D03*
X220000D03*
Y60000D03*
X240000D03*
X260000Y100000D03*
Y80000D03*
X240000D03*
X220000D03*
Y100000D03*
X240000D03*
X260000Y140000D03*
Y120000D03*
X240000D03*
X220000D03*
X242649Y141870D03*
X262000Y209000D03*
X235649Y195492D03*
X231991Y198543D03*
X231149Y207992D03*
X235649Y165492D03*
Y180492D03*
X219749Y176661D03*
Y181361D03*
X253000Y260000D03*
X266899Y237161D03*
X235649Y245492D03*
Y235492D03*
X231149Y217441D03*
X266899Y248011D03*
X255000Y280000D03*
X235649Y265492D03*
Y275492D03*
X219649Y300161D03*
X242649Y314114D03*
X220000Y360000D03*
X240000Y380000D03*
X220000D03*
Y400000D03*
X240000D03*
Y420000D03*
X220000D03*
Y440000D03*
X240000D03*
Y460000D03*
X220000D03*
Y480000D03*
X240000D03*
Y500000D03*
X220000D03*
X265392Y539225D03*
Y533725D03*
X250586Y533920D03*
Y539420D03*
X260703Y529168D03*
X255203D03*
X220000Y520000D03*
X265275Y596896D03*
X250974Y597308D03*
X243051Y594626D03*
X265275Y602396D03*
X250974Y602808D03*
X255410Y607833D03*
X235649Y648248D03*
Y633248D03*
Y618248D03*
X260910Y607833D03*
X219749Y618917D03*
Y623417D03*
X255500Y664500D03*
X231149Y670197D03*
X235649Y688248D03*
X231149Y660748D03*
Y651299D03*
X266899Y689917D03*
X235649Y728248D03*
Y718248D03*
Y698248D03*
X264739Y732114D03*
X258600Y715500D03*
X266899Y700767D03*
X242649Y766870D03*
X219649Y752917D03*
X248500Y788500D03*
X264731Y749551D03*
X225000Y840000D03*
X245000D03*
X265000Y795000D03*
X225000Y815000D03*
Y880000D03*
X245000D03*
X225000Y860000D03*
X245000D03*
X225000Y900000D03*
X245000D03*
X223100Y920600D03*
X245000Y940000D03*
X239000Y985600D03*
X221712Y961155D03*
X263000Y1023000D03*
X219563Y1001225D03*
X223563D03*
X252100Y990100D03*
X244600Y1004600D03*
X261100Y1005700D03*
X227063Y994925D03*
X263000Y1047000D03*
X235649Y1071004D03*
X242649Y1047382D03*
X219749Y1082173D03*
X231149Y1122953D03*
Y1113504D03*
Y1104055D03*
X235649Y1101004D03*
Y1086004D03*
X264864Y1120500D03*
X219749Y1086873D03*
X235649Y1171004D03*
Y1151004D03*
X235300Y1142700D03*
X266899Y1141173D03*
X255000Y1207500D03*
X242649Y1219626D03*
X235649Y1181004D03*
X219649Y1205673D03*
X264594Y1190768D03*
X259594D03*
X257000Y1253000D03*
X220000Y1270000D03*
Y1320000D03*
X230000D03*
X240000D03*
X250000D03*
X260000D03*
X220000Y1280000D03*
X230000D03*
X250000Y1290000D03*
X240000D03*
X230000D03*
X220000D03*
Y1300000D03*
X230000D03*
X240000D03*
X250000D03*
X260000D03*
Y1310000D03*
X250000D03*
X240000D03*
X230000D03*
X220000D03*
X300000Y20000D03*
X280000D03*
X300000Y40000D03*
X280000Y60000D03*
Y40000D03*
X312079Y68379D03*
X303029Y68429D03*
X280000Y100000D03*
Y80000D03*
X313312Y98705D03*
X312355Y72855D03*
X313628Y112926D03*
X303000Y73500D03*
X280000Y140000D03*
Y120000D03*
X314370Y118452D03*
X314439Y133669D03*
X270000Y179500D03*
X285500Y189500D03*
X283000Y181000D03*
X314329Y212420D03*
X312912Y201661D03*
X301612Y179661D03*
X304500Y237000D03*
X297862Y254661D03*
X298362Y219661D03*
X302862D03*
X307362D03*
X300000Y300000D03*
X269649Y266261D03*
X300000Y320000D03*
Y340000D03*
X295000Y400000D03*
Y440000D03*
X291601Y418503D03*
X295000Y460000D03*
X292153Y486059D03*
X306388Y486022D03*
X302513Y512294D03*
X306771Y516331D03*
X292536Y516368D03*
X288278Y512331D03*
X296032Y527469D03*
X310259Y527473D03*
X282263Y589225D03*
X270263D03*
X274263D03*
X286263D03*
X290263D03*
X278263D03*
X293763Y582925D03*
X277000Y618500D03*
X275000Y647000D03*
X294500Y607500D03*
X284000D03*
X301612Y632417D03*
X312912Y665417D03*
X307362Y672417D03*
X302862D03*
X298362D03*
X312912Y654417D03*
X277972Y744575D03*
X297862Y707417D03*
X277981Y720485D03*
X278024Y710397D03*
X274520Y709457D03*
X286000Y810500D03*
X268100Y982300D03*
X273300Y981700D03*
X280800Y1011900D03*
X281200Y1033000D03*
X305200Y1068400D03*
X295200Y1078400D03*
Y1058400D03*
X271100Y1063200D03*
X281500Y1036744D03*
X281000Y1105000D03*
X312912Y1118273D03*
X307362Y1125173D03*
X302862D03*
X298362D03*
X313232Y1106499D03*
X301327Y1085173D03*
X304500Y1142500D03*
X302452Y1165162D03*
X278577Y1161725D03*
X277930Y1175001D03*
X269649Y1165673D03*
X275385Y1152596D03*
X271165Y1147172D03*
X306000Y1182500D03*
X278076Y1197355D03*
X278146Y1182940D03*
X315500Y1216700D03*
X276100Y1229100D03*
X273243Y1182915D03*
X286925Y1201945D03*
X301000Y1231000D03*
X295900Y1339700D03*
X296100Y1335100D03*
X279900Y1328300D03*
X283700D03*
X286100Y1349659D03*
X292600Y1337367D03*
X289510Y1342259D03*
X360000Y20000D03*
X340000D03*
X320000D03*
X360000Y40000D03*
X340000D03*
X320000D03*
X355200Y58400D03*
X346245Y58745D03*
X354100Y62100D03*
X322500Y68345D03*
X334845Y58745D03*
X317812Y98905D03*
X353001Y81799D03*
X351000Y70700D03*
X322545Y72845D03*
X361776Y70842D03*
X335081Y104081D03*
X339219Y95188D03*
X339914Y82415D03*
X344304Y82439D03*
X345321Y102400D03*
X347647Y95614D03*
X353001Y114815D03*
X347881Y114881D03*
X351416Y95788D03*
X337641Y114910D03*
X334947Y94605D03*
X342761Y114861D03*
X328000Y150500D03*
X333021Y129679D03*
X350441Y117541D03*
X337721Y129821D03*
X323813Y118512D03*
X341114Y123622D03*
X345321Y118921D03*
X323813Y133722D03*
X359862Y165492D03*
Y180492D03*
Y195492D03*
X355362Y198543D03*
Y207992D03*
X323362Y187461D03*
X340712Y194661D03*
X335062Y194861D03*
X344062Y176461D03*
X343962Y181161D03*
X322362Y201661D03*
X327362D03*
X332362D03*
X337362D03*
X333500Y219000D03*
X359862Y245492D03*
Y235492D03*
X355362Y217441D03*
X321862Y234661D03*
Y247161D03*
X359862Y265492D03*
Y275492D03*
X337662Y276861D03*
X343862Y300161D03*
X352000Y331000D03*
X320000Y340000D03*
X320474Y379474D03*
X316534D03*
X320474Y363234D03*
X316534D03*
X350000Y440000D03*
X330000D03*
X350000Y500000D03*
Y480000D03*
Y460000D03*
X330000D03*
X320925Y485385D03*
X315925D03*
X330000Y540000D03*
X350000D03*
Y520000D03*
X320925Y508600D03*
X315925D03*
X333000Y560000D03*
Y580000D03*
X350000Y560000D03*
X333000Y604000D03*
X359862Y648248D03*
Y633248D03*
Y618248D03*
X340712Y647517D03*
X335062Y647617D03*
X323362Y640217D03*
X333682Y621858D03*
X343862Y633917D03*
X330000Y672000D03*
X355362Y670197D03*
X359862Y688248D03*
X355362Y660748D03*
Y651299D03*
X321862Y687417D03*
X322362Y654417D03*
X327362D03*
X332362D03*
X337362D03*
X359862Y728248D03*
Y718248D03*
Y698248D03*
X337662Y729617D03*
X321862Y699917D03*
X355000Y780500D03*
X320000Y750000D03*
X330000Y770000D03*
X347000Y788500D03*
X343862Y752917D03*
X320474Y832229D03*
X316534D03*
X361500Y901500D03*
X330000Y900000D03*
X320925Y938140D03*
X315600Y933600D03*
X335300Y926900D03*
X360000Y960000D03*
Y940000D03*
X330000Y960000D03*
X337100Y972100D03*
X320925Y961355D03*
X315925D03*
X322000Y988500D03*
X362000Y1017000D03*
X344737Y995637D03*
X350673Y1031200D03*
X328000Y1061000D03*
X359862Y1071004D03*
X344062Y1082073D03*
X355362Y1122953D03*
Y1113504D03*
Y1104055D03*
X359862Y1101004D03*
Y1086004D03*
X340812Y1100273D03*
X335062Y1100373D03*
X323362Y1092973D03*
X344062Y1086773D03*
X322362Y1107173D03*
X327362D03*
X332362D03*
X337362D03*
X358518Y1171114D03*
X359862Y1151004D03*
Y1141004D03*
X321862Y1140173D03*
Y1152673D03*
X331679Y1175800D03*
X327500Y1197000D03*
X359862Y1181004D03*
X337662Y1182373D03*
X343862Y1205673D03*
X353000Y1231000D03*
X330000Y1302000D03*
X380000Y20000D03*
Y60000D03*
Y40000D03*
X401000Y89000D03*
X400000Y80000D03*
X365162Y88731D03*
Y77731D03*
X377144Y84720D03*
X377944Y95929D03*
X388500Y153500D03*
X395500Y160500D03*
X366862Y141870D03*
X386000Y209000D03*
X390312Y237161D03*
X390412Y248011D03*
X389000Y289000D03*
X386800Y263800D03*
X385500Y313000D03*
X366862Y314114D03*
X390000Y500000D03*
X370000D03*
X390000Y540000D03*
Y520000D03*
X370000D03*
Y540000D03*
X389000Y594500D03*
X390000Y560000D03*
X370000D03*
X366862Y594626D03*
X395000Y631000D03*
X388000Y607000D03*
X410000Y692500D03*
X379000Y664000D03*
X391112Y689917D03*
X402129Y744503D03*
X388796Y732042D03*
X402138Y720413D03*
X402181Y710325D03*
X393862Y719917D03*
X398677Y709385D03*
X391112Y700767D03*
X402500Y780500D03*
X366862Y766870D03*
X388788Y749479D03*
X407714Y761291D03*
X398254Y763517D03*
X397000Y911000D03*
X380000Y960000D03*
Y940000D03*
X393500Y988500D03*
Y1017000D03*
X408672Y1008038D03*
X390000Y1055000D03*
X366862Y1047382D03*
X388888Y1118173D03*
X391112Y1142673D03*
X399474Y1166787D03*
X385210Y1166347D03*
X393679Y1157480D03*
X383191Y1170203D03*
X391112Y1153500D03*
X366862Y1219626D03*
X406037Y1192706D03*
X402403Y1188312D03*
X398527Y1188659D03*
X383849Y1190833D03*
X388849Y1191148D03*
X398527Y1233336D03*
X437124Y212661D03*
X447574Y187461D03*
X437124Y201661D03*
X429224Y176300D03*
X446951Y213656D03*
X451951D03*
X456951D03*
X446074Y247161D03*
X422300Y254661D03*
X446074Y234661D03*
X431574Y219661D03*
X427074D03*
X422574D03*
X441645Y288847D03*
Y284647D03*
X456190Y354105D03*
X444687Y379474D03*
X440747D03*
X444687Y363234D03*
X440747D03*
X452800Y420912D03*
X418600Y445462D03*
X421700Y450200D03*
X445138Y487743D03*
X440138D03*
X447533Y475900D03*
X458679Y470700D03*
X450500Y459562D03*
X416303Y486022D03*
X430538Y485985D03*
X430000Y545500D03*
X460000Y540000D03*
X426663Y512257D03*
X430921Y516294D03*
X416686Y516331D03*
X412428Y512294D03*
X420182Y527432D03*
X434409Y527436D03*
X440138Y508600D03*
X445138D03*
X460000Y600000D03*
X445000D03*
X440000Y560000D03*
X460000D03*
X440000Y613000D03*
X459274Y647617D03*
X447574Y640217D03*
X425824Y632317D03*
X457853Y622091D03*
X417000Y652500D03*
X454500Y672000D03*
X446074Y687417D03*
X437224Y665417D03*
Y654417D03*
X431574Y672417D03*
X427074D03*
X422574D03*
X456574Y654417D03*
X451574D03*
X446574D03*
X452500Y744500D03*
X437500Y744000D03*
X422074Y707417D03*
X446074Y699917D03*
X455000Y780000D03*
X445000D03*
X440000Y760000D03*
X445000Y798000D03*
X444687Y832229D03*
X440747D03*
X444687Y816765D03*
X440747D03*
X445138Y938140D03*
X440138D03*
X435082Y915200D03*
X437600Y917800D03*
X445582Y925352D03*
X449137Y967757D03*
X440138Y961355D03*
X445138D03*
X428000Y988500D03*
X429613Y1017920D03*
X432657Y1015102D03*
X442600Y998300D03*
X413000Y1054200D03*
X442473Y1068726D03*
X447173D03*
X424000Y1105000D03*
X453473Y1089300D03*
X456919Y1121725D03*
X447919D03*
X452419D03*
X441976Y1107576D03*
X446627Y1112973D03*
X418500Y1176800D03*
X437104Y1160696D03*
X441400Y1169400D03*
X450500Y1208500D03*
X424000Y1206000D03*
X416900Y1221800D03*
X454500Y1248500D03*
X460000Y1320000D03*
X440000D03*
X460000Y1300000D03*
X412300Y1326200D03*
X415422Y1352000D03*
X422373Y1359747D03*
X418922Y1356522D03*
X476319Y144481D03*
X506750Y165324D03*
X480159Y201245D03*
X500184Y200328D03*
X497785Y178034D03*
X478306Y195593D03*
X461122Y194861D03*
X462200Y173109D03*
X468472Y182441D03*
X461951Y213656D03*
X484074Y245492D03*
X478651Y220734D03*
X484074Y235492D03*
Y275492D03*
X481174Y265492D03*
X461874Y276861D03*
X468074Y300161D03*
X491074Y314114D03*
X470000Y400000D03*
Y380000D03*
Y430000D03*
X465000Y491000D03*
X462133Y473300D03*
X481533Y480875D03*
X506746Y512331D03*
X497351Y531531D03*
X501023Y534941D03*
X499000Y553000D03*
X491074Y594626D03*
X472022Y582062D03*
X484074Y648248D03*
Y633248D03*
Y618248D03*
X464924Y647417D03*
X468174Y633917D03*
X479574Y670197D03*
X484074Y688248D03*
X479574Y660748D03*
Y651299D03*
X461574Y654417D03*
X484074Y728248D03*
Y718248D03*
Y698248D03*
X461874Y729617D03*
X461500Y769500D03*
X491074Y766870D03*
X468074Y752917D03*
X500000Y960000D03*
Y940000D03*
X480000Y960000D03*
Y940000D03*
X504000Y988500D03*
X462000D03*
X465200Y1018200D03*
X468000Y1047000D03*
X484074Y1071004D03*
X491074Y1047382D03*
X460673Y1071976D03*
X460873Y1077526D03*
X506500Y1051900D03*
X465346Y1122953D03*
X479574Y1113504D03*
Y1104055D03*
X484074Y1101004D03*
Y1086004D03*
X504724Y1118073D03*
Y1107073D03*
X484074Y1171004D03*
Y1151004D03*
Y1141004D03*
X506700Y1141973D03*
X505874Y1134773D03*
X506700Y1145973D03*
X502500Y1211500D03*
X476373Y1219498D03*
X484074Y1181004D03*
X461874Y1182373D03*
X468074Y1205673D03*
X508103Y1190557D03*
X480000Y1320000D03*
X500000Y1300000D03*
X480000D03*
Y1280000D03*
X509180Y145419D03*
X546009Y187821D03*
X539584Y184694D03*
X542155Y187543D03*
X519868Y242334D03*
X557057Y220152D03*
X553674Y220121D03*
X550219Y220111D03*
X515324Y252511D03*
X515500Y301000D03*
X550987Y262810D03*
X553742Y267705D03*
X510700Y277200D03*
X548500Y343000D03*
X515000Y322500D03*
X534905Y354105D03*
X547500Y440000D03*
X539350Y487659D03*
X534350D03*
X510621Y486059D03*
X524856Y486022D03*
X520981Y512294D03*
X549279Y513331D03*
X525579Y538331D03*
X557279Y513331D03*
X525239Y516331D03*
X511004Y516368D03*
X518700Y548700D03*
X553279Y523331D03*
X514500Y524469D03*
X528727Y524973D03*
X553279Y513331D03*
X530130Y547167D03*
X534350Y508600D03*
X539350D03*
X540000Y583000D03*
Y600000D03*
X520000D03*
X533879Y566031D03*
X548767Y556819D03*
X520579Y553231D03*
X517499Y576931D03*
X557279Y570331D03*
X527179Y568731D03*
X528000Y611000D03*
X532000Y623000D03*
X549937Y632317D03*
X515324Y689917D03*
X555787Y672417D03*
X551287D03*
X546787D03*
X526225Y744756D03*
X546287Y707417D03*
X512892Y732295D03*
X526277Y710578D03*
X526234Y720666D03*
X509996Y716996D03*
X522773Y709638D03*
X515324Y700667D03*
X509000Y772000D03*
X512884Y749732D03*
X555500Y852000D03*
X551500Y888000D03*
X523500Y883500D03*
X525000Y937000D03*
X525500Y967000D03*
X530800Y1028300D03*
X515800Y1028000D03*
X523000Y1045000D03*
X528500Y1073500D03*
X556022Y1042817D03*
X552436Y1042494D03*
X546787Y1125173D03*
X551287D03*
X555787D03*
X549773Y1085173D03*
X514474Y1107073D03*
X519474D03*
X524474D03*
X529474D03*
X546287Y1160173D03*
X535320Y1152771D03*
X534874Y1139774D03*
X526523Y1177122D03*
X526501Y1166546D03*
X509037Y1136700D03*
X524828Y1159231D03*
X526388Y1197747D03*
X526367Y1183111D03*
X522867Y1190284D03*
X513103Y1190557D03*
X522867Y1231097D03*
X539000Y1309000D03*
X520600Y1324100D03*
X536000Y1359826D03*
X541362D03*
X518397Y1360000D03*
X512900Y1345600D03*
X553587Y1346026D03*
X527000Y1340600D03*
X521500Y1342800D03*
X603787Y207992D03*
X604517Y196263D03*
X603697Y182091D03*
X586719Y196888D03*
X568687Y187660D03*
X583487Y194861D03*
X566271Y167387D03*
X561437Y197249D03*
X592767Y179277D03*
X598236Y181981D03*
X582697Y200744D03*
X577697D03*
X572697D03*
X587697D03*
X588188Y216520D03*
X570287Y234661D03*
X563000Y217600D03*
X569009Y247887D03*
X592287Y300161D03*
X582758Y276861D03*
X590000Y342000D03*
X568899Y379474D03*
X564959D03*
X568899Y363234D03*
X564959D03*
X560000Y438500D03*
X594500Y462000D03*
X569529Y502127D03*
X575700Y528831D03*
X563279Y506731D03*
X602379Y547831D03*
X570779Y542831D03*
X568779Y512831D03*
X575779D03*
X593079Y516531D03*
Y512531D03*
X585479Y537731D03*
Y543994D03*
X572229Y520081D03*
X580279Y512831D03*
X592000Y595000D03*
X580000Y600000D03*
X560000D03*
X571408Y577450D03*
X584279Y577431D03*
X575779D03*
X579718D03*
X592779D03*
X588779D03*
X562279D03*
X567641Y577473D03*
X571529Y562951D03*
X579529D03*
X602779Y552331D03*
X586000Y611000D03*
X589137Y647417D03*
X583487Y647617D03*
X571787Y640217D03*
X592387Y629417D03*
Y634017D03*
X579000Y672000D03*
X603787Y670197D03*
Y660748D03*
Y651299D03*
X570287Y687417D03*
X561437Y665417D03*
Y654417D03*
X585787D03*
X580787D03*
X575787D03*
X570787D03*
X559000Y741000D03*
X586087Y729617D03*
X570287Y699917D03*
X603000Y781000D03*
X592287Y752917D03*
X568899Y832229D03*
X564959D03*
X593365Y877358D03*
X592614Y882300D03*
X604000Y897000D03*
X592000Y900500D03*
X569350Y941640D03*
X564350D03*
X569350Y961355D03*
X564350D03*
X589500Y988000D03*
X571000D03*
X571400Y1000100D03*
X575000Y1057500D03*
X586500Y1061500D03*
X586000Y1046500D03*
X575000Y1046000D03*
X592387Y1082173D03*
X561337Y1120873D03*
X583487Y1100373D03*
X571787Y1092973D03*
X589137Y1100173D03*
X603787Y1122953D03*
Y1113504D03*
Y1104055D03*
X561337Y1107173D03*
X592387Y1086873D03*
X570787Y1107173D03*
X575787D03*
X580787D03*
X585787D03*
X570287Y1140173D03*
Y1152673D03*
X600640Y1171000D03*
X567500Y1189500D03*
X586087Y1182373D03*
X592287Y1205673D03*
X592400Y1214456D03*
X590000Y1247000D03*
X613500Y66000D03*
X634500Y77000D03*
X629024Y107633D03*
X607929Y112329D03*
X619171D03*
X614967Y134777D03*
X606718Y168580D03*
X639537Y237161D03*
X608287Y245492D03*
Y235492D03*
X639537Y248011D03*
X649500Y285000D03*
X608287Y275492D03*
X607961Y263934D03*
X642287Y266461D03*
X650000Y322500D03*
X615287Y314114D03*
X649000Y429500D03*
X652663Y502400D03*
X647663D03*
X612000Y502300D03*
X624028Y503558D03*
X638263Y503494D03*
X643000Y549500D03*
X620153Y511994D03*
X634388Y511957D03*
X615100Y513287D03*
X638646Y515994D03*
X624411Y516031D03*
X615119Y551586D03*
X627000Y538581D03*
Y542909D03*
X609334Y538306D03*
Y543306D03*
X619560Y547201D03*
X627863Y522000D03*
X642509Y520667D03*
X652663Y516600D03*
X647663D03*
X615287Y594626D03*
X615147Y565956D03*
X637213Y582155D03*
X623236Y562574D03*
X608287Y648248D03*
Y633248D03*
Y618248D03*
Y688248D03*
X639537Y689917D03*
X650659Y744673D03*
X608287Y728248D03*
Y718248D03*
Y698248D03*
X637326Y732212D03*
X650668Y720583D03*
X650711Y710495D03*
X642287Y719817D03*
X647207Y709555D03*
X639537Y700767D03*
X631500Y774000D03*
X615287Y766870D03*
X637318Y749649D03*
X642000Y889500D03*
X632000Y936000D03*
X654000Y911000D03*
X646500Y898500D03*
X634000Y988000D03*
X638500Y1046500D03*
X608287Y1071004D03*
X615287Y1047382D03*
X645200Y1067800D03*
X608287Y1101004D03*
Y1086004D03*
X643000Y1146173D03*
X608287Y1171004D03*
Y1151004D03*
Y1141004D03*
X651216Y1164051D03*
X636803Y1167864D03*
X642942Y1156818D03*
X632603Y1136225D03*
X647716Y1154150D03*
X639537Y1153523D03*
X615238Y1218951D03*
X608287Y1181004D03*
X650644Y1197038D03*
X650626Y1182447D03*
X627632Y1217300D03*
X647126Y1189513D03*
X632316Y1190474D03*
X637316D03*
X700000Y60000D03*
X675000Y75500D03*
X697457Y107247D03*
X697483Y111500D03*
X661965Y106177D03*
X687566Y109568D03*
X663449Y115606D03*
X690807Y103298D03*
X658500Y184500D03*
X695137Y189130D03*
X685545Y212806D03*
X677450Y185669D03*
X685250Y199493D03*
X699950Y200846D03*
X694950D03*
X689426Y236628D03*
X694500Y247161D03*
X670500Y254661D03*
X674313Y220374D03*
X669813D03*
X673500Y344000D03*
X689232Y355251D03*
X693112Y385976D03*
X689172D03*
Y358978D03*
X698500Y415500D03*
X695500Y462500D03*
X670000Y531500D03*
X658646Y515180D03*
X696787Y580633D03*
X658681Y571798D03*
X654681D03*
X683341Y580479D03*
X689747D03*
X696000Y641717D03*
X682000Y628449D03*
X694500Y687417D03*
X685550Y665417D03*
Y654417D03*
X679929Y673058D03*
X675429D03*
X670929D03*
X700000Y654417D03*
X695000D03*
X670500Y707417D03*
X694500Y699917D03*
X691500Y778000D03*
X692500Y790500D03*
X678500Y776500D03*
X673500Y752000D03*
X658574Y930100D03*
X677457Y944796D03*
X688563Y961355D03*
X693563D03*
X663800Y1018300D03*
X682200Y1026500D03*
X674300Y1001620D03*
X696000Y1092973D03*
X685250Y1113673D03*
Y1102873D03*
X680000Y1125173D03*
X675500D03*
X671000D03*
X674700Y1098500D03*
X695000Y1107173D03*
X700000D03*
X667700Y1160173D03*
X694500Y1140173D03*
X692671Y1152747D03*
X668000Y1195000D03*
X680500Y1208500D03*
X698500Y1306500D03*
X664000Y1278100D03*
X673000Y1354100D03*
X740000Y40000D03*
X720000D03*
Y60000D03*
X740000D03*
X724645Y138941D03*
X732500Y180492D03*
Y165492D03*
X728000Y207992D03*
Y198543D03*
X732100Y198373D03*
X707700Y194861D03*
X713350Y194661D03*
X747242Y197553D03*
X717188Y176461D03*
X716600Y181161D03*
X709950Y200846D03*
X704950D03*
X728000Y217441D03*
X732500Y245492D03*
X731048Y238563D03*
X738361Y306612D03*
X732500Y275492D03*
Y265492D03*
X710300Y276861D03*
X716500Y300161D03*
X724000Y338500D03*
X748000Y368500D03*
X726000Y369000D03*
X732000Y374500D03*
Y383000D03*
X748500Y409000D03*
X721500Y462500D03*
X727500Y476000D03*
X705348Y478425D03*
X724000Y583500D03*
X702500Y563000D03*
X739500Y594626D03*
X732500Y648248D03*
Y633248D03*
Y618248D03*
X713350Y647417D03*
X716600Y629417D03*
Y633917D03*
X704500Y672000D03*
X728000Y670197D03*
X732500Y688248D03*
X728000Y660748D03*
Y651299D03*
X707700Y649117D03*
X710000Y654417D03*
X705000D03*
X732500Y728248D03*
Y718248D03*
Y698248D03*
X710300Y729617D03*
X748000Y783000D03*
X739500Y766870D03*
X716500Y752917D03*
X745000Y833000D03*
X704500Y795000D03*
X730882Y888502D03*
X716233Y868219D03*
X733422Y857828D03*
X708683Y876958D03*
X747656Y876717D03*
X724283Y860689D03*
X737984Y861689D03*
X741883Y861389D03*
X709500Y894500D03*
X733883Y935689D03*
X736883Y938689D03*
Y929189D03*
Y933689D03*
X747383Y924689D03*
X733883Y940689D03*
X736462Y948996D03*
X736883Y943189D03*
X712000Y1046000D03*
X732500Y1071004D03*
X739500Y1047382D03*
X716600Y1081973D03*
X728000Y1122953D03*
Y1113504D03*
Y1104055D03*
X732500Y1101004D03*
Y1086004D03*
X713350Y1100173D03*
X707700Y1100373D03*
X716600Y1086673D03*
X705000Y1107173D03*
X710000D03*
X716000Y1136000D03*
X732500Y1171004D03*
Y1151004D03*
Y1141004D03*
X739500Y1219626D03*
X732500Y1181004D03*
X710300Y1182373D03*
X716500Y1205673D03*
X728174Y1275611D03*
X725678Y1272799D03*
X722790Y1270557D03*
X720446Y1267427D03*
X748500Y1287500D03*
X731500Y1277811D03*
X789045Y11615D03*
X780000Y40000D03*
X760000D03*
Y60000D03*
X780000D03*
X757020Y159692D03*
X752950Y213450D03*
X758619Y168537D03*
X767405Y210364D03*
X763188Y172500D03*
X771500Y311000D03*
X789739Y365493D03*
X764000Y439500D03*
X767500Y463500D03*
X772000Y479500D03*
X787000Y514000D03*
X798140Y630220D03*
X798210Y626440D03*
X798367Y622400D03*
X751750Y685300D03*
X754500Y668741D03*
X755000Y677700D03*
X793000Y828000D03*
Y851000D03*
X765124Y864089D03*
X766707Y872260D03*
X762453Y872413D03*
X765025Y867802D03*
X757664Y868974D03*
X753883Y929689D03*
Y937689D03*
X763883Y907689D03*
X755883D03*
X750883Y903689D03*
X753893Y912630D03*
X753883Y945689D03*
X776400Y956500D03*
X780800Y959300D03*
X778000Y988500D03*
X762500D03*
X786800Y1016000D03*
X784000Y1024000D03*
X763000Y1075000D03*
X759500Y1056100D03*
X756250Y1140250D03*
X779535Y1180469D03*
X792263Y1178661D03*
Y1174461D03*
Y1170261D03*
X752500Y1167500D03*
X756250Y1151750D03*
X752000Y1197500D03*
X756000Y1225500D03*
X784544Y1210178D03*
Y1205978D03*
X779535Y1193469D03*
Y1189269D03*
Y1184669D03*
X797177Y1189537D03*
X797225Y1185337D03*
X792263Y1182861D03*
X770000Y1231500D03*
X769500Y1283500D03*
X792336Y1319537D03*
X782230Y1323670D03*
X769728Y1325747D03*
X785340Y1320410D03*
X789549Y1322310D03*
X777009Y1322690D03*
X781000Y1373000D03*
X781290Y1328490D03*
X772900Y1328550D03*
X790290Y1328410D03*
X785640Y1328370D03*
X784000Y1443000D03*
X796848Y1469724D03*
X829921Y-458D03*
X825984D03*
X833724Y-3346D03*
X833671Y254D03*
X806299Y-458D03*
X802362D03*
X814173D03*
X810236D03*
X822047D03*
X818110D03*
X845661Y-3642D03*
X843463Y530D03*
X802102Y51075D03*
X799102Y48575D03*
X802102Y46075D03*
X799102Y43575D03*
X802102Y41075D03*
X845961Y61762D03*
Y56762D03*
Y52762D03*
X838521Y41568D03*
X838043Y37217D03*
X806314Y35952D03*
X802350Y35923D03*
X842470Y41295D03*
X841733Y36654D03*
X818300Y39845D03*
X814300D03*
Y43845D03*
X818300D03*
X846000Y116500D03*
X810301Y78654D03*
X805301D03*
X802801Y75654D03*
X807801D03*
X812801D03*
X811500Y372000D03*
X800000Y400000D03*
X811500Y469500D03*
X846400Y469300D03*
Y473900D03*
X839000Y541000D03*
X839500Y508500D03*
Y560000D03*
X800867Y619400D03*
X803367Y622400D03*
X809015Y661000D03*
X804015D03*
X808920Y652340D03*
Y656460D03*
X806515Y664000D03*
X827500Y922500D03*
X827000Y1168000D03*
X802036Y1164244D03*
X803438Y1139700D03*
X802500Y1194500D03*
X807500D03*
X812500D03*
X810000Y1191500D03*
X805000D03*
X809600Y1236300D03*
X804600D03*
X802100Y1233300D03*
X807100D03*
X812100D03*
X806952Y1460496D03*
X806568Y1464275D03*
X802433Y1461619D03*
X800900Y1465234D03*
X800462Y1469231D03*
X839414Y1520763D03*
X834813Y1528889D03*
X834974Y1533243D03*
X882000Y-105500D03*
X885046Y20384D03*
X886322Y69D03*
X867080Y393D03*
X886427Y3802D03*
X873892Y287D03*
X886418Y-7350D03*
X849484Y649D03*
X886351Y-3735D03*
X857513Y659D03*
X861101Y66680D03*
X862099Y61626D03*
Y56626D03*
X861961Y52762D03*
X852769Y66957D03*
X848769D03*
X856769D03*
X853961Y52762D03*
X849961D03*
X857961D03*
X874244Y37026D03*
Y44935D03*
X885448Y37380D03*
X877265Y52540D03*
X881265D03*
X885265D03*
X873265D03*
X869265D03*
X869459Y56626D03*
Y61626D03*
X869044Y66985D03*
X873044D03*
X877139Y66926D03*
X885265Y60540D03*
Y56540D03*
X881750Y37397D03*
X858496Y37121D03*
X854180Y36996D03*
X852995Y40965D03*
X856995D03*
X852769Y74957D03*
X856769D03*
X861142Y71026D03*
X852810Y71303D03*
X856810D03*
X853900Y89701D03*
X886073Y78824D03*
X885464Y83201D03*
X878549Y78905D03*
Y82905D03*
X869044Y70985D03*
X873044D03*
X882549Y76905D03*
Y80905D03*
X888500Y260500D03*
X872796Y251714D03*
X850500Y266000D03*
X866000Y315000D03*
X881549Y326304D03*
X890982Y349498D03*
X874800Y355798D03*
X856500Y373000D03*
X858632Y399200D03*
X855032D03*
Y395600D03*
X858632D03*
X855032Y392000D03*
X858632D03*
X852832Y406400D03*
Y402800D03*
X856432Y406400D03*
Y402800D03*
X887100Y359100D03*
X887500Y378495D03*
X875132Y399200D03*
X878732D03*
Y395600D03*
X875132D03*
X878732Y392000D03*
X875132D03*
X880932Y406400D03*
Y402800D03*
X877332Y406400D03*
Y402800D03*
X874807Y375193D03*
X852832Y410000D03*
X856432D03*
X866276Y454900D03*
X866317Y446725D03*
X880932Y410000D03*
X877332D03*
X857300Y454300D03*
X862000Y453600D03*
X852000Y454200D03*
X866321Y451300D03*
X855500Y499500D03*
X871487Y463589D03*
X878500Y476000D03*
X878193Y467707D03*
X866278Y459562D03*
X870600Y476900D03*
X851800Y477200D03*
X860092Y542405D03*
X867500Y643000D03*
X877000Y664500D03*
X868500Y665000D03*
X868100Y685600D03*
X871700D03*
X875300D03*
X884600Y688800D03*
X881000D03*
X877400D03*
X891000Y743500D03*
X874715Y707651D03*
X871115D03*
X867515D03*
X884700Y705200D03*
X881100D03*
X877500D03*
X870500Y762500D03*
X885600Y824400D03*
X870163Y836153D03*
X865663Y834403D03*
X867663Y818831D03*
X887600Y811900D03*
X891200Y838200D03*
X878673Y804527D03*
X874569Y811300D03*
X885882Y861618D03*
X894965Y843500D03*
X877673Y868873D03*
X888962Y843262D03*
X873647Y861653D03*
X882333Y896320D03*
X895616Y985932D03*
X863800Y1309876D03*
X885301Y1358557D03*
X884746Y1350438D03*
X873495Y1370213D03*
X885300Y1371050D03*
X872164Y1350464D03*
X873259Y1365805D03*
X872181Y1354764D03*
X886792Y1404100D03*
X873918Y1411149D03*
X873800Y1418200D03*
X871432Y1420932D03*
X874900Y1421900D03*
X877406Y1419124D03*
X875740Y1415070D03*
X882226Y1404197D03*
X873694Y1404575D03*
X873700Y1375746D03*
X873570Y1380401D03*
X877300Y1432400D03*
X886500Y1432500D03*
X872192Y1424492D03*
X882000Y1432600D03*
X870921Y1432300D03*
X893158Y1516542D03*
X893050Y1489500D03*
X868791Y1478782D03*
X888800Y1493500D03*
X876514Y1514948D03*
X863851Y1501681D03*
X877828Y1500379D03*
X892966Y1508549D03*
X893036Y1512600D03*
X877946Y1496527D03*
X876096Y1505499D03*
X889002Y1489638D03*
X873972Y1472467D03*
X873922Y1477766D03*
X860179Y1491170D03*
X892682Y1520718D03*
X855092Y1535821D03*
X866621Y1544206D03*
X893020Y1566530D03*
X876200Y1553900D03*
X892700Y1543900D03*
X892558Y1528458D03*
X889300Y1551000D03*
X876190Y1537187D03*
X876100Y1549000D03*
X876200Y1558400D03*
X892700Y1524700D03*
X848551Y1542440D03*
X910500Y-137500D03*
X928600Y-115200D03*
X902000Y-58000D03*
X922687Y93D03*
X928138Y-8453D03*
X909000Y89000D03*
X898000Y133000D03*
X911000Y305500D03*
X898000Y268000D03*
X942000Y752850D03*
X897000Y839000D03*
X915000Y879000D03*
X903000Y842500D03*
X926185Y928342D03*
X924974Y933041D03*
X895869Y932822D03*
X914876Y901029D03*
X937621Y915324D03*
X920810Y902210D03*
X928100Y900650D03*
X900615Y909723D03*
X902571Y906534D03*
X903368Y934568D03*
X904594Y931141D03*
X916204Y938572D03*
X917550Y934742D03*
X901540Y937712D03*
X896679Y927505D03*
X896420Y916712D03*
X898468Y912970D03*
X931085Y936172D03*
X941274Y900845D03*
X924563Y962945D03*
X919759Y970868D03*
X938009Y987330D03*
X941868Y952101D03*
X934142Y974344D03*
X939481Y980230D03*
X912994Y971921D03*
X910397Y979189D03*
X902991Y982230D03*
X909826Y982874D03*
X905271Y974586D03*
X899846Y971468D03*
X898617Y975434D03*
X895837Y978389D03*
X896629Y982285D03*
X935623Y971054D03*
X898920Y1020000D03*
X916446Y1035438D03*
X941640Y995820D03*
X904601Y998556D03*
X910040Y1006613D03*
X911807Y1002342D03*
X919656Y998764D03*
X939544Y1003485D03*
X903442Y1003265D03*
X896371Y1002112D03*
X936378Y1035722D03*
X929257Y1035883D03*
X920770Y1067389D03*
X921149Y1062424D03*
X914948Y1063255D03*
X908477Y1061823D03*
X910387Y1055344D03*
X904875Y1051177D03*
X906000Y1222000D03*
X924500Y1236000D03*
X942925Y1369010D03*
X928384Y1346435D03*
X932559Y1360137D03*
X928439Y1360167D03*
X932564Y1346100D03*
X896500Y1341800D03*
X936959Y1360143D03*
X896212Y1345788D03*
X932294Y1379995D03*
X928194D03*
X895900Y1390100D03*
X896200Y1386000D03*
X896100Y1393800D03*
X896200Y1397900D03*
Y1405300D03*
X896100Y1401600D03*
X923829Y1389012D03*
X936994Y1379895D03*
X927601Y1384433D03*
X923486Y1384268D03*
X904941Y1456941D03*
X906600Y1461600D03*
X909400Y1459200D03*
X910000Y1464900D03*
X905500Y1467161D03*
X932500Y1493200D03*
X926500Y1499700D03*
X918500D03*
X938000Y1499200D03*
X942000Y1499500D03*
X922500Y1499700D03*
X908742Y1477427D03*
X908542Y1481127D03*
X922500Y1509700D03*
X906000Y1543700D03*
X918505Y1530405D03*
X918800Y1534500D03*
X941000Y1564200D03*
X937000D03*
X926500Y1556700D03*
X931500Y1564200D03*
X913250Y1547700D03*
X940000Y1529200D03*
X940750Y1549200D03*
X900000Y1526500D03*
X897400Y1574000D03*
X897038Y1577600D03*
X911516Y1573202D03*
X911616Y1576802D03*
X911710Y1582375D03*
X911094Y1585923D03*
X924059Y1647700D03*
X986713Y-115570D03*
X971713D03*
X981700Y-115500D03*
X976713Y-115570D03*
X991713Y-115413D03*
X989316Y-94984D03*
X992185Y-54411D03*
X989050Y-70850D03*
X975500Y11500D03*
X990565Y130230D03*
Y135230D03*
Y125230D03*
X974000Y402000D03*
X985688Y362549D03*
X974000Y523000D03*
X985500Y613500D03*
X978000Y677000D03*
X977794Y695103D03*
X952200Y742600D03*
X957100Y742900D03*
X977622Y699464D03*
X953200Y736700D03*
X956900Y737600D03*
X949048Y755225D03*
X952476Y753652D03*
X951300Y747900D03*
X956200Y748200D03*
X957320Y769818D03*
X947866Y763541D03*
X957629Y766231D03*
X952820Y769518D03*
X944500Y760750D03*
X962900Y905000D03*
X981580Y932678D03*
X953967Y933635D03*
X961100Y931640D03*
X960503Y936185D03*
X967583Y933607D03*
X968698Y928957D03*
X974484Y935078D03*
X976419Y931628D03*
X976460Y927891D03*
X981679Y936678D03*
X976213Y938846D03*
X966000Y937500D03*
X976580Y986180D03*
X948942Y974655D03*
X961134Y976191D03*
X959400Y960300D03*
X953013Y960147D03*
X947174Y957150D03*
X979020Y960000D03*
Y956200D03*
X973900Y960000D03*
Y956200D03*
X968780Y960000D03*
Y956200D03*
X987734Y979575D03*
X946138Y1006299D03*
X987970Y1004157D03*
X955700Y1030700D03*
X951200D03*
X946700D03*
X947759Y998726D03*
X961220Y1001600D03*
Y1005400D03*
X966340Y1001600D03*
Y1005400D03*
X971460Y1001600D03*
Y1005400D03*
X974020Y1026200D03*
Y1022400D03*
X968900Y1026200D03*
Y1022400D03*
X963780Y1026200D03*
Y1022400D03*
X956600Y1001700D03*
Y1005700D03*
X977400Y1157900D03*
X964537Y1160310D03*
X958870Y1163617D03*
X962941Y1165929D03*
X967497Y1168802D03*
X957871Y1171219D03*
X963000Y1174427D03*
X969463Y1177599D03*
X972924Y1158033D03*
X954395Y1145604D03*
X977500Y1182300D03*
X982387Y1183598D03*
X962500Y1298500D03*
X947125Y1369010D03*
X951525Y1369107D03*
X955500Y1369000D03*
X944921Y1515200D03*
X988624Y1502923D03*
X951815Y1491459D03*
X946300Y1499300D03*
X969198Y1505851D03*
X969472Y1501978D03*
X950300Y1499500D03*
X975813Y1556916D03*
X953500Y1563200D03*
X962000Y1564200D03*
X958000D03*
X949000D03*
X945000D03*
X972001Y1533926D03*
X975813Y1545916D03*
X954700Y1524100D03*
Y1530363D03*
X974787Y1525100D03*
Y1529300D03*
X948750Y1549200D03*
X979963Y1545689D03*
X1034916Y-82413D03*
Y-87913D03*
X1011984Y-83066D03*
X1012174Y-88726D03*
X1004213Y-95837D03*
X998045Y-79300D03*
X993816Y-95184D03*
X1036713Y-115500D03*
X1015582Y-69800D03*
X1014800Y-62100D03*
X999300Y-64400D03*
X1009100Y-48600D03*
X1035000Y-66800D03*
X1022618Y-36900D03*
X1023300Y-44200D03*
X1032053Y-34953D03*
X1038712Y-34812D03*
X1007582Y-39418D03*
X1000300Y-74200D03*
X1032080Y-45980D03*
X1004082Y-38200D03*
X1000418Y-69982D03*
X993000Y-60600D03*
X1019118Y-34382D03*
X1019082Y-71000D03*
X1026717Y-11646D03*
X1021086Y-11682D03*
X1017600Y63600D03*
Y58900D03*
Y54200D03*
X1010650Y49950D03*
Y67650D03*
X993000Y108000D03*
X1036003Y93543D03*
X1038503Y97543D03*
X1033503D03*
Y102543D03*
Y107543D03*
Y112543D03*
X993000Y157000D03*
X1030775Y130016D03*
X1030890Y137780D03*
X993565Y137730D03*
Y132730D03*
Y127730D03*
X1030774Y133840D03*
X1030758Y126274D03*
X1030825Y122335D03*
X993000Y329000D03*
X1020250Y357188D03*
X998000Y378000D03*
X995000Y455000D03*
X1040180Y437510D03*
X995000Y488000D03*
X1018322Y545207D03*
X1018300Y550000D03*
X993000Y635000D03*
X1025000Y817000D03*
X1028472Y834829D03*
X1027063Y850703D03*
X1031563Y852453D03*
X1038215Y877191D03*
X1034271Y876911D03*
X1011100Y904600D03*
X1025000Y897700D03*
X1036431Y929752D03*
X1037083Y933300D03*
X1016842Y916445D03*
X1014891Y943357D03*
X1013713Y974651D03*
X997694Y974940D03*
X1035947Y948800D03*
X1025774Y1001538D03*
X992994Y1005740D03*
X1012494Y1033840D03*
X1028657Y1009103D03*
X1020654Y1023940D03*
X1018094Y1021240D03*
X1015534Y1023840D03*
X1007849Y1033743D03*
X996600D03*
X1012974Y1021240D03*
X1013700Y1007640D03*
X1009509Y1009850D03*
X1037282Y995028D03*
X1005294Y997940D03*
Y1001740D03*
X1010414Y997940D03*
Y1001740D03*
X1023214Y1007140D03*
X1007372Y1023832D03*
X1017194Y1033840D03*
X1018000Y1076500D03*
X1037000Y1067100D03*
X1032500D03*
X1017000Y1093950D03*
X1021200Y1094300D03*
X1031400Y1124700D03*
X1026900Y1129466D03*
X1022400Y1129183D03*
X1036160Y1095500D03*
Y1091700D03*
Y1111900D03*
X1019000Y1178000D03*
X1013400Y1137500D03*
X1021991Y1141526D03*
X1004294Y1137600D03*
X994923Y1137488D03*
X997500Y1192500D03*
X1006800Y1191200D03*
X995948Y1184250D03*
X1017354Y1196124D03*
X1021061Y1198543D03*
X1032500Y1248000D03*
X993500Y1317000D03*
X1016835Y1323916D03*
X1025335Y1324216D03*
X1031000Y1350500D03*
X1031474Y1354526D03*
X1016672Y1338228D03*
X1025284Y1341216D03*
X1025335Y1337616D03*
Y1330916D03*
X1016600Y1332000D03*
X1033000Y1416125D03*
X1028000Y1404700D03*
Y1411000D03*
X1031500Y1408000D03*
X1020854Y1455075D03*
X1016854D03*
X1065621Y-85082D03*
X1046713Y-115570D03*
X1076713D03*
X1084200Y-82300D03*
X1074400Y-81000D03*
X1051713Y-114887D03*
X1056713Y-115413D03*
X1086713Y-115570D03*
X1081713D03*
X1071713D03*
X1066713D03*
X1041713Y-115465D03*
X1085300Y-90700D03*
X1070500Y-67900D03*
X1074400Y-39100D03*
X1079600Y-50700D03*
X1087700Y-37886D03*
X1045800Y-75936D03*
X1058333Y-72770D03*
X1061325Y-40378D03*
X1054625Y-40278D03*
X1079455Y-30742D03*
X1043000Y-67600D03*
X1043112Y-34912D03*
X1066600Y-72800D03*
X1066225Y-40278D03*
X1054593Y-51122D03*
X1078900Y-45782D03*
X1085800Y-57100D03*
X1070918Y-73618D03*
X1076000Y-10500D03*
X1043303Y-27685D03*
X1045873Y-24660D03*
X1043513Y-21696D03*
X1077505Y22405D03*
X1076418Y31082D03*
X1076944Y35182D03*
X1077260Y42612D03*
X1077400Y52000D03*
X1077082Y38982D03*
X1076905Y46195D03*
X1076299Y27282D03*
X1054800Y22405D03*
X1078500Y99000D03*
X1043703Y112543D03*
Y107543D03*
Y102543D03*
X1041003Y93543D03*
X1043703Y97543D03*
X1062854Y83434D03*
X1078500Y135500D03*
X1043500Y310500D03*
X1048500Y346000D03*
X1058500Y368500D03*
X1045000Y364000D03*
X1050100Y392600D03*
Y397600D03*
Y402600D03*
X1044600Y392500D03*
Y397500D03*
Y402500D03*
X1041500Y382858D03*
X1078100Y392600D03*
Y397600D03*
Y402600D03*
X1072600Y392500D03*
Y397500D03*
Y402500D03*
X1045292Y384688D03*
X1044600Y407500D03*
X1050100Y407600D03*
X1042833Y434409D03*
X1074425Y447225D03*
X1071950Y453288D03*
X1072600Y407500D03*
X1078100Y407600D03*
X1043674Y451921D03*
X1043500Y446600D03*
X1042800Y442000D03*
X1047000Y492000D03*
X1079000Y477000D03*
X1058000D03*
X1069018Y456900D03*
X1065985Y460500D03*
X1045106Y561249D03*
X1058000Y616000D03*
X1073000Y676000D03*
X1047000Y751000D03*
X1045163Y840400D03*
X1082000Y815500D03*
X1054419Y839493D03*
Y828081D03*
X1050763Y829163D03*
X1086600Y833200D03*
X1054000Y866000D03*
X1075500Y848000D03*
X1044680Y921400D03*
X1053200Y901703D03*
X1043882Y901568D03*
X1044101Y927130D03*
X1083633Y932172D03*
X1073408Y942399D03*
X1058571Y943852D03*
X1072000Y1035000D03*
X1053099Y1021657D03*
X1048512Y1021378D03*
X1041616Y997225D03*
X1052000Y1054000D03*
X1082500Y1067100D03*
X1073500D03*
X1054080Y1077680D03*
X1069000Y1067100D03*
X1064500Y1096150D03*
X1068700Y1096600D03*
X1087700Y1125800D03*
X1083355Y1125903D03*
X1070155D03*
X1048960Y1113900D03*
Y1117700D03*
X1041280Y1121500D03*
Y1113900D03*
Y1117700D03*
X1081078Y1095362D03*
X1083660Y1092700D03*
X1041280Y1095500D03*
Y1091700D03*
Y1100500D03*
X1048960Y1095500D03*
Y1091700D03*
Y1099300D03*
X1054080Y1113900D03*
Y1117700D03*
X1068700Y1108700D03*
X1083355Y1116103D03*
X1070155D03*
X1075600Y1179090D03*
X1053743Y1174221D03*
X1046900Y1168000D03*
X1052522Y1145153D03*
X1076032Y1191144D03*
X1070000Y1184100D03*
X1079500Y1276100D03*
X1047000Y1258687D03*
X1051300Y1253300D03*
X1077300Y1271700D03*
X1042343Y1324216D03*
X1048251Y1349992D03*
X1046372Y1356326D03*
X1042343Y1337616D03*
X1042443Y1342668D03*
X1042343Y1330916D03*
X1076754Y1455075D03*
X1072754D03*
X1044654D03*
X1048654D03*
X1134500Y-103500D03*
X1117535Y-115157D03*
X1115000Y-77500D03*
X1097600Y-82462D03*
X1107700Y-76800D03*
X1100929Y-90371D03*
X1116600Y-85538D03*
X1106300Y-94800D03*
X1089318Y-91682D03*
X1114400Y-55662D03*
X1093900Y-64500D03*
X1113300Y-44100D03*
X1101246Y-31005D03*
X1124024Y-30840D03*
X1128765Y-34297D03*
X1094200Y-38400D03*
X1111254Y-31020D03*
X1105328Y-31005D03*
X1094300Y-60300D03*
X1103300Y-60000D03*
X1115603Y-60293D03*
X1134110Y176500D03*
X1136203Y167600D03*
X1089300Y836100D03*
X1119159Y878130D03*
Y873130D03*
Y868130D03*
X1116159Y870630D03*
Y875630D03*
X1119419Y888607D03*
X1100847Y905617D03*
X1105847D03*
X1110847D03*
X1108347Y902617D03*
X1103347D03*
X1116419Y896107D03*
Y891107D03*
X1119419Y893607D03*
Y898607D03*
X1110447Y944217D03*
X1105447D03*
X1100447D03*
X1102947Y947217D03*
X1107947D03*
X1119700Y1067200D03*
X1124500D03*
X1091400Y1070900D03*
X1091494Y1075994D03*
X1097800Y1070700D03*
X1097500Y1075100D03*
X1103800Y1070600D03*
Y1075600D03*
X1128900Y1067200D03*
X1101580Y1091120D03*
X1107100Y1096050D03*
X1111600Y1097800D03*
X1124100Y1125100D03*
X1119500D03*
X1115000D03*
X1123600Y1096400D03*
X1123838Y1092800D03*
X1123600Y1100000D03*
X1133981Y1096283D03*
X1134002Y1092600D03*
X1134103Y1099881D03*
X1137436Y1124750D03*
X1128800Y1125100D03*
X1092200Y1125800D03*
X1103064Y1113626D03*
X1099020Y1112276D03*
X1096460Y1115125D03*
X1092742Y1113462D03*
X1134100Y1433300D03*
X1090818Y1531620D03*
X1092927Y1558887D03*
Y1555087D03*
X1095938Y1531620D03*
Y1535420D03*
X1090818D03*
X1096547Y1558887D03*
Y1555087D03*
X1139500Y-58500D03*
X1150000Y-63000D03*
X1146768Y-31238D03*
X1139808Y-31171D03*
X1149699Y-35153D03*
X1142293Y-37522D03*
X1181568Y55168D03*
X1181868Y50568D03*
Y45568D03*
X1181568Y60168D03*
X1178268Y64068D03*
X1183268D03*
X1184088Y101360D03*
X1184141Y96794D03*
X1178268Y85068D03*
Y69068D03*
Y89068D03*
X1183268Y85068D03*
Y69068D03*
Y89068D03*
X1178656Y104637D03*
X1176952Y93390D03*
X1177500Y153500D03*
X1140550Y179200D03*
X1142800Y174637D03*
X1140500Y171400D03*
X1182590Y254388D03*
X1171749Y259163D03*
X1175400Y258800D03*
X1174037Y281343D03*
X1176300Y284500D03*
X1180953Y284800D03*
X1185588Y285035D03*
X1185000Y281343D03*
X1176100Y270603D03*
X1176300Y288600D03*
X1173500Y397000D03*
X1156500Y467000D03*
X1166500Y635000D03*
X1156500Y619000D03*
X1176835Y618934D03*
X1156500Y650000D03*
X1169768Y730300D03*
Y723100D03*
Y726700D03*
X1175568Y712300D03*
X1171968D03*
X1175568Y715900D03*
X1171968D03*
X1173368Y730300D03*
X1171968Y719500D03*
X1175568D03*
X1173368Y726700D03*
Y723100D03*
X1181000Y814000D03*
X1156500Y813000D03*
X1179000Y829500D03*
X1166500D03*
X1138198Y832424D03*
X1158500Y868500D03*
X1172736Y1031786D03*
X1177036Y1032086D03*
X1144580Y1078680D03*
X1170140Y1043939D03*
X1172564Y1118373D03*
X1152880Y1097672D03*
X1152682Y1091138D03*
X1149984Y1115804D03*
X1143550Y1120317D03*
X1139524Y1121817D03*
X1152800Y1223062D03*
X1152700Y1216213D03*
X1150420Y1229800D03*
X1181400Y1266100D03*
X1184000Y1260100D03*
X1149823Y1233373D03*
X1144000Y1310000D03*
X1150232Y1316358D03*
X1154500Y1327500D03*
X1150911Y1329500D03*
X1147900Y1421500D03*
X1143900Y1431000D03*
X1142400Y1427700D03*
X1146002Y1427906D03*
X1145007Y1424446D03*
X1148556Y1425056D03*
X1153000Y1496000D03*
X1163000Y1612000D03*
X1141000Y1632000D03*
X1228500Y12500D03*
X1204768Y64368D03*
X1199768D03*
X1209768D03*
X1204068Y50368D03*
Y45368D03*
X1203768Y60568D03*
Y55568D03*
X1188268Y64068D03*
X1224000Y104000D03*
X1199768Y69368D03*
X1204768D03*
X1209768D03*
X1204768Y85368D03*
X1199768D03*
X1209768D03*
Y89368D03*
X1199768D03*
X1204768D03*
X1188268Y85068D03*
Y69068D03*
Y89068D03*
X1215795Y181242D03*
X1186500Y220500D03*
X1224800Y225200D03*
X1219917Y239646D03*
X1215600Y261800D03*
X1219962Y244739D03*
X1186600Y253200D03*
X1215547Y246355D03*
X1194700Y261700D03*
X1189700Y308527D03*
X1190200Y285023D03*
X1201835Y305319D03*
X1193800Y307857D03*
X1198100Y306858D03*
X1194600Y288237D03*
X1197000Y279400D03*
X1226045Y431102D03*
X1232500Y541000D03*
X1197868Y730300D03*
X1194268D03*
Y723100D03*
Y726700D03*
X1197868Y723100D03*
Y726700D03*
X1192068Y712300D03*
X1195668D03*
X1192068Y715900D03*
X1195668D03*
Y719500D03*
X1192068D03*
X1188000Y753000D03*
X1192000Y869000D03*
X1232700Y950400D03*
X1194000Y1037900D03*
X1229691Y1148580D03*
X1232842Y1140722D03*
X1198130Y1151410D03*
X1205303Y1227604D03*
X1214500Y1320500D03*
X1220500Y1311000D03*
X1194000Y1499000D03*
X1240500Y20000D03*
X1254000Y105000D03*
X1281500Y103500D03*
X1278421Y205974D03*
X1281603Y203340D03*
X1282106Y180492D03*
X1280800Y167200D03*
X1282287Y243489D03*
X1277606Y217441D03*
X1282106Y235492D03*
X1248193Y242618D03*
X1255600Y237300D03*
X1250016Y247017D03*
X1253300Y227700D03*
X1273200Y263700D03*
X1276200Y277400D03*
X1262075Y297100D03*
X1250500Y266600D03*
X1280000Y430000D03*
X1235796Y517450D03*
X1250011Y516707D03*
X1239362Y524168D03*
X1253511Y517606D03*
X1264878Y508068D03*
X1282106Y648248D03*
Y633248D03*
Y618248D03*
X1253800Y689600D03*
X1277606Y670197D03*
X1282106Y688248D03*
X1277606Y660748D03*
Y651299D03*
X1282106Y728248D03*
Y718248D03*
Y698248D03*
X1268400Y716100D03*
X1265891Y699583D03*
X1263250Y823436D03*
X1243200Y933700D03*
X1259808Y927260D03*
X1250475Y969248D03*
X1271296Y986867D03*
X1274413Y984613D03*
X1279599Y976407D03*
X1253338Y980784D03*
X1253975Y970147D03*
X1264269Y981248D03*
X1263618Y990606D03*
X1268378Y990608D03*
X1239900Y1024000D03*
X1256142Y1029316D03*
X1279081Y1071085D03*
X1252400Y1054100D03*
X1277606Y1122953D03*
Y1113504D03*
Y1104055D03*
X1282106Y1101004D03*
Y1086004D03*
X1251250Y1141700D03*
X1282106Y1171004D03*
Y1151004D03*
Y1141004D03*
X1246557Y1148155D03*
X1249600Y1155800D03*
X1272755Y1137293D03*
X1260300Y1169000D03*
X1240314Y1139741D03*
X1268948Y1150173D03*
X1282106Y1181004D03*
X1254800Y1269600D03*
X1257000Y1300000D03*
X1263500Y1318500D03*
X1240276Y1356700D03*
X1319000Y12000D03*
X1309000Y45500D03*
X1318500Y34500D03*
X1323829Y55929D03*
X1328295Y55800D03*
X1320055Y68000D03*
X1319100Y78800D03*
X1323521Y79179D03*
X1312999Y107280D03*
X1317661Y107896D03*
X1299569Y84272D03*
X1304563Y84309D03*
Y100771D03*
X1299569Y100639D03*
X1312263Y95463D03*
X1327921Y78900D03*
X1308228Y93399D03*
X1315961Y98112D03*
X1289000Y145400D03*
X1314794Y162944D03*
X1324134Y126967D03*
X1313127Y120839D03*
X1315118Y126967D03*
X1324207Y138756D03*
X1315102Y137903D03*
X1302074Y183779D03*
X1311200Y172661D03*
X1304293Y165909D03*
X1315838Y188804D03*
X1297507Y195492D03*
X1330807Y181473D03*
X1311750Y187911D03*
X1326637Y226568D03*
X1316637D03*
X1321637D03*
X1298700Y272800D03*
X1298500Y302900D03*
X1305000Y299400D03*
X1313000Y302900D03*
X1313915Y263541D03*
X1289000Y309500D03*
X1311000Y321000D03*
X1303500Y434000D03*
X1287000Y456000D03*
X1310000Y597000D03*
X1289106Y594626D03*
X1303800Y636417D03*
X1311200Y625417D03*
X1307500Y615417D03*
X1315400Y648017D03*
X1326500Y627917D03*
X1311750Y640667D03*
X1312000Y615417D03*
X1318000Y680417D03*
X1323000D03*
X1328000D03*
X1302500Y718917D03*
X1314000Y717417D03*
X1298500Y752417D03*
X1305000D03*
X1313000D03*
X1289106Y766870D03*
X1316000Y772200D03*
X1310500Y774700D03*
X1312767Y885535D03*
X1286000Y982200D03*
X1284695Y956586D03*
X1305000Y1041500D03*
X1289114Y1048624D03*
X1311200Y1078173D03*
X1305100Y1068173D03*
X1326500Y1080673D03*
X1317400Y1068000D03*
X1309600Y1068173D03*
X1303800Y1089173D03*
X1315300Y1100773D03*
X1311750Y1093423D03*
X1302500Y1171673D03*
X1313950Y1165990D03*
X1328000Y1133173D03*
X1318000D03*
X1323000D03*
X1300065Y1206008D03*
X1305000Y1205173D03*
X1313000D03*
X1289106Y1219626D03*
X1357500Y43500D03*
X1347500Y21000D03*
X1332500Y56500D03*
X1351200Y68600D03*
X1359350Y66350D03*
X1351201Y90099D03*
X1358355Y81488D03*
X1338215Y107586D03*
X1336034Y82542D03*
X1334383Y75892D03*
X1340961Y78811D03*
X1343521Y85472D03*
X1347607Y101337D03*
X1346081Y80671D03*
X1348641Y83326D03*
X1352351Y101724D03*
X1350779Y106496D03*
X1348641Y110550D03*
X1333281Y85133D03*
X1341922Y105649D03*
X1354500Y75400D03*
X1332934Y137712D03*
X1349931Y138361D03*
X1338400Y126015D03*
X1333988Y161471D03*
X1358971Y129978D03*
X1362685Y130109D03*
X1351665Y128325D03*
X1343112Y128997D03*
X1364017Y123277D03*
X1337662Y137188D03*
X1334500Y202548D03*
Y207548D03*
Y212548D03*
X1377463Y237100D03*
X1334500Y217548D03*
X1372274Y272874D03*
X1355991Y275272D03*
X1374338Y292900D03*
X1358573Y290900D03*
X1372000Y335000D03*
X1375700Y413400D03*
X1338000Y546500D03*
X1346363Y516578D03*
X1332148Y517321D03*
X1357316Y542311D03*
X1346057Y529857D03*
X1338100Y520300D03*
X1353500Y518900D03*
X1359882Y508014D03*
X1364882D03*
X1337500Y576500D03*
X1355700Y587600D03*
X1359700D03*
X1372272Y573560D03*
X1336000Y627000D03*
X1375463Y689917D03*
X1334000Y666417D03*
Y661917D03*
Y657417D03*
Y652917D03*
X1373553Y700994D03*
X1347600Y734078D03*
X1344062Y737800D03*
X1339500Y794000D03*
X1354500Y747304D03*
X1360920Y749829D03*
X1334300Y771200D03*
X1338729Y776131D03*
X1338700Y771500D03*
X1334329Y775831D03*
X1373519Y761900D03*
X1341219Y933282D03*
X1346080Y907004D03*
X1344000Y987500D03*
X1362000Y987000D03*
X1331070Y966090D03*
X1348796Y969488D03*
X1378100Y972100D03*
X1339404Y969600D03*
X1353762Y969886D03*
X1367382Y961355D03*
X1362382D03*
X1349829Y1014840D03*
X1365551Y1028250D03*
X1368935Y1123365D03*
X1361074Y1114565D03*
X1334500Y1104700D03*
Y1111173D03*
Y1116173D03*
Y1121173D03*
X1365461Y1136100D03*
X1375463Y1142673D03*
X1364713Y1143791D03*
X1360238Y1143867D03*
X1370716Y1148037D03*
X1351321Y1152553D03*
X1355733Y1241900D03*
X1369600Y1330100D03*
X1373700Y1330000D03*
X1365551Y1353500D03*
X1413268Y146062D03*
X1401819Y207992D03*
X1394705Y195413D03*
X1406319Y180492D03*
X1405100Y166000D03*
X1427663Y167032D03*
X1403963Y245492D03*
X1385051Y218684D03*
X1406000Y236700D03*
X1384475Y255839D03*
X1426713Y266161D03*
X1426400Y307400D03*
X1406319Y275492D03*
Y265492D03*
X1398493Y314114D03*
X1384713Y323200D03*
X1400000Y406000D03*
X1427000Y380000D03*
X1414882Y397271D03*
X1395300Y438500D03*
X1418225Y421700D03*
X1425000Y480000D03*
X1405000D03*
Y460000D03*
X1385000Y480000D03*
X1396500Y511000D03*
X1383500Y509500D03*
X1418493Y531407D03*
X1425600Y544600D03*
X1418507Y517007D03*
X1407936Y552099D03*
Y548099D03*
X1425200Y540100D03*
X1414319Y523900D03*
X1413319Y594626D03*
X1413400Y575000D03*
X1396297Y573397D03*
X1421239Y558029D03*
X1396297Y579803D03*
X1421239Y562229D03*
X1406319Y648248D03*
Y633248D03*
Y618248D03*
X1421500Y664000D03*
X1401819Y670197D03*
X1406319Y688248D03*
X1401819Y660748D03*
Y651299D03*
X1426713Y718917D03*
X1406319Y728248D03*
Y718248D03*
Y698248D03*
X1383952Y717435D03*
X1422713Y752417D03*
X1398245Y766870D03*
X1395000Y791500D03*
X1392355Y886696D03*
X1391000Y932400D03*
X1380300Y930200D03*
X1390000Y955500D03*
X1384800Y1002666D03*
X1390500Y1048000D03*
X1406319Y1071004D03*
X1413319Y1047382D03*
X1406319Y1086004D03*
Y1101004D03*
X1401819Y1104055D03*
X1385494Y1113504D03*
X1401819Y1122953D03*
X1406319Y1141004D03*
Y1151004D03*
Y1171004D03*
X1426713Y1171673D03*
X1383899Y1166690D03*
X1406319Y1181004D03*
X1413319Y1219626D03*
X1422713Y1205173D03*
X1388500Y1224900D03*
X1413000Y1241500D03*
X1387000Y1243500D03*
X1386500Y1258000D03*
X1418000Y1291500D03*
X1400000Y1320000D03*
X1420000D03*
X1381800Y1329600D03*
X1431713Y162661D03*
X1463804Y138605D03*
X1436204Y159247D03*
X1428013Y185956D03*
X1445994Y174086D03*
X1440300Y188000D03*
X1435963Y183833D03*
X1450713Y173049D03*
X1456373Y168971D03*
X1458764Y212625D03*
Y208025D03*
Y203425D03*
X1438186Y261287D03*
X1442213Y227661D03*
X1447213D03*
X1452213D03*
X1458764Y217225D03*
X1463000Y307000D03*
X1439300Y301500D03*
X1429800Y302500D03*
X1447170Y337890D03*
X1466500Y338100D03*
X1444238Y349852D03*
X1439654D03*
X1441770Y365790D03*
X1461100Y366000D03*
X1441970Y403990D03*
X1461300Y404200D03*
X1431909Y359311D03*
X1439500Y421500D03*
X1440000Y460000D03*
X1449576Y495482D03*
X1468605Y493549D03*
X1463000Y490638D03*
X1457200Y549600D03*
X1470700Y522100D03*
X1456439Y515000D03*
X1448261D03*
X1435200D03*
X1443700D03*
X1460200D03*
X1452200D03*
X1465700D03*
X1439200D03*
X1442500Y548400D03*
X1456450Y529600D03*
X1448450D03*
X1452279Y563600D03*
X1464700Y585600D03*
X1470000Y580000D03*
X1460274Y592498D03*
X1459200Y579600D03*
X1452200D03*
X1442500Y554700D03*
X1455750Y572350D03*
X1474700Y569100D03*
X1447700Y579600D03*
X1474700Y579100D03*
X1428013Y636417D03*
X1435413Y625417D03*
X1431713Y615417D03*
X1439713Y647917D03*
X1450713Y627817D03*
X1435963Y640667D03*
X1455202Y618557D03*
X1436213Y615417D03*
X1442213Y680417D03*
X1447213D03*
X1452213D03*
X1458713Y658417D03*
Y663417D03*
Y668417D03*
Y652217D03*
X1449000Y698000D03*
X1438087Y713756D03*
X1429213Y752417D03*
X1437213D03*
X1474083Y764750D03*
X1471608Y768500D03*
X1432000Y831000D03*
X1459500Y814000D03*
X1450500Y802500D03*
X1459500Y796500D03*
X1473000Y798000D03*
X1433500Y864500D03*
X1435300Y882700D03*
X1440500Y893500D03*
X1448000Y910000D03*
X1457500Y987500D03*
X1440000Y986500D03*
X1473008Y969646D03*
X1458967Y969535D03*
X1463616Y969265D03*
X1451800Y1004700D03*
X1433500Y1044000D03*
X1456000D03*
X1435413Y1078173D03*
X1431713Y1068173D03*
X1450713Y1080673D03*
X1446213Y1062300D03*
X1436213Y1068173D03*
X1428013Y1089173D03*
X1439713Y1100773D03*
X1442213Y1132173D03*
X1447213D03*
X1452213D03*
X1439750Y1096673D03*
X1461713Y1123173D03*
Y1118173D03*
Y1113173D03*
X1461700Y1107200D03*
X1438213Y1170173D03*
X1470953Y1152427D03*
X1475953D03*
X1429213Y1205173D03*
X1437213D03*
X1467000Y1221800D03*
X1458000Y1265500D03*
X1473600Y1242777D03*
X1460000Y1300000D03*
Y1320000D03*
X1440000D03*
X1511177Y125412D03*
X1498900Y235800D03*
X1499775Y248061D03*
X1508925Y323200D03*
X1505000Y378500D03*
X1520000Y421500D03*
X1481938Y489926D03*
X1479212Y535612D03*
X1494100Y526400D03*
X1507900Y539100D03*
X1481938Y512568D03*
X1485932Y522335D03*
X1500600Y523300D03*
X1502400Y544100D03*
X1497849Y545264D03*
X1486594Y508098D03*
X1491594D03*
X1513200Y519700D03*
X1509800Y516100D03*
X1509911Y553511D03*
X1478700Y579100D03*
X1502400Y554100D03*
X1494400Y560400D03*
Y556100D03*
X1494462Y692179D03*
X1500539Y739639D03*
X1498000Y743000D03*
X1505900Y717600D03*
X1495480Y704558D03*
X1489000Y723000D03*
X1515000Y789000D03*
X1520000Y776000D03*
X1499500Y774000D03*
X1476558Y759088D03*
X1479033Y762259D03*
X1486600Y786559D03*
X1499500Y831000D03*
X1510500Y878000D03*
X1510000Y860500D03*
X1505900Y930400D03*
X1521200Y928000D03*
X1512500Y949000D03*
X1503394Y968179D03*
X1477974Y970044D03*
X1491594Y961355D03*
X1486594D03*
X1508500Y1028500D03*
X1484000Y992315D03*
X1481500Y995758D03*
X1478194Y1017166D03*
X1481529Y1030500D03*
X1508500Y1050500D03*
X1488500Y1096000D03*
X1489096Y1131456D03*
X1489108Y1121674D03*
X1485608Y1113628D03*
X1499675Y1142673D03*
X1489333Y1147664D03*
X1504200Y1171300D03*
X1485833Y1140369D03*
X1495900Y1149000D03*
X1480000Y1320000D03*
X1491662Y1351300D03*
X1494662Y1336000D03*
X1497200Y1342500D03*
X1501600Y1342300D03*
X1525336Y149369D03*
X1555925Y162661D03*
X1545383Y164116D03*
X1560000Y140000D03*
X1560425Y162661D03*
X1552225Y183661D03*
X1559625Y172661D03*
X1563925Y195261D03*
X1526031Y207992D03*
Y198543D03*
X1530531Y195492D03*
Y180492D03*
X1560175Y187911D03*
X1530531Y245492D03*
X1526031Y217441D03*
X1530142Y238021D03*
X1566425Y227661D03*
X1571425D03*
X1550925Y266161D03*
X1546925Y299661D03*
X1553425D03*
X1561425D03*
X1562425Y264661D03*
X1530531Y275492D03*
Y265492D03*
X1537531Y314114D03*
X1545000Y455000D03*
X1560000D03*
X1525000D03*
X1568500Y438500D03*
X1545000Y475000D03*
X1560000D03*
Y500000D03*
Y525000D03*
X1568500Y544100D03*
X1568000Y548500D03*
X1552000Y584500D03*
X1566000Y595000D03*
X1537531Y594626D03*
X1552225Y636417D03*
X1559625Y625417D03*
X1555925Y615417D03*
X1530531Y648248D03*
Y633248D03*
Y618248D03*
X1555175Y642667D03*
X1560425Y615417D03*
X1558925Y650017D03*
X1526031Y670197D03*
X1530531Y688248D03*
X1526031Y660748D03*
Y651299D03*
X1566425Y677417D03*
X1571425D03*
X1565593Y654856D03*
X1565618Y660773D03*
Y665773D03*
Y670773D03*
X1550925Y718917D03*
X1562425Y717417D03*
X1530531Y728248D03*
Y718248D03*
Y698248D03*
X1526000Y728000D03*
X1555000Y770000D03*
X1546925Y752417D03*
X1553425D03*
X1561425D03*
X1537531Y766870D03*
X1525000Y878000D03*
X1570500Y888400D03*
X1564500Y931000D03*
X1548500Y933000D03*
X1564000Y949000D03*
X1552500Y1028000D03*
X1557500Y1043500D03*
X1537531Y1047382D03*
X1559625Y1078173D03*
X1555925Y1068173D03*
X1530531Y1071004D03*
X1570425Y1062000D03*
X1560425Y1068173D03*
X1552225Y1089173D03*
X1526031Y1122953D03*
Y1113504D03*
Y1104055D03*
X1530531Y1101004D03*
Y1086004D03*
X1547800Y1098819D03*
X1552800D03*
X1557800D03*
X1562800D03*
X1550925Y1171673D03*
X1552575Y1139700D03*
X1562425Y1170173D03*
X1530531Y1171004D03*
Y1151004D03*
X1528723Y1138918D03*
X1556231Y1134920D03*
X1546898Y1204827D03*
X1553425Y1208897D03*
X1561425Y1205173D03*
X1537879Y1219626D03*
X1530531Y1181004D03*
X1558650Y1217426D03*
X1600000Y20000D03*
X1620000D03*
X1580000D03*
X1600000Y60000D03*
X1620000Y40000D03*
X1600000D03*
X1580000D03*
Y60000D03*
X1620000Y100000D03*
X1600000Y80000D03*
X1620000D03*
X1580000D03*
X1620000Y140000D03*
Y120000D03*
X1585757Y134147D03*
X1607000Y199000D03*
X1574925Y175061D03*
X1579371Y166019D03*
X1582925Y210661D03*
Y205661D03*
Y200661D03*
X1595500Y258500D03*
X1621100Y240561D03*
X1608000Y256000D03*
X1576425Y227661D03*
X1621100Y244661D03*
X1582925Y215661D03*
X1600000Y340000D03*
X1620000D03*
Y320000D03*
X1600000D03*
X1579500Y331000D03*
X1597245Y516662D03*
X1583030Y517405D03*
X1586596Y518723D03*
X1600745Y517561D03*
X1615807Y508600D03*
X1610807D03*
X1573000Y565500D03*
X1574925Y627817D03*
X1578926Y618657D03*
X1576425Y677417D03*
X1620469Y697517D03*
X1580000Y780000D03*
X1576500Y928500D03*
X1584800Y895800D03*
X1587400Y912200D03*
X1608200Y914400D03*
X1618200Y916800D03*
X1597221Y969572D03*
X1583180Y969461D03*
X1574576Y976700D03*
X1615494Y973179D03*
X1587829Y969191D03*
X1602187Y969970D03*
X1615807Y961355D03*
X1610807D03*
X1596000Y990000D03*
X1580381Y1007066D03*
X1602400Y1019366D03*
X1620059Y1032932D03*
X1611500Y1078000D03*
X1593000Y1043500D03*
X1574925Y1080673D03*
X1603425Y1105040D03*
Y1100040D03*
X1598425Y1102440D03*
Y1107440D03*
X1620059Y1128071D03*
X1615909Y1150262D03*
X1593500Y1185500D03*
X1581500Y1240000D03*
X1613400Y1236500D03*
X1600000Y1320000D03*
X1640000Y20000D03*
X1660000D03*
X1640000Y60000D03*
X1660000D03*
Y40000D03*
X1640000D03*
Y100000D03*
X1660000D03*
X1640000Y80000D03*
X1660000D03*
Y120000D03*
X1640000D03*
X1661744Y141870D03*
X1650244Y207992D03*
Y198543D03*
X1654744Y195492D03*
Y180492D03*
Y165492D03*
Y245492D03*
X1650244Y217441D03*
X1654744Y235492D03*
X1652387Y277343D03*
X1653789Y267766D03*
X1622738Y264938D03*
X1639000Y320000D03*
X1640000Y340000D03*
X1660000D03*
X1661744Y314114D03*
X1660000Y400000D03*
X1640000Y360000D03*
X1660000Y440000D03*
Y480000D03*
X1640000D03*
Y460000D03*
X1660000D03*
X1640000Y500000D03*
X1660000D03*
Y520000D03*
X1640000D03*
X1660000Y540000D03*
X1640000D03*
Y560000D03*
X1660000D03*
X1661744Y594626D03*
X1654744Y648248D03*
Y633248D03*
Y618248D03*
X1623888Y689917D03*
X1652962Y670204D03*
X1654744Y688248D03*
X1650244Y660748D03*
Y651299D03*
X1637000Y729000D03*
X1638000Y740000D03*
X1654744Y728248D03*
Y718248D03*
Y698248D03*
X1621138Y719238D03*
X1630000Y780000D03*
Y760000D03*
X1661744Y766870D03*
X1625000Y800000D03*
X1643344Y887455D03*
X1646013Y884255D03*
X1639644Y889755D03*
X1651500Y913500D03*
X1633600Y936300D03*
X1621787Y917108D03*
X1636400Y925800D03*
X1650000Y950000D03*
Y980000D03*
X1629094Y975179D03*
X1653500Y1016500D03*
X1650000Y1000000D03*
X1632000Y1049500D03*
X1654744Y1071004D03*
X1661744Y1047382D03*
X1650244Y1122953D03*
Y1113504D03*
Y1104055D03*
X1654744Y1101004D03*
Y1086004D03*
X1627563Y1132075D03*
X1627802Y1118949D03*
X1627769Y1110037D03*
X1624198Y1111309D03*
X1635688Y1141158D03*
X1650841Y1168660D03*
X1654744Y1151004D03*
Y1141004D03*
X1627197Y1143044D03*
X1633138Y1165673D03*
X1635688Y1153773D03*
X1661744Y1219626D03*
X1668378Y1181004D03*
X1640000Y1260000D03*
X1660000D03*
X1640000Y1320000D03*
Y1300000D03*
X1660000Y1320000D03*
Y1300000D03*
Y1280000D03*
X1640000D03*
X1624500Y1349100D03*
X1700000Y20000D03*
X1680000D03*
X1700000Y60000D03*
Y40000D03*
X1680000Y60000D03*
Y40000D03*
Y100000D03*
Y80000D03*
X1700000Y100000D03*
Y80000D03*
Y140000D03*
Y120000D03*
X1680000D03*
X1679500Y144000D03*
X1680138Y162661D03*
X1684638D03*
X1676438Y183661D03*
X1683838Y172661D03*
X1688138Y195261D03*
X1684388Y187911D03*
X1699138Y175061D03*
X1703584Y166019D03*
X1707138Y210661D03*
Y205661D03*
Y200661D03*
X1690638Y227661D03*
X1695638D03*
X1700638D03*
X1707138Y215661D03*
X1675475Y267424D03*
X1671138Y299661D03*
X1677638D03*
X1685638D03*
X1686638Y264661D03*
X1678500Y320000D03*
X1700000Y400000D03*
X1680000Y380000D03*
X1700000Y360000D03*
X1680000Y440000D03*
Y420000D03*
X1700000Y440000D03*
Y420000D03*
Y460000D03*
X1680000Y480000D03*
Y460000D03*
Y500000D03*
Y520000D03*
X1700000Y540000D03*
X1680000D03*
X1707495Y517152D03*
X1711061Y518470D03*
X1700000Y560000D03*
X1680000D03*
X1676438Y636417D03*
X1683838Y625417D03*
X1680138Y615417D03*
X1688138Y648017D03*
X1684388Y638324D03*
X1699138Y627917D03*
X1705000Y618667D03*
X1684638Y615417D03*
X1699638Y675417D03*
X1689638D03*
X1694638D03*
X1707100Y652500D03*
X1707138Y658417D03*
Y663417D03*
Y668417D03*
X1675138Y718917D03*
X1686638Y717417D03*
X1710000Y770000D03*
Y785000D03*
X1685000Y770000D03*
X1671138Y752417D03*
X1677638D03*
X1685638D03*
X1709000Y915000D03*
X1687000Y905500D03*
X1692100Y923600D03*
X1704010Y898000D03*
X1716500Y943500D03*
X1674814Y961977D03*
X1677056Y954636D03*
X1680012Y952402D03*
X1706000Y1022000D03*
X1717681Y1006054D03*
X1712181Y1001554D03*
X1685047Y1014966D03*
X1680087Y1023983D03*
X1671422Y1009266D03*
X1690279Y1011526D03*
X1691771Y1035163D03*
X1683838Y1078173D03*
X1680138Y1068173D03*
X1699138Y1080573D03*
X1685100Y1054000D03*
X1679300Y1043169D03*
X1694638Y1063600D03*
X1684638Y1068173D03*
X1688138Y1100773D03*
X1676438Y1089173D03*
X1700638Y1131673D03*
X1695638D03*
X1690638D03*
X1684388Y1091723D03*
X1707138Y1111173D03*
Y1116173D03*
Y1121173D03*
X1707200Y1105200D03*
X1686638Y1170173D03*
X1675138Y1171673D03*
X1685638Y1205173D03*
X1677638D03*
X1671138D03*
X1702838Y1215300D03*
X1680000Y1240000D03*
X1700000Y1260000D03*
X1680000D03*
X1710617Y1231429D03*
X1715049Y1234000D03*
X1700000Y1320000D03*
Y1300000D03*
Y1280000D03*
X1680000Y1320000D03*
Y1300000D03*
Y1280000D03*
X1760000Y20000D03*
X1740000D03*
X1720000D03*
X1760000Y60000D03*
Y40000D03*
X1740000D03*
Y60000D03*
X1720000Y40000D03*
Y60000D03*
X1740000Y100000D03*
X1760000D03*
X1740000Y80000D03*
X1760000D03*
X1720000Y100000D03*
Y80000D03*
X1740000Y140000D03*
X1760000Y120000D03*
X1740000D03*
X1720000Y140000D03*
Y120000D03*
X1728500Y249500D03*
X1746600Y240561D03*
X1760486Y217441D03*
X1746400Y244561D03*
X1763500Y288000D03*
X1720000Y300000D03*
Y280000D03*
X1747550Y265000D03*
X1720000Y340000D03*
X1760000D03*
X1740000Y320000D03*
X1760000Y440000D03*
Y420000D03*
Y500000D03*
Y480000D03*
Y460000D03*
X1740000Y540000D03*
X1760000D03*
Y520000D03*
X1721710Y516409D03*
X1725100Y519300D03*
X1740019Y508600D03*
X1735019D03*
X1745000Y670000D03*
Y690000D03*
Y660000D03*
X1730000Y690000D03*
Y670000D03*
Y730000D03*
Y710000D03*
X1735000Y785000D03*
X1730000Y775000D03*
Y750000D03*
X1725000Y800000D03*
X1718000Y876000D03*
X1752000Y929200D03*
X1759884Y969161D03*
X1757600Y987200D03*
X1761600D03*
Y983200D03*
X1757600D03*
X1742001Y965464D03*
X1755010Y966285D03*
X1740019Y961355D03*
X1735019D03*
X1738863Y985225D03*
X1761600Y991200D03*
Y999200D03*
Y995200D03*
X1757600Y991200D03*
X1753600Y995200D03*
Y999200D03*
X1757600D03*
Y995200D03*
X1726681Y1001554D03*
X1719681D03*
X1722181Y1009054D03*
X1763714Y1015491D03*
X1755900Y1014600D03*
X1740499Y1008223D03*
X1749863Y1003925D03*
X1756100Y1004362D03*
X1746030Y1004209D03*
X1737241Y997843D03*
X1740363Y989225D03*
X1755000Y1045000D03*
X1725000D03*
X1745000Y1100000D03*
X1759055Y1113504D03*
X1736725Y1123446D03*
X1733245Y1115503D03*
X1748100Y1142673D03*
X1736871Y1158178D03*
X1736941Y1141871D03*
X1751400Y1173900D03*
X1732768Y1141697D03*
X1748100Y1153673D03*
X1718117Y1152553D03*
X1723117D03*
X1728000Y1204500D03*
X1755900Y1212704D03*
X1720000Y1320000D03*
X1760000D03*
X1753000Y1302000D03*
X1740000Y1346900D03*
X1780000Y60000D03*
Y40000D03*
X1800000Y100000D03*
Y80000D03*
X1780000Y100000D03*
Y80000D03*
X1800000Y120000D03*
X1780000D03*
X1785956Y141870D03*
X1804350Y162661D03*
X1808850D03*
X1801988Y183904D03*
X1808050Y172661D03*
X1812350Y195261D03*
X1774456Y207992D03*
Y198543D03*
X1778956Y195492D03*
Y180492D03*
X1775140Y165728D03*
X1808600Y187911D03*
X1778956Y245492D03*
Y235492D03*
X1799350Y266161D03*
X1795350Y299661D03*
X1801850D03*
X1809850D03*
X1810850Y264661D03*
X1778956Y275492D03*
Y265492D03*
X1785956Y314114D03*
X1800000Y440000D03*
X1780000D03*
X1800000Y500000D03*
X1780000D03*
X1800000Y480000D03*
Y460000D03*
X1780000Y480000D03*
Y460000D03*
X1800000Y540000D03*
X1780000D03*
X1800000Y520000D03*
X1780000D03*
X1800000Y560000D03*
X1785956Y594626D03*
X1800650Y636417D03*
X1808050Y625417D03*
X1804350Y615417D03*
X1812350Y648017D03*
X1778956Y648248D03*
Y633248D03*
Y618248D03*
X1808600Y640667D03*
X1808850Y615417D03*
X1774456Y670197D03*
X1778956Y688248D03*
X1774456Y660748D03*
Y651299D03*
X1799326Y717506D03*
X1811474Y717423D03*
X1778956Y728248D03*
Y718248D03*
Y698248D03*
X1766721Y716500D03*
Y720500D03*
X1795468Y752594D03*
X1801968D03*
X1809968D03*
X1785956Y766870D03*
X1773500Y879500D03*
X1813851Y927406D03*
X1771000Y944500D03*
X1799000Y945500D03*
X1788361Y964676D03*
X1799051Y963346D03*
X1768692Y966073D03*
X1797463Y968652D03*
X1806077Y961860D03*
X1782666Y961344D03*
X1777666D03*
X1783778Y970371D03*
X1774863Y1024725D03*
X1788726Y1034726D03*
X1778863Y1005725D03*
X1787163Y1009741D03*
X1772863Y1005304D03*
X1778963Y999125D03*
X1772263Y995925D03*
X1785956Y1047382D03*
X1808050Y1078173D03*
X1800750Y1067973D03*
X1778956Y1071004D03*
X1812050Y1071223D03*
X1805250Y1067973D03*
X1800650Y1089173D03*
X1811968Y1100773D03*
X1774456Y1122953D03*
Y1104055D03*
X1778956Y1101004D03*
Y1086004D03*
X1799350Y1171673D03*
X1810850Y1170173D03*
X1778956Y1171004D03*
Y1151004D03*
Y1141004D03*
X1795350Y1205173D03*
X1801850D03*
X1809850D03*
X1785956Y1219626D03*
X1778956Y1181004D03*
X1772111Y1232695D03*
X1860000Y60000D03*
Y80000D03*
Y100000D03*
X1840000D03*
X1820000D03*
X1860000Y140000D03*
Y120000D03*
X1840000D03*
X1820000Y140000D03*
Y120000D03*
X1859017Y161725D03*
X1841021Y152968D03*
X1845517Y158475D03*
X1859117Y167375D03*
X1851717Y179075D03*
X1856219Y212661D03*
Y201661D03*
X1823350Y175161D03*
X1827796Y166019D03*
X1831350Y210661D03*
Y205661D03*
Y200661D03*
X1841169Y254661D03*
X1850669Y219661D03*
X1846169D03*
X1841669D03*
X1824850Y227661D03*
X1819850D03*
X1814850D03*
X1831350Y215661D03*
X1840000Y340000D03*
Y320000D03*
X1860000D03*
X1820000D03*
Y440000D03*
Y480000D03*
Y460000D03*
X1840000Y540000D03*
X1820000D03*
X1845545Y516536D03*
X1831330Y517279D03*
X1834896Y518597D03*
X1849045Y517435D03*
X1859232Y508600D03*
X1840000Y580000D03*
X1820000D03*
X1840000Y560000D03*
X1820000D03*
X1858917Y614481D03*
X1859117Y620131D03*
X1851717Y635331D03*
X1823350Y627917D03*
X1827667Y618703D03*
X1840855Y606200D03*
X1845417Y611231D03*
X1862200Y686700D03*
X1856219Y665417D03*
X1841669Y672417D03*
X1846169D03*
X1850669D03*
X1814850Y680417D03*
X1819850D03*
X1824850D03*
X1856219Y654417D03*
X1831350Y658417D03*
Y663417D03*
Y668417D03*
X1831300Y652600D03*
X1850000Y745000D03*
X1837576Y707417D03*
X1820000Y780000D03*
X1848491Y819787D03*
Y823787D03*
Y815787D03*
Y807787D03*
X1850151Y835119D03*
X1850177Y838746D03*
X1838239Y831626D03*
X1845579Y831731D03*
X1838311Y827911D03*
X1845651Y828016D03*
X1848491Y811787D03*
X1855676Y800787D03*
X1824170Y886349D03*
X1860276Y916059D03*
Y912059D03*
X1843731Y936066D03*
X1819541Y921500D03*
X1823937Y890883D03*
X1821152Y907899D03*
X1843811Y940067D03*
X1840419Y945557D03*
Y951057D03*
X1825945Y945449D03*
Y950949D03*
X1830665Y941751D03*
X1836165D03*
X1825971Y1015512D03*
Y1010012D03*
X1840445Y1015620D03*
Y1010120D03*
X1835895Y1020064D03*
X1830395D03*
X1857363Y1002625D03*
X1845363D03*
X1849363D03*
X1861363D03*
X1853363D03*
X1823350Y1080673D03*
X1856437Y1106400D03*
X1858046Y1092779D03*
X1836953Y1103391D03*
X1850363Y1115037D03*
X1847506Y1118794D03*
X1851565Y1118784D03*
X1850280Y1111373D03*
X1816046Y1098532D03*
X1836200Y1130000D03*
X1828850Y1106173D03*
Y1111173D03*
Y1116173D03*
Y1121173D03*
X1850532Y1153286D03*
X1836231Y1140669D03*
X1824850Y1133173D03*
X1814850D03*
X1819850D03*
X1840585Y1151653D03*
X1836400Y1151900D03*
X1860000Y1320000D03*
X1842000Y1344700D03*
X1880000Y60000D03*
X1900000D03*
X1880000Y80000D03*
X1900000D03*
Y100000D03*
X1880000D03*
X1900000Y120000D03*
X1880000Y140000D03*
Y120000D03*
X1910169Y141870D03*
X1898669Y207992D03*
Y198543D03*
X1903169Y195492D03*
Y180492D03*
Y165492D03*
X1885204Y184345D03*
X1869500Y179134D03*
X1876938Y181062D03*
X1865669Y201661D03*
X1870669D03*
X1875669D03*
X1880669D03*
X1873500Y219000D03*
X1865169Y247161D03*
Y234661D03*
X1903169Y245492D03*
X1898669Y217441D03*
X1903169Y235492D03*
X1881088Y296184D03*
X1903169Y275492D03*
Y265492D03*
X1880969Y276861D03*
X1880000Y340000D03*
Y320000D03*
X1910169Y314114D03*
X1890000Y400000D03*
Y380000D03*
Y360000D03*
Y440000D03*
Y420000D03*
X1864232Y508600D03*
X1910169Y594626D03*
X1903169Y648248D03*
Y633248D03*
Y618248D03*
X1885300Y636800D03*
X1869500Y633500D03*
X1878900Y637000D03*
X1898669Y670197D03*
X1903169Y688248D03*
X1898669Y660748D03*
Y651299D03*
X1879669Y652917D03*
X1874669D03*
X1869669D03*
X1864669D03*
X1903169Y728248D03*
Y718248D03*
Y698248D03*
X1880969Y729617D03*
X1865169Y699917D03*
X1880000Y780000D03*
X1910169Y766870D03*
X1887169Y752917D03*
X1908107Y831894D03*
X1902607D03*
X1907999Y846368D03*
X1902499D03*
X1884800Y890750D03*
X1902441Y888500D03*
X1892443Y894350D03*
X1872276Y916059D03*
X1876276D03*
Y920059D03*
X1872276D03*
X1868276Y916059D03*
X1864276Y912059D03*
X1868276D03*
X1864276Y916059D03*
X1876276Y912059D03*
X1872276D03*
X1884200Y895000D03*
X1896943Y894350D03*
X1891676Y917759D03*
X1884500Y912500D03*
X1904000Y933500D03*
Y929000D03*
Y925000D03*
X1906500Y893400D03*
X1909358Y897500D03*
X1904000Y938000D03*
X1873001Y901396D03*
X1904000Y921000D03*
X1872190Y936766D03*
X1875801Y946796D03*
X1875769Y951122D03*
X1880122Y954062D03*
X1880383Y950341D03*
X1865363Y1002625D03*
X1867963Y996425D03*
X1868100Y1055410D03*
X1871000Y1073300D03*
X1903169Y1071004D03*
X1910169Y1047382D03*
X1884835Y1067400D03*
X1887402Y1050193D03*
X1872162Y1055426D03*
X1864617Y1040934D03*
X1888085Y1059938D03*
X1876662Y1055426D03*
X1863700Y1085000D03*
X1898669Y1122953D03*
Y1113504D03*
Y1104055D03*
X1903169Y1101004D03*
Y1086004D03*
X1864833Y1091419D03*
X1870779Y1091763D03*
X1875779D03*
X1880779D03*
X1863131Y1133108D03*
X1903169Y1171004D03*
X1903100Y1149700D03*
X1903169Y1141004D03*
X1864352Y1153308D03*
X1871174Y1138730D03*
X1887169Y1205673D03*
X1910169Y1219626D03*
X1903169Y1181004D03*
X1880969Y1182373D03*
X1900000Y1260000D03*
Y1280000D03*
Y1320000D03*
Y1300000D03*
X1873500Y1329000D03*
X1920000Y60000D03*
Y80000D03*
Y100000D03*
Y120000D03*
X1912551Y836444D03*
Y841944D03*
X1911676Y893469D03*
X1920000Y1260000D03*
Y1280000D03*
Y1320000D03*
Y1300000D03*
X2432929Y1395966D03*
G54D30*
X942126Y58465D03*
Y346457D03*
Y437598D03*
Y725590D03*
X1110236Y58465D03*
Y346457D03*
Y437598D03*
Y725590D03*
X2432929Y305166D03*
G54D21*
X127988Y190242D03*
Y185742D03*
Y194242D03*
Y181742D03*
Y634498D03*
Y638498D03*
Y642998D03*
Y646998D03*
Y1087254D03*
Y1091254D03*
Y1095754D03*
Y1099754D03*
X252200Y190242D03*
Y185742D03*
Y194242D03*
Y181742D03*
Y634498D03*
Y638498D03*
Y642998D03*
Y646998D03*
Y1087254D03*
Y1091254D03*
Y1095754D03*
Y1099754D03*
X376413Y190242D03*
Y185742D03*
Y194242D03*
Y181742D03*
Y634498D03*
Y638498D03*
Y642998D03*
Y646998D03*
Y1087254D03*
Y1091254D03*
Y1095754D03*
Y1099754D03*
X500625Y190242D03*
Y185742D03*
Y194242D03*
Y181742D03*
Y634498D03*
Y638498D03*
Y642998D03*
Y646998D03*
Y1087254D03*
Y1091254D03*
Y1095754D03*
Y1099754D03*
X624838Y190242D03*
Y185742D03*
Y194242D03*
Y181742D03*
Y634498D03*
Y638498D03*
Y642998D03*
Y646998D03*
Y1087254D03*
Y1091254D03*
Y1095754D03*
Y1099754D03*
X749051Y190242D03*
Y185742D03*
Y194242D03*
Y181742D03*
Y634498D03*
Y638498D03*
Y642998D03*
Y646998D03*
Y1087254D03*
Y1091254D03*
Y1095754D03*
Y1099754D03*
X1066750Y1224035D03*
X1070750D03*
X1075250D03*
X1079250D03*
X1066750Y1209862D03*
X1070750D03*
X1075250D03*
X1079250D03*
X1066750Y1216949D03*
X1070750D03*
X1075250D03*
X1079250D03*
X1066750Y1231122D03*
X1070750D03*
X1075250D03*
X1079250D03*
X1066750Y1238209D03*
X1070750D03*
X1075250D03*
X1079250D03*
X1066750Y1245295D03*
X1070750D03*
X1075250D03*
X1079250D03*
X1066750Y1301988D03*
X1070750D03*
X1075250D03*
X1079250D03*
X1066750Y1309075D03*
X1070750D03*
X1075250D03*
X1079250D03*
X1066750Y1316161D03*
X1070750D03*
X1075250D03*
X1079250D03*
X1066750Y1323248D03*
X1070750D03*
X1075250D03*
X1079250D03*
X1066750Y1294902D03*
X1070750D03*
X1075250D03*
X1079250D03*
X1066750Y1330335D03*
X1070750D03*
X1075250D03*
X1079250D03*
X1066750Y1387028D03*
X1070750D03*
X1075250D03*
X1079250D03*
X1066750Y1394114D03*
X1070750D03*
X1075250D03*
X1079250D03*
X1066750Y1401201D03*
X1070750D03*
X1075250D03*
X1079250D03*
X1066750Y1408287D03*
X1070750D03*
X1075250D03*
X1079250D03*
X1066750Y1415374D03*
X1070750D03*
X1075250D03*
X1079250D03*
X1066750Y1379941D03*
X1070750D03*
X1075250D03*
X1079250D03*
X1278900Y182823D03*
X1274900D03*
X1270400D03*
X1266400D03*
X1261250Y167823D03*
X1256750D03*
X1265250D03*
X1252750D03*
X1278500Y634498D03*
Y638498D03*
Y642998D03*
Y646998D03*
X1259800Y631998D03*
Y627998D03*
Y623498D03*
Y619498D03*
Y1080754D03*
Y1076254D03*
Y1072254D03*
X1278500Y1087254D03*
Y1091254D03*
Y1095754D03*
Y1099754D03*
X1259800Y1084754D03*
X1376963Y167823D03*
X1402713Y181742D03*
Y185742D03*
Y190242D03*
Y194242D03*
X1380963Y167823D03*
X1385463D03*
X1389463D03*
X1402713Y634498D03*
Y638498D03*
Y642998D03*
Y646998D03*
X1384013Y631998D03*
Y627998D03*
Y623498D03*
Y619498D03*
Y1080754D03*
Y1076254D03*
Y1072254D03*
X1402713Y1087254D03*
Y1091254D03*
Y1095754D03*
Y1099754D03*
X1384013Y1084754D03*
X1515450Y181700D03*
X1511450D03*
X1506950D03*
X1502950D03*
X1508225Y631998D03*
Y627998D03*
Y623498D03*
Y619498D03*
Y1080754D03*
Y1076254D03*
Y1072254D03*
Y1084754D03*
X1526925Y181742D03*
Y185742D03*
Y190242D03*
Y194242D03*
Y634498D03*
Y638498D03*
Y642998D03*
Y646998D03*
Y1087254D03*
Y1091254D03*
Y1095754D03*
Y1099754D03*
X1651138Y181742D03*
Y185742D03*
Y190242D03*
Y194242D03*
X1632438Y179242D03*
Y175242D03*
Y170742D03*
Y166742D03*
X1651138Y634498D03*
Y638498D03*
Y642998D03*
Y646998D03*
X1632438Y631998D03*
Y627998D03*
Y623498D03*
Y619498D03*
Y1080754D03*
Y1076254D03*
Y1072254D03*
X1651138Y1087254D03*
Y1091254D03*
Y1095754D03*
Y1099754D03*
X1632438Y1084754D03*
X1756650Y179242D03*
Y175242D03*
Y170742D03*
Y166742D03*
X1725350Y634498D03*
Y638498D03*
Y642998D03*
Y646998D03*
X1731650Y631998D03*
Y627998D03*
Y623498D03*
Y619498D03*
X1756650Y1080754D03*
Y1076254D03*
Y1072254D03*
Y1084754D03*
X1775350Y181742D03*
Y185742D03*
Y190242D03*
Y194242D03*
Y1087254D03*
Y1091254D03*
Y1095754D03*
Y1099754D03*
X1899563Y181742D03*
Y185742D03*
Y190242D03*
Y194242D03*
X1880863Y179242D03*
Y175242D03*
Y170742D03*
Y166742D03*
X1899563Y634498D03*
Y638498D03*
Y642998D03*
Y646998D03*
X1880863Y631998D03*
Y627998D03*
Y623498D03*
Y619498D03*
Y1080754D03*
Y1076254D03*
Y1072254D03*
X1899563Y1087254D03*
Y1091254D03*
Y1095754D03*
Y1099754D03*
X1880863Y1084754D03*
X2432929Y1456566D03*
G54D31*
X975787Y-25590D03*
X2432929Y2166D03*
G54D13*
X15157Y474409D03*
X904921Y-25591D03*
X1894684Y474409D03*
X2432929Y-58434D03*
G54D22*
X173228Y1062992D03*
X421653Y1141732D03*
X670079Y1062992D03*
X1343701D03*
X1592126Y1141732D03*
X1840551Y1062992D03*
X2432929Y789966D03*
G54D32*
X975786Y564960D03*
X2432929Y911166D03*
G54D14*
X31496Y882677D03*
X168307Y646457D03*
X660236D03*
X718110Y820866D03*
X1366142Y646457D03*
X1462992Y866929D03*
X1602756Y646457D03*
X1903346Y803937D03*
X2432929Y668766D03*
G54D23*
X173228Y1114173D03*
X670079D03*
X1343700D03*
X1840551D03*
X2432929Y123366D03*
G54D33*
X986614Y1619764D03*
X974016D03*
Y1597126D03*
X986614D03*
X974016Y1591220D03*
Y1603031D03*
Y1613858D03*
X986614Y1591220D03*
Y1613858D03*
Y1603031D03*
X974016Y1642401D03*
X986614D03*
X974016Y1625669D03*
Y1636496D03*
Y1648307D03*
X986614Y1625669D03*
Y1636496D03*
Y1648307D03*
X1030709Y1619764D03*
X1014961D03*
X1002362D03*
Y1597126D03*
X1014961D03*
X1030709D03*
X1002362Y1591220D03*
Y1603031D03*
Y1613858D03*
X1014961Y1591220D03*
Y1603031D03*
Y1613858D03*
X1030709Y1591220D03*
Y1613858D03*
Y1603031D03*
X1002362Y1642401D03*
X1014961D03*
X1030709D03*
X1002362Y1625669D03*
Y1636496D03*
Y1648307D03*
X1014961Y1625669D03*
Y1636496D03*
Y1648307D03*
X1030709Y1625669D03*
Y1636496D03*
Y1648307D03*
X1043307Y1619764D03*
Y1597126D03*
Y1591220D03*
Y1603031D03*
Y1613858D03*
Y1642401D03*
Y1625669D03*
Y1636496D03*
Y1648307D03*
X1101457Y1588583D03*
X1119685D03*
X1101457Y1601181D03*
X1119685D03*
X1108150Y1588583D03*
X1126378D03*
X1108150Y1601181D03*
X1126378D03*
X2432929Y971766D03*
G54D15*
X60540Y-85109D03*
X59536Y1573374D03*
X79000Y1301900D03*
X1826700Y77600D03*
X1865705Y1573374D03*
X1898432Y-93682D03*
X1908500Y1346800D03*
X2432929Y426366D03*
G54D24*
X429724Y63977D03*
Y68307D03*
X443898Y63977D03*
X458071D03*
X436811Y67914D03*
X450984D03*
X458071Y68307D03*
X443898D03*
X429724Y116339D03*
Y92323D03*
Y96654D03*
Y102166D03*
Y106496D03*
Y110827D03*
Y87993D03*
Y82481D03*
Y78150D03*
Y73819D03*
X443898Y116339D03*
X458071D03*
X436811Y114764D03*
X450984D03*
X436811Y82087D03*
X450984D03*
X443898Y92323D03*
X458071D03*
X443898Y96654D03*
X458071D03*
X436811Y96260D03*
X450984D03*
X443898Y102166D03*
X458071D03*
X436811Y100591D03*
X450984D03*
X443898Y106496D03*
X458071D03*
X436811Y106103D03*
X450984D03*
X443898Y110827D03*
X458071D03*
X436811Y110433D03*
X450984D03*
X458071Y87993D03*
Y82481D03*
X450984Y91930D03*
Y86418D03*
X443898Y87993D03*
Y82481D03*
X436811Y91930D03*
Y86418D03*
X443898Y78150D03*
X458071D03*
Y73819D03*
X450984Y77756D03*
Y72245D03*
X443898Y73819D03*
X436811Y77756D03*
Y72245D03*
X429724Y120670D03*
X443898D03*
X458071D03*
X436811Y120276D03*
X450984D03*
X465157Y67914D03*
X472244Y63977D03*
X479331Y67914D03*
X472244Y68307D03*
X465157Y114764D03*
X472244Y116339D03*
X479331Y114764D03*
X465157Y82087D03*
Y96260D03*
Y100591D03*
Y106103D03*
Y110433D03*
X479331Y82087D03*
X472244Y92323D03*
Y96654D03*
X479331Y96260D03*
X472244Y102166D03*
X479331Y100591D03*
X472244Y106496D03*
X479331Y106103D03*
X472244Y110827D03*
X479331Y110433D03*
Y91930D03*
Y86418D03*
X472244Y87993D03*
Y82481D03*
X465157Y91930D03*
Y86418D03*
X472244Y78150D03*
X479331Y77756D03*
Y72245D03*
X472244Y73819D03*
X465157Y77756D03*
Y72245D03*
Y120276D03*
X472244Y120670D03*
X479331Y120276D03*
X514764Y63977D03*
Y68307D03*
X550197Y67914D03*
X536024D03*
X521850D03*
X543110Y63977D03*
X528937D03*
X543110Y68307D03*
X528937D03*
X557283Y63977D03*
Y68307D03*
X514764Y116339D03*
Y110827D03*
Y106496D03*
Y102166D03*
Y96654D03*
Y92323D03*
Y87993D03*
Y82481D03*
Y78150D03*
Y73819D03*
X550197Y114764D03*
X536024D03*
X521850D03*
X543110Y116339D03*
X528937D03*
X550197Y110433D03*
X536024D03*
X521850D03*
X543110Y110827D03*
X528937D03*
X550197Y106103D03*
X536024D03*
X521850D03*
X543110Y106496D03*
X528937D03*
X550197Y100591D03*
X536024D03*
X521850D03*
X543110Y102166D03*
X528937D03*
X550197Y96260D03*
X536024D03*
X521850D03*
X543110Y96654D03*
X528937D03*
X543110Y92323D03*
X528937D03*
X550197Y82087D03*
X536024D03*
X521850D03*
X550197Y91930D03*
Y86418D03*
X543110Y87993D03*
Y82481D03*
X536024Y91930D03*
Y86418D03*
X528937Y87993D03*
Y82481D03*
X521850Y91930D03*
Y86418D03*
X543110Y78150D03*
X528937D03*
X550197Y77756D03*
Y72245D03*
X543110Y73819D03*
X536024Y77756D03*
Y72245D03*
X528937Y73819D03*
X521850Y77756D03*
Y72245D03*
X557283Y116339D03*
Y110827D03*
Y106496D03*
Y102166D03*
Y96654D03*
Y92323D03*
Y87993D03*
Y82481D03*
Y78150D03*
Y73819D03*
X514764Y120670D03*
X550197Y120276D03*
X536024D03*
X521850D03*
X543110Y120670D03*
X528937D03*
X557283D03*
X564370Y67914D03*
Y114764D03*
Y110433D03*
Y106103D03*
Y100591D03*
Y96260D03*
Y82087D03*
Y91930D03*
Y86418D03*
Y77756D03*
Y72245D03*
Y120276D03*
X833859Y1594095D03*
Y1598425D03*
Y1603937D03*
Y1608268D03*
Y1612599D03*
X840945Y1598032D03*
X826772D03*
X840945Y1602363D03*
X826772D03*
X840945Y1607874D03*
X826772D03*
X840945Y1612205D03*
X826772D03*
X840945Y1616536D03*
X826772D03*
X833859Y1618111D03*
Y1622441D03*
Y1626772D03*
Y1632284D03*
Y1636614D03*
Y1640945D03*
Y1646457D03*
Y1650788D03*
X840945Y1622048D03*
X826772D03*
X840945Y1626378D03*
X826772D03*
X840945Y1630709D03*
X826772D03*
X840945Y1636221D03*
X826772D03*
X840945Y1640551D03*
X826772D03*
X840945Y1644882D03*
X826772D03*
X840945Y1650394D03*
X826772D03*
X876378Y1594095D03*
X862205D03*
X848032D03*
X876378Y1598425D03*
X862205D03*
X848032D03*
X876378Y1603937D03*
X862205D03*
X848032D03*
X876378Y1608268D03*
X862205D03*
X848032D03*
X876378Y1612599D03*
X862205D03*
X848032D03*
X890552Y1598032D03*
X869292D03*
X855118D03*
X890552Y1602363D03*
X869292D03*
X855118D03*
X890552Y1607874D03*
X869292D03*
X855118D03*
X890552Y1612205D03*
X869292D03*
X855118D03*
X890552Y1616536D03*
X869292D03*
X855118D03*
X876378Y1618111D03*
X862205D03*
X848032D03*
X876378Y1622441D03*
X862205D03*
X848032D03*
X876378Y1626772D03*
X862205D03*
X848032D03*
X876378Y1632284D03*
X862205D03*
X848032D03*
X876378Y1636614D03*
X862205D03*
X848032D03*
X876378Y1640945D03*
X862205D03*
X848032D03*
X876378Y1646457D03*
X862205D03*
X848032D03*
X876378Y1650788D03*
X862205D03*
X848032D03*
X890552Y1622048D03*
X869292D03*
X855118D03*
X890552Y1626378D03*
X869292D03*
X855118D03*
X890552Y1630709D03*
X869292D03*
X855118D03*
X890552Y1636221D03*
X869292D03*
X855118D03*
X890552Y1640551D03*
X869292D03*
X855118D03*
X890552Y1644882D03*
X869292D03*
X855118D03*
X890552Y1650394D03*
X869292D03*
X855118D03*
X911811Y1603937D03*
Y1608268D03*
Y1612599D03*
X904725Y1602363D03*
Y1607874D03*
Y1612205D03*
Y1616536D03*
X911811Y1594095D03*
Y1598425D03*
X904725Y1598032D03*
X897638Y1594095D03*
Y1598425D03*
Y1603937D03*
Y1608268D03*
Y1612599D03*
X911811Y1632284D03*
Y1636614D03*
Y1640945D03*
Y1646457D03*
Y1650788D03*
X904725Y1630709D03*
Y1636221D03*
Y1640551D03*
Y1644882D03*
Y1650394D03*
X911811Y1618111D03*
Y1622441D03*
Y1626772D03*
X904725Y1622048D03*
Y1626378D03*
X897638Y1618111D03*
Y1622441D03*
Y1626772D03*
Y1632284D03*
Y1636614D03*
Y1640945D03*
Y1646457D03*
Y1650788D03*
X1091089Y988592D03*
X1095420D03*
X1100932D03*
X1105262D03*
X1109593D03*
X1115105D03*
X1119435D03*
X1123766D03*
X1129278D03*
X1133609D03*
X1095026Y995678D03*
X1099357D03*
X1104869D03*
X1109199D03*
X1113530D03*
X1119042D03*
X1123372D03*
X1127703D03*
X1133215D03*
X1091089Y1002765D03*
X1095420D03*
X1100932D03*
X1105262D03*
X1109593D03*
X1115105D03*
X1119435D03*
X1123766D03*
X1129278D03*
X1133609D03*
X1095026Y1009852D03*
X1099357D03*
X1104869D03*
X1109199D03*
X1113530D03*
X1119042D03*
X1123372D03*
X1127703D03*
X1133215D03*
X1091089Y1016938D03*
X1095420D03*
X1100932D03*
X1105262D03*
X1109593D03*
X1115105D03*
X1119435D03*
X1123766D03*
X1129278D03*
X1133609D03*
X1095026Y1024025D03*
X1099357D03*
X1104869D03*
X1109199D03*
X1113530D03*
X1119042D03*
X1123372D03*
X1127703D03*
X1133215D03*
X1091089Y1031111D03*
X1095420D03*
X1100932D03*
X1105262D03*
X1109593D03*
X1115105D03*
X1119435D03*
X1123766D03*
X1129278D03*
X1133609D03*
X1095026Y1038198D03*
X1099357D03*
X1104869D03*
X1109199D03*
X1113530D03*
X1119042D03*
X1123372D03*
X1127703D03*
X1133215D03*
X1091089Y1160257D03*
Y1174430D03*
X1095420Y1160257D03*
Y1174430D03*
X1100932Y1160257D03*
Y1174430D03*
X1105262Y1160257D03*
Y1174430D03*
X1109593Y1160257D03*
Y1174430D03*
X1115105Y1160257D03*
Y1174430D03*
X1119435Y1160257D03*
Y1174430D03*
X1123766Y1160257D03*
Y1174430D03*
X1129278Y1160257D03*
Y1174430D03*
X1133609Y1160257D03*
Y1174430D03*
X1095026Y1167343D03*
X1099357D03*
X1104869D03*
X1109199D03*
X1113530D03*
X1119042D03*
X1123372D03*
X1127703D03*
X1133215D03*
X1091089Y1188603D03*
Y1202776D03*
Y1216949D03*
X1095420Y1188603D03*
Y1202776D03*
Y1216949D03*
X1100932Y1188603D03*
Y1202776D03*
Y1216949D03*
X1105262Y1188603D03*
Y1202776D03*
Y1216949D03*
X1109593Y1188603D03*
Y1202776D03*
Y1216949D03*
X1115105Y1188603D03*
Y1202776D03*
Y1216949D03*
X1119435Y1188603D03*
Y1202776D03*
Y1216949D03*
X1123766Y1188603D03*
Y1202776D03*
Y1216949D03*
X1129278Y1188603D03*
Y1202776D03*
Y1216949D03*
X1133609Y1188603D03*
Y1202776D03*
Y1216949D03*
X1095026Y1181516D03*
Y1195690D03*
Y1209863D03*
Y1224036D03*
X1099357Y1181516D03*
Y1195690D03*
Y1209863D03*
Y1224036D03*
X1104869Y1181516D03*
Y1195690D03*
Y1209863D03*
Y1224036D03*
X1109199Y1181516D03*
Y1195690D03*
Y1209863D03*
Y1224036D03*
X1113530Y1181516D03*
Y1195690D03*
Y1209863D03*
Y1224036D03*
X1119042Y1181516D03*
Y1195690D03*
Y1209863D03*
Y1224036D03*
X1123372Y1181516D03*
Y1195690D03*
Y1209863D03*
Y1224036D03*
X1127703Y1181516D03*
Y1195690D03*
Y1209863D03*
Y1224036D03*
X1133215Y1181516D03*
Y1195690D03*
Y1209863D03*
Y1224036D03*
X1091089Y1231123D03*
Y1245296D03*
Y1259469D03*
Y1273642D03*
X1095420Y1231123D03*
Y1245296D03*
Y1259469D03*
Y1273642D03*
X1100932Y1231123D03*
Y1245296D03*
Y1259469D03*
Y1273642D03*
X1105262Y1231123D03*
Y1245296D03*
Y1259469D03*
Y1273642D03*
X1109593Y1231123D03*
Y1245296D03*
Y1259469D03*
Y1273642D03*
X1115105Y1231123D03*
Y1245296D03*
Y1259469D03*
Y1273642D03*
X1119435Y1231123D03*
Y1245296D03*
Y1259469D03*
Y1273642D03*
X1123766Y1231123D03*
Y1245296D03*
Y1259469D03*
Y1273642D03*
X1129278Y1231123D03*
Y1245296D03*
Y1259469D03*
Y1273642D03*
X1133609Y1231123D03*
Y1245296D03*
Y1259469D03*
Y1273642D03*
X1095026Y1238209D03*
Y1252382D03*
Y1266556D03*
X1099357Y1238209D03*
Y1252382D03*
Y1266556D03*
X1104869Y1238209D03*
Y1252382D03*
Y1266556D03*
X1109199Y1238209D03*
Y1252382D03*
Y1266556D03*
X1113530Y1238209D03*
Y1252382D03*
Y1266556D03*
X1119042Y1238209D03*
Y1252382D03*
Y1266556D03*
X1123372Y1238209D03*
Y1252382D03*
Y1266556D03*
X1127703Y1238209D03*
Y1252382D03*
Y1266556D03*
X1133215Y1238209D03*
Y1252382D03*
Y1266556D03*
X1091089Y1287816D03*
Y1301989D03*
Y1316162D03*
X1095420Y1287816D03*
Y1301989D03*
Y1316162D03*
X1100932Y1287816D03*
Y1301989D03*
Y1316162D03*
X1105262Y1287816D03*
Y1301989D03*
Y1316162D03*
X1109593Y1287816D03*
Y1301989D03*
Y1316162D03*
X1115105Y1287816D03*
Y1301989D03*
Y1316162D03*
X1119435Y1287816D03*
Y1301989D03*
Y1316162D03*
X1123766Y1287816D03*
Y1301989D03*
Y1316162D03*
X1129278Y1287816D03*
Y1301989D03*
Y1316162D03*
X1133609Y1287816D03*
Y1301989D03*
Y1316162D03*
X1095026Y1280729D03*
Y1294902D03*
Y1309075D03*
Y1323249D03*
X1099357Y1280729D03*
Y1294902D03*
Y1309075D03*
Y1323249D03*
X1104869Y1280729D03*
Y1294902D03*
Y1309075D03*
Y1323249D03*
X1109199Y1280729D03*
Y1294902D03*
Y1309075D03*
Y1323249D03*
X1113530Y1280729D03*
Y1294902D03*
Y1309075D03*
Y1323249D03*
X1119042Y1280729D03*
Y1294902D03*
Y1309075D03*
Y1323249D03*
X1123372Y1280729D03*
Y1294902D03*
Y1309075D03*
Y1323249D03*
X1127703Y1280729D03*
Y1294902D03*
Y1309075D03*
Y1323249D03*
X1133215Y1280729D03*
Y1294902D03*
Y1309075D03*
Y1323249D03*
X1091089Y1330335D03*
Y1344508D03*
Y1358682D03*
Y1372855D03*
X1095420Y1330335D03*
Y1344508D03*
Y1358682D03*
Y1372855D03*
X1100932Y1330335D03*
Y1344508D03*
Y1358682D03*
Y1372855D03*
X1105262Y1330335D03*
Y1344508D03*
Y1358682D03*
Y1372855D03*
X1109593Y1330335D03*
Y1344508D03*
Y1358682D03*
Y1372855D03*
X1115105Y1330335D03*
Y1344508D03*
Y1358682D03*
Y1372855D03*
X1119435Y1330335D03*
Y1344508D03*
Y1358682D03*
Y1372855D03*
X1123766Y1330335D03*
Y1344508D03*
Y1358682D03*
Y1372855D03*
X1129278Y1330335D03*
Y1344508D03*
Y1358682D03*
Y1372855D03*
X1133609Y1330335D03*
Y1344508D03*
Y1358682D03*
Y1372855D03*
X1095026Y1337422D03*
Y1351595D03*
Y1365768D03*
X1099357Y1337422D03*
Y1351595D03*
Y1365768D03*
X1104869Y1337422D03*
Y1351595D03*
Y1365768D03*
X1109199Y1337422D03*
Y1351595D03*
Y1365768D03*
X1113530Y1337422D03*
Y1351595D03*
Y1365768D03*
X1119042Y1337422D03*
Y1351595D03*
Y1365768D03*
X1123372Y1337422D03*
Y1351595D03*
Y1365768D03*
X1127703Y1337422D03*
Y1351595D03*
Y1365768D03*
X1133215Y1337422D03*
Y1351595D03*
Y1365768D03*
X1091089Y1387028D03*
Y1401201D03*
X1095420Y1387028D03*
Y1401201D03*
X1100932Y1387028D03*
Y1401201D03*
X1105262Y1387028D03*
Y1401201D03*
X1109593Y1387028D03*
Y1401201D03*
X1115105Y1387028D03*
Y1401201D03*
X1119435Y1387028D03*
Y1401201D03*
X1123766Y1387028D03*
Y1401201D03*
X1129278Y1387028D03*
Y1401201D03*
X1133609Y1387028D03*
Y1401201D03*
X1095026Y1379942D03*
Y1394115D03*
Y1408288D03*
X1099357Y1379942D03*
Y1394115D03*
Y1408288D03*
X1104869Y1379942D03*
Y1394115D03*
Y1408288D03*
X1109199Y1379942D03*
Y1394115D03*
Y1408288D03*
X1113530Y1379942D03*
Y1394115D03*
Y1408288D03*
X1119042Y1379942D03*
Y1394115D03*
Y1408288D03*
X1123372Y1379942D03*
Y1394115D03*
Y1408288D03*
X1127703Y1379942D03*
Y1394115D03*
Y1408288D03*
X1133215Y1379942D03*
Y1394115D03*
Y1408288D03*
X1398228Y63977D03*
Y68307D03*
X1412402Y63977D03*
X1426575D03*
X1405315Y67914D03*
X1419488D03*
X1426575Y68307D03*
X1412402D03*
X1398228Y116339D03*
Y92323D03*
Y96654D03*
Y102166D03*
Y106496D03*
Y110827D03*
Y87993D03*
Y82481D03*
Y78150D03*
Y73819D03*
X1412402Y116339D03*
X1426575D03*
X1405315Y114764D03*
X1419488D03*
X1405315Y82087D03*
X1419488D03*
X1412402Y92323D03*
X1426575D03*
X1412402Y96654D03*
X1426575D03*
X1405315Y96260D03*
X1419488D03*
X1412402Y102166D03*
X1426575D03*
X1405315Y100591D03*
X1419488D03*
X1412402Y106496D03*
X1426575D03*
X1405315Y106103D03*
X1419488D03*
X1412402Y110827D03*
X1426575D03*
X1405315Y110433D03*
X1419488D03*
X1426575Y87993D03*
Y82481D03*
X1419488Y91930D03*
Y86418D03*
X1412402Y87993D03*
Y82481D03*
X1405315Y91930D03*
Y86418D03*
X1412402Y78150D03*
X1426575D03*
Y73819D03*
X1419488Y77756D03*
Y72245D03*
X1412402Y73819D03*
X1405315Y77756D03*
Y72245D03*
X1398228Y120670D03*
X1412402D03*
X1426575D03*
X1405315Y120276D03*
X1419488D03*
X1433661Y67914D03*
X1440748Y63977D03*
X1447835Y67914D03*
X1440748Y68307D03*
X1433661Y114764D03*
X1440748Y116339D03*
X1447835Y114764D03*
X1433661Y82087D03*
Y96260D03*
Y100591D03*
Y106103D03*
Y110433D03*
X1447835Y82087D03*
X1440748Y92323D03*
Y96654D03*
X1447835Y96260D03*
X1440748Y102166D03*
X1447835Y100591D03*
X1440748Y106496D03*
X1447835Y106103D03*
X1440748Y110827D03*
X1447835Y110433D03*
Y91930D03*
Y86418D03*
X1440748Y87993D03*
Y82481D03*
X1433661Y91930D03*
Y86418D03*
X1440748Y78150D03*
X1447835Y77756D03*
Y72245D03*
X1440748Y73819D03*
X1433661Y77756D03*
Y72245D03*
Y120276D03*
X1440748Y120670D03*
X1447835Y120276D03*
X1483268Y63977D03*
Y68307D03*
X1518701Y67914D03*
X1504528D03*
X1490354D03*
X1511614Y63977D03*
X1497441D03*
X1511614Y68307D03*
X1497441D03*
X1483268Y116339D03*
Y110827D03*
Y106496D03*
Y102166D03*
Y96654D03*
Y92323D03*
Y87993D03*
Y82481D03*
Y78150D03*
Y73819D03*
X1518701Y114764D03*
X1504528D03*
X1490354D03*
X1511614Y116339D03*
X1497441D03*
X1518701Y110433D03*
X1504528D03*
X1490354D03*
X1511614Y110827D03*
X1497441D03*
X1518701Y106103D03*
X1504528D03*
X1490354D03*
X1511614Y106496D03*
X1497441D03*
X1518701Y100591D03*
X1504528D03*
X1490354D03*
X1511614Y102166D03*
X1497441D03*
X1518701Y96260D03*
X1504528D03*
X1490354D03*
X1511614Y96654D03*
X1497441D03*
X1511614Y92323D03*
X1497441D03*
X1518701Y82087D03*
X1504528D03*
X1490354D03*
X1518701Y91930D03*
Y86418D03*
X1511614Y87993D03*
Y82481D03*
X1504528Y91930D03*
Y86418D03*
X1497441Y87993D03*
Y82481D03*
X1490354Y91930D03*
Y86418D03*
X1511614Y78150D03*
X1497441D03*
X1518701Y77756D03*
Y72245D03*
X1511614Y73819D03*
X1504528Y77756D03*
Y72245D03*
X1497441Y73819D03*
X1490354Y77756D03*
Y72245D03*
X1483268Y120670D03*
X1518701Y120276D03*
X1504528D03*
X1490354D03*
X1511614Y120670D03*
X1497441D03*
X1532874Y67914D03*
X1525787Y63977D03*
Y68307D03*
X1532874Y114764D03*
X1525787Y116339D03*
X1532874Y110433D03*
X1525787Y110827D03*
X1532874Y106103D03*
X1525787Y106496D03*
X1532874Y100591D03*
X1525787Y102166D03*
X1532874Y96260D03*
X1525787Y96654D03*
Y92323D03*
X1532874Y82087D03*
Y91930D03*
Y86418D03*
X1525787Y87993D03*
Y82481D03*
Y78150D03*
X1532874Y77756D03*
Y72245D03*
X1525787Y73819D03*
X1532874Y120276D03*
X1525787Y120670D03*
X2432929Y1274766D03*
G54D34*
X988795Y1571058D03*
Y1576658D03*
X1026106Y1545595D03*
Y1539995D03*
X1031706Y1545595D03*
Y1539995D03*
X1020574Y1540059D03*
Y1545659D03*
X1039758Y1559605D03*
X1014974Y1540059D03*
Y1545659D03*
X1039358Y1565405D03*
X1033717Y1563634D03*
X1028223Y1563763D03*
X1022623D03*
X994305Y1566342D03*
X1017023Y1563763D03*
X1011476Y1565175D03*
X1005658Y1565005D03*
X1000058D03*
X1039958Y1553705D03*
Y1548105D03*
Y1542505D03*
X1039358Y1571005D03*
Y1576605D03*
X1005658Y1575905D03*
X1033917Y1574834D03*
X1033717Y1569234D03*
X1000058Y1575905D03*
X1028423Y1574963D03*
X1028223Y1569363D03*
X994460Y1577240D03*
X1022823Y1574963D03*
X1022623Y1569363D03*
X1017223Y1574963D03*
X1017023Y1569363D03*
X994305Y1571942D03*
X1011676Y1576375D03*
X1011476Y1570775D03*
X1005658Y1570605D03*
X1000058D03*
X1078358Y1561105D03*
Y1566705D03*
X1072758Y1561105D03*
Y1566705D03*
X1067158Y1561105D03*
Y1566705D03*
X1061558Y1561105D03*
Y1566705D03*
X1055768Y1566675D03*
X1055418Y1560785D03*
X1055618Y1554885D03*
Y1549285D03*
Y1543685D03*
X1078358Y1572305D03*
X1072758D03*
X1067158D03*
X1061558D03*
X1055768Y1572275D03*
Y1577875D03*
X2432929Y1092966D03*
G54D25*
X450984Y124507D03*
X436811D03*
X479830D03*
X465157D03*
X550197D03*
X536023D03*
X521850D03*
X564370D03*
X1137446Y1024025D03*
Y1009852D03*
Y995679D03*
Y1038198D03*
Y1167343D03*
Y1224036D03*
Y1209863D03*
Y1195690D03*
Y1181516D03*
Y1266556D03*
Y1252383D03*
Y1238209D03*
Y1309076D03*
Y1323249D03*
Y1294902D03*
Y1280729D03*
Y1365769D03*
Y1351595D03*
Y1337422D03*
Y1394115D03*
Y1408288D03*
Y1379942D03*
X1447834Y124507D03*
X1504527D03*
X1490354D03*
X1518701D03*
X1532874D03*
X2432929Y1335366D03*
G54D16*
X103642Y36220D03*
X654822D03*
X1274311D03*
X1825492D03*
X2432929Y608166D03*
G54D35*
X1039845Y1467746D03*
X1026345D03*
X1030845D03*
X1035345D03*
X1039845Y1463246D03*
X1026345D03*
X1030845D03*
X1035345D03*
X1005400Y1463157D03*
X1000900D03*
X996400D03*
X1009900D03*
X1005400Y1467657D03*
X1000900D03*
X996400D03*
X1009900D03*
X1035345Y1476746D03*
X1030845D03*
X1026345D03*
X1039845D03*
Y1472246D03*
X1026345D03*
X1030845D03*
X1035345D03*
X1005400Y1472157D03*
X1000900D03*
X996400D03*
X1009900D03*
Y1476657D03*
X1005400D03*
X1000900D03*
X996400D03*
X1023583Y1489593D03*
X995783D03*
X1000500Y1511400D03*
X1036578Y1511210D03*
X1014690Y1511178D03*
X1010190D03*
X1005690D03*
X1031790Y1511078D03*
X1027290D03*
X1019600Y1511100D03*
X1023583Y1501593D03*
Y1507593D03*
Y1495593D03*
X995783D03*
Y1501593D03*
Y1507593D03*
X1040583Y1517883D03*
X1031799Y1534392D03*
X1031882Y1528985D03*
X1026459Y1528919D03*
X1026376Y1534326D03*
X1014867D03*
X1014950Y1528919D03*
X1020290Y1534392D03*
X1020373Y1528985D03*
X1040500Y1529290D03*
X1040583Y1523883D03*
X1062700Y1463100D03*
X1058200D03*
X1067200D03*
X1062700Y1467600D03*
X1058200D03*
X1067200D03*
X1053700Y1463100D03*
Y1467600D03*
X1062700Y1472100D03*
X1058200D03*
X1067200D03*
Y1476600D03*
X1058200D03*
X1062700D03*
X1053700Y1472100D03*
Y1476600D03*
X1078683Y1489593D03*
X1051383D03*
X1041810Y1511084D03*
X1055310D03*
X1059810D03*
X1064310D03*
X1068810D03*
X1073310D03*
X1078683Y1495593D03*
Y1501593D03*
Y1507593D03*
Y1516593D03*
X1051383Y1495593D03*
Y1501593D03*
Y1507593D03*
X1078683Y1522593D03*
X2432929Y1153566D03*
G54D17*
X80019Y51968D03*
X127263Y20472D03*
X631200Y51968D03*
X678444Y20472D03*
X1250689Y51969D03*
X1297933Y20472D03*
X1801870Y51969D03*
X1849114Y20472D03*
X2432929Y365766D03*
G54D26*
X496653Y80906D03*
X1465157D03*
X2432929Y244566D03*
G54D27*
X496653Y110552D03*
X1465157D03*
X2432929Y183966D03*
G54D18*
X111024Y153681D03*
Y606437D03*
Y1059193D03*
X235236Y153681D03*
Y606437D03*
Y1059193D03*
X359449Y153681D03*
Y606437D03*
Y1059193D03*
X483661Y153681D03*
Y606437D03*
Y1059193D03*
X607874Y153681D03*
Y606437D03*
Y1059193D03*
X732087Y153681D03*
Y606437D03*
Y1059193D03*
X949902Y-115157D03*
X1281693Y153681D03*
Y606437D03*
Y1059193D03*
X1405906Y153681D03*
Y606437D03*
Y1059193D03*
X1530118Y153681D03*
Y606437D03*
Y1059193D03*
X1654331Y153681D03*
Y606437D03*
Y1059193D03*
X1778543Y153681D03*
Y606437D03*
Y1059193D03*
X1902756Y153681D03*
Y606437D03*
Y1059193D03*
X2432929Y547566D03*
G54D36*
X1104527Y1630792D03*
X2432929Y850566D03*
G54D37*
G01X363248Y-425196D02*
Y-505196D01*
G01D02*
X1639148D01*
G01X359248Y-409196D02*
G02I-12000J0D01*
G01X354098D02*
G02I-6850J0D01*
G01X347248Y-425196D02*
Y-393196D01*
G01X363248Y-425196D02*
X1639148D01*
G01X363248Y-460696D02*
X1639148D01*
G01X363248Y-409196D02*
X331248D01*
G01X720748Y-425196D02*
Y-505196D01*
G01X858248Y-425196D02*
Y-505196D01*
G01X973248Y-425196D02*
Y-505196D01*
G01X1271648Y-425196D02*
Y-505196D01*
G01X1441648Y-425196D02*
Y-505196D01*
G01X1639148Y-425196D02*
Y-505196D01*
G01X1667148Y-409196D02*
G02I-12000J0D01*
G01X1661998D02*
G02I-6850J0D01*
G01X1655148Y-425196D02*
Y-393196D01*
G01X1671148Y-409196D02*
X1639148D01*
G54D28*
X503248Y829921D03*
X1673917D03*
X2432929Y62766D03*
G54D19*
X111024Y302303D03*
Y755059D03*
Y1207815D03*
X235236Y302303D03*
Y755059D03*
Y1207815D03*
X359449Y302303D03*
Y755059D03*
Y1207815D03*
X483661Y302303D03*
Y755059D03*
Y1207815D03*
X607874Y302303D03*
Y755059D03*
Y1207815D03*
X732087Y302303D03*
Y755059D03*
Y1207815D03*
X1098524Y-115157D03*
X1281693Y302303D03*
Y755059D03*
Y1207815D03*
X1405906Y302303D03*
Y755059D03*
Y1207815D03*
X1530118Y302303D03*
Y755059D03*
Y1207815D03*
X1654331Y302303D03*
Y755059D03*
Y1207815D03*
X1778543Y302303D03*
Y755059D03*
Y1207815D03*
X1902756Y302303D03*
Y755059D03*
Y1207815D03*
X2432929Y486966D03*
G54D38*
G01X23457Y475151D02*
X45107Y482259D01*
G01X27740Y478136D02*
X23457Y475151D01*
X28675Y475286D01*
X27740Y478136D01*
G01X6857Y470459D02*
Y478359D01*
G02X23457I8300J0D01*
G01Y470459D01*
G02X6857I-8300J0D01*
G01X66231Y348700D02*
X67731Y343700D01*
X69231Y348700D01*
X66231D01*
G01X67731Y363873D02*
Y343700D01*
G01X126201D02*
X62731D01*
G01X69231Y394409D02*
X67731Y399409D01*
X66231Y394409D01*
X69231D01*
G01X67731Y374473D02*
Y399409D01*
G01X126201D02*
X62731D01*
G01X67730Y827229D02*
Y852165D01*
G01X66230Y801456D02*
X67730Y796456D01*
X69230Y801456D01*
X66230D01*
G01X67730Y816629D02*
Y796456D01*
G01X126200D02*
X62730D01*
G01X69230Y847165D02*
X67730Y852165D01*
X66230Y847165D01*
X69230D01*
G01X126200Y852165D02*
X62730D01*
G01X126201Y1249212D02*
X62731D01*
G01X67731Y1269385D02*
Y1249212D01*
G01X66231Y1254212D02*
X67731Y1249212D01*
X69231Y1254212D01*
X66231D01*
G01X126201Y1304921D02*
X62731D01*
G01X67731Y1279985D02*
Y1304921D01*
G01X69231Y1299921D02*
X67731Y1304921D01*
X66231Y1299921D01*
X69231D01*
G01X141182Y392016D02*
G03X121221I-9980J-3040D01*
G02X114296Y378885I-37662J11471D01*
G03X148107I16906J-13531D01*
G02X141182Y392016I30737J24602D01*
G01X86370Y383976D02*
X84870Y388976D01*
X83370Y383976D01*
X86370D01*
G01X84870Y382286D02*
Y388976D01*
G01X83370Y370354D02*
X84870Y365354D01*
X86370Y370354D01*
X83370D01*
G01X84870Y371686D02*
Y365354D01*
G01X126201D02*
X79870D01*
G01X126201Y388976D02*
X79870D01*
G01X86369Y836732D02*
X84869Y841732D01*
X83369Y836732D01*
X86369D01*
G01X84869Y835042D02*
Y841732D01*
G01X83369Y823110D02*
X84869Y818110D01*
X86369Y823110D01*
X83369D01*
G01X84869Y824442D02*
Y818110D01*
G01X126200D02*
X79869D01*
G01X141181Y844772D02*
G03X121220I-9980J-3040D01*
G02X114295Y831641I-37662J11471D01*
G03X148106I16905J-13531D01*
G02X141181Y844772I30737J24602D01*
G01X126200Y841732D02*
X79869D01*
G01X141182Y1297528D02*
G03X121221I-9980J-3040D01*
G02X114296Y1284397I-37662J11471D01*
G03X148107I16906J-13531D01*
G02X141182Y1297528I30737J24602D01*
G01X126201Y1270866D02*
X79870D01*
G01X84870Y1277198D02*
Y1270866D01*
G01X83370Y1275866D02*
X84870Y1270866D01*
X86370Y1275866D01*
X83370D01*
G01X126201Y1294488D02*
X79870D01*
G01X84870Y1287798D02*
Y1294488D01*
G01X86370Y1289488D02*
X84870Y1294488D01*
X83370Y1289488D01*
X86370D01*
G01X147637Y351256D02*
X165018Y336349D01*
G01X152409Y349140D02*
X147637Y351256D01*
X150456Y346862D01*
X152409Y349140D01*
G01X169398Y339725D02*
X165398Y333725D01*
G01X169398Y336725D02*
G03I-2000J0D01*
G01X139332Y395514D02*
X167177Y417904D01*
G01X142289Y399816D02*
X139332Y395514D01*
X144168Y397478D01*
X142289Y399816D01*
G01X152493Y369299D02*
X164865Y378945D01*
G01X155514Y373556D02*
X152493Y369299D01*
X157358Y371190D01*
X155514Y373556D01*
G01X171557Y420716D02*
X167557Y414716D01*
G01X171557Y417716D02*
G03I-2000J0D01*
G01X147636Y804012D02*
X165017Y789105D01*
G01X169397Y792481D02*
X165397Y786481D01*
G01X169397Y789481D02*
G03I-2000J0D01*
G01X152408Y801896D02*
X147636Y804012D01*
X150455Y799618D01*
X152408Y801896D01*
G01X152492Y822055D02*
X164864Y831701D01*
G01X155513Y826312D02*
X152492Y822055D01*
X157357Y823946D01*
X155513Y826312D01*
G01X139331Y848270D02*
X167176Y870660D01*
G01X142288Y852572D02*
X139331Y848270D01*
X144167Y850234D01*
X142288Y852572D01*
G01X171556Y873472D02*
X167556Y867472D01*
G01X171556Y870472D02*
G03I-2000J0D01*
G01X155514Y1279068D02*
X152493Y1274811D01*
X157358Y1276702D01*
X155514Y1279068D01*
G01X152493Y1274811D02*
X164865Y1284457D01*
G01X169398Y1242237D02*
G03I-2000J0D01*
G01Y1245237D02*
X165398Y1239237D01*
G01X152409Y1254652D02*
X147637Y1256768D01*
X150456Y1252374D01*
X152409Y1254652D01*
G01X147637Y1256768D02*
X165018Y1241861D01*
G01X171557Y1323228D02*
G03I-2000J0D01*
G01Y1326228D02*
X167557Y1320228D01*
G01X142289Y1305328D02*
X139332Y1301026D01*
X144168Y1302990D01*
X142289Y1305328D01*
G01X139332Y1301026D02*
X167177Y1323416D01*
G01X374232Y343700D02*
X310762D01*
G01X374232Y399409D02*
X310762D01*
G01X374232Y796456D02*
X310762D01*
G01X374232Y852165D02*
X310762D01*
G01X374232Y1249212D02*
X310762D01*
G01X374232Y1304921D02*
X310762D01*
G01X389213Y392016D02*
G03X369252I-9981J-3040D01*
G02X362327Y378885I-37662J11471D01*
G03X396138I16905J-13531D01*
G02X389213Y392016I30737J24602D01*
G01X315762Y363873D02*
Y343700D01*
G01X314262Y348700D02*
X315762Y343700D01*
X317262Y348700D01*
X314262D01*
G01X374232Y388976D02*
X327901D01*
G01X374232Y365354D02*
X327901D01*
G01X332901Y371686D02*
Y365354D01*
G01X331401Y370354D02*
X332901Y365354D01*
X334401Y370354D01*
X331401D01*
G01X332901Y382286D02*
Y388976D01*
G01X334401Y383976D02*
X332901Y388976D01*
X331401Y383976D01*
X334401D01*
G01X315762Y374473D02*
Y399409D01*
G01X317262Y394409D02*
X315762Y399409D01*
X314262Y394409D01*
X317262D01*
G01X315762Y827229D02*
Y852165D01*
G01X314262Y801456D02*
X315762Y796456D01*
X317262Y801456D01*
X314262D01*
G01X315762Y816629D02*
Y796456D01*
G01X334401Y836732D02*
X332901Y841732D01*
X331401Y836732D01*
X334401D01*
G01X332901Y835042D02*
Y841732D01*
G01X331401Y823110D02*
X332901Y818110D01*
X334401Y823110D01*
X331401D01*
G01X332901Y824442D02*
Y818110D01*
G01X374232D02*
X327901D01*
G01X389213Y844772D02*
G03X369252I-9981J-3040D01*
G02X362327Y831641I-37662J11471D01*
G03X396138I16905J-13531D01*
G02X389213Y844772I30737J24602D01*
G01X317262Y847165D02*
X315762Y852165D01*
X314262Y847165D01*
X317262D01*
G01X374232Y841732D02*
X327901D01*
G01X314262Y1254212D02*
X315762Y1249212D01*
X317262Y1254212D01*
X314262D01*
G01X315762Y1269385D02*
Y1249212D01*
G01X331401Y1275866D02*
X332901Y1270866D01*
X334401Y1275866D01*
X331401D01*
G01X332901Y1277198D02*
Y1270866D01*
G01X374232D02*
X327901D01*
G01X389213Y1297528D02*
G03X369252I-9981J-3040D01*
G02X362327Y1284397I-37662J11471D01*
G03X396138I16905J-13531D01*
G02X389213Y1297528I30737J24602D01*
G01X317262Y1299921D02*
X315762Y1304921D01*
X314262Y1299921D01*
X317262D01*
G01X315762Y1279985D02*
Y1304921D01*
G01X334401Y1289488D02*
X332901Y1294488D01*
X331401Y1289488D01*
X334401D01*
G01X332901Y1287798D02*
Y1294488D01*
G01X374232D02*
X327901D01*
G01X394744Y-485863D02*
X395618Y-484988D01*
X396273Y-483530D01*
X396710Y-481487D01*
X396273Y-479738D01*
X395400Y-478571D01*
X393871Y-477696D01*
X387976D01*
Y-495196D01*
X395181D01*
X396710Y-494030D01*
X397583Y-492279D01*
X398020Y-490238D01*
X397583Y-488196D01*
X396273Y-486446D01*
X394744Y-485863D01*
X387976D01*
G01X407441Y-495196D02*
Y-483530D01*
G01Y-485863D02*
X408533Y-484696D01*
X409625Y-483821D01*
X411153Y-483530D01*
X412244Y-483821D01*
X413555Y-484696D01*
G01X423413Y-500446D02*
X424723Y-501029D01*
X426470Y-500446D01*
X427561Y-499280D01*
X428435Y-497821D01*
X429744Y-493155D01*
X432583Y-483530D01*
G01X425596D02*
X429744Y-493155D01*
G01X448991Y-484988D02*
X447463Y-483821D01*
X446153Y-483530D01*
X444406Y-484113D01*
X443096Y-485279D01*
X442223Y-487321D01*
X442004Y-489363D01*
X442223Y-491405D01*
X443096Y-493155D01*
X444406Y-494613D01*
X446153Y-495196D01*
X447681Y-494613D01*
X448991Y-493446D01*
G01X459723Y-487321D02*
X466710D01*
X466055Y-485279D01*
X464963Y-484113D01*
X463435Y-483530D01*
X461906Y-483821D01*
X460596Y-484696D01*
X459723Y-486738D01*
X459286Y-488488D01*
Y-490238D01*
X459723Y-491988D01*
X460815Y-493738D01*
X462125Y-494904D01*
X463653Y-495196D01*
X465181Y-494613D01*
X466710Y-492863D01*
G01X502801Y-479155D02*
X501491Y-478279D01*
X499963Y-477696D01*
X498216D01*
X496251Y-478571D01*
X494723Y-480029D01*
X493631Y-481780D01*
X492758Y-484696D01*
X492539Y-487321D01*
X492976Y-489946D01*
X493631Y-491696D01*
X494941Y-493446D01*
X496470Y-494613D01*
X497998Y-495196D01*
X499526D01*
X501055Y-494613D01*
X502365Y-493738D01*
X503457Y-492572D01*
G01X519428Y-495196D02*
Y-483530D01*
G01Y-485571D02*
X518555Y-484405D01*
X517244Y-483821D01*
X515716Y-483530D01*
X514188Y-484113D01*
X512878Y-485279D01*
X512004Y-487029D01*
X511568Y-489363D01*
X512004Y-491696D01*
X512878Y-493446D01*
X514188Y-494613D01*
X515716Y-495196D01*
X517244Y-494904D01*
X518555Y-494030D01*
X519428Y-492863D01*
G01X529286Y-495196D02*
Y-483530D01*
G01Y-486446D02*
X530160Y-484988D01*
X531470Y-483821D01*
X533216Y-483530D01*
X534744Y-483821D01*
X536055Y-484988D01*
X536710Y-487029D01*
Y-495196D01*
G01X545913Y-500446D02*
X547223Y-501029D01*
X548970Y-500446D01*
X550061Y-499280D01*
X550935Y-497821D01*
X552244Y-493155D01*
X555083Y-483530D01*
G01X548096D02*
X552244Y-493155D01*
G01X567998Y-495196D02*
X566688Y-494904D01*
X565378Y-493738D01*
X564504Y-491696D01*
X564068Y-489363D01*
X564504Y-487029D01*
X565378Y-484988D01*
X566688Y-483821D01*
X567998Y-483530D01*
X569308Y-483821D01*
X570618Y-484988D01*
X571491Y-487029D01*
X571710Y-489363D01*
X571491Y-491696D01*
X570618Y-493738D01*
X569308Y-494904D01*
X567998Y-495196D01*
G01X581786D02*
Y-483530D01*
G01Y-486446D02*
X582660Y-484988D01*
X583970Y-483821D01*
X585716Y-483530D01*
X587244Y-483821D01*
X588555Y-484988D01*
X589210Y-487029D01*
Y-495196D01*
G01X616350D02*
Y-477696D01*
X624646D01*
G01X621590Y-486154D02*
X616350D01*
G01X637998Y-495779D02*
X637561Y-495488D01*
Y-494904D01*
X637998Y-494613D01*
X638435Y-494904D01*
Y-495488D01*
X637998Y-495779D01*
G01X650695Y-495196D02*
Y-477696D01*
X655061D01*
X656808Y-478571D01*
X658118Y-479738D01*
X659210Y-481487D01*
X660083Y-483530D01*
X660301Y-486446D01*
X660083Y-489363D01*
X659210Y-491405D01*
X658118Y-493155D01*
X656808Y-494321D01*
X655061Y-495196D01*
X650695D01*
G01X668631D02*
Y-477696D01*
X673871D01*
X675618Y-478571D01*
X676928Y-480613D01*
X677365Y-482946D01*
X676928Y-485279D01*
X675836Y-487029D01*
X673871Y-487905D01*
X668631D01*
G01X692244Y-485863D02*
X693118Y-484988D01*
X693773Y-483530D01*
X694210Y-481487D01*
X693773Y-479738D01*
X692900Y-478571D01*
X691371Y-477696D01*
X685476D01*
Y-495196D01*
X692681D01*
X694210Y-494030D01*
X695083Y-492279D01*
X695520Y-490238D01*
X695083Y-488196D01*
X693773Y-486446D01*
X692244Y-485863D01*
X685476D01*
G01X400440Y349140D02*
X395668Y351256D01*
X398487Y346862D01*
X400440Y349140D01*
G01X395668Y351256D02*
X413049Y336349D01*
G01X403545Y373556D02*
X400524Y369299D01*
X405389Y371190D01*
X403545Y373556D01*
G01X400524Y369299D02*
X412896Y378945D01*
G01X390320Y399816D02*
X387363Y395514D01*
X392199Y397478D01*
X390320Y399816D01*
G01X387363Y395514D02*
X415208Y417904D01*
G01X395668Y804012D02*
X413049Y789105D01*
G01X400440Y801896D02*
X395668Y804012D01*
X398487Y799618D01*
X400440Y801896D01*
G01X400524Y822055D02*
X412896Y831701D01*
G01X403545Y826312D02*
X400524Y822055D01*
X405389Y823946D01*
X403545Y826312D01*
G01X387363Y848270D02*
X415208Y870660D01*
G01X390320Y852572D02*
X387363Y848270D01*
X392199Y850234D01*
X390320Y852572D01*
G01X395668Y1256768D02*
X413049Y1241861D01*
G01X400440Y1254652D02*
X395668Y1256768D01*
X398487Y1252374D01*
X400440Y1254652D01*
G01X400524Y1274811D02*
X412896Y1284457D01*
G01X403545Y1279068D02*
X400524Y1274811D01*
X405389Y1276702D01*
X403545Y1279068D01*
G01X387363Y1301026D02*
X415208Y1323416D01*
G01X390320Y1305328D02*
X387363Y1301026D01*
X392199Y1302990D01*
X390320Y1305328D01*
G01X417429Y336725D02*
G03I-2000J0D01*
G01Y339725D02*
X413429Y333725D01*
G01X419588Y417716D02*
G03I-2000J0D01*
G01Y420716D02*
X415588Y414716D01*
G01X417429Y792481D02*
X413429Y786481D01*
G01X417429Y789481D02*
G03I-2000J0D01*
G01X419588Y873472D02*
X415588Y867472D01*
G01X419588Y870472D02*
G03I-2000J0D01*
G01X417429Y1245237D02*
X413429Y1239237D01*
G01X417429Y1242237D02*
G03I-2000J0D01*
G01X419588Y1326228D02*
X415588Y1320228D01*
G01X419588Y1323228D02*
G03I-2000J0D01*
G01X501071Y-450196D02*
Y-432696D01*
X506748Y-447279D01*
X512425Y-432696D01*
Y-450196D01*
G01X524248D02*
X522938Y-449904D01*
X521628Y-448738D01*
X520754Y-446696D01*
X520318Y-444363D01*
X520754Y-442029D01*
X521628Y-439988D01*
X522938Y-438821D01*
X524248Y-438530D01*
X525558Y-438821D01*
X526868Y-439988D01*
X527741Y-442029D01*
X527960Y-444363D01*
X527741Y-446696D01*
X526868Y-448738D01*
X525558Y-449904D01*
X524248Y-450196D01*
G01X545678Y-432696D02*
Y-450196D01*
G01Y-447572D02*
X544805Y-449030D01*
X543494Y-449904D01*
X541966Y-450196D01*
X540220Y-449613D01*
X538910Y-448155D01*
X538036Y-446405D01*
X537818Y-444363D01*
X538036Y-442321D01*
X538910Y-440571D01*
X540220Y-439113D01*
X541966Y-438530D01*
X543494Y-438821D01*
X544586Y-439405D01*
X545678Y-440571D01*
G01X555973Y-442321D02*
X562960D01*
X562305Y-440279D01*
X561213Y-439113D01*
X559685Y-438530D01*
X558156Y-438821D01*
X556846Y-439696D01*
X555973Y-441738D01*
X555536Y-443488D01*
Y-445238D01*
X555973Y-446988D01*
X557065Y-448738D01*
X558375Y-449904D01*
X559903Y-450196D01*
X561431Y-449613D01*
X562960Y-447863D01*
G01X576748Y-450196D02*
Y-432696D01*
G01X622263Y343700D02*
X558793D01*
G01X563793Y363873D02*
Y343700D01*
G01X562293Y348700D02*
X563793Y343700D01*
X565293Y348700D01*
X562293D01*
G01X622263Y388976D02*
X575932D01*
G01X622263Y365354D02*
X575932D01*
G01X580932Y371686D02*
Y365354D01*
G01X579432Y370354D02*
X580932Y365354D01*
X582432Y370354D01*
X579432D01*
G01X580932Y382286D02*
Y388976D01*
G01X582432Y383976D02*
X580932Y388976D01*
X579432Y383976D01*
X582432D01*
G01X622263Y399409D02*
X558793D01*
G01X563793Y374473D02*
Y399409D01*
G01X565293Y394409D02*
X563793Y399409D01*
X562293Y394409D01*
X565293D01*
G01X563793Y827229D02*
Y852165D01*
G01X562293Y801456D02*
X563793Y796456D01*
X565293Y801456D01*
X562293D01*
G01X563793Y816629D02*
Y796456D01*
G01X622263D02*
X558793D01*
G01X582432Y836732D02*
X580932Y841732D01*
X579432Y836732D01*
X582432D01*
G01X580932Y835042D02*
Y841732D01*
G01X579432Y823110D02*
X580932Y818110D01*
X582432Y823110D01*
X579432D01*
G01X580932Y824442D02*
Y818110D01*
G01X622263D02*
X575932D01*
G01X565293Y847165D02*
X563793Y852165D01*
X562293Y847165D01*
X565293D01*
G01X622263Y852165D02*
X558793D01*
G01X622263Y841732D02*
X575932D01*
G01X562293Y1254212D02*
X563793Y1249212D01*
X565293Y1254212D01*
X562293D01*
G01X563793Y1269385D02*
Y1249212D01*
G01X622263D02*
X558793D01*
G01X579432Y1275866D02*
X580932Y1270866D01*
X582432Y1275866D01*
X579432D01*
G01X580932Y1277198D02*
Y1270866D01*
G01X622263D02*
X575932D01*
G01X565293Y1299921D02*
X563793Y1304921D01*
X562293Y1299921D01*
X565293D01*
G01X563793Y1279985D02*
Y1304921D01*
G01X622263D02*
X558793D01*
G01X582432Y1289488D02*
X580932Y1294488D01*
X579432Y1289488D01*
X582432D01*
G01X580932Y1287798D02*
Y1294488D01*
G01X622263D02*
X575932D01*
G01X637244Y392016D02*
G03X617283I-9980J-3040D01*
G02X610358Y378885I-37662J11471D01*
G03X644169I16906J-13531D01*
G02X637244Y392016I30737J24602D01*
G01X648471Y349140D02*
X643699Y351256D01*
X646518Y346862D01*
X648471Y349140D01*
G01X643699Y351256D02*
X661080Y336349D01*
G01X651576Y373556D02*
X648555Y369299D01*
X653420Y371190D01*
X651576Y373556D01*
G01X648555Y369299D02*
X660927Y378945D01*
G01X638351Y399816D02*
X635394Y395514D01*
X640230Y397478D01*
X638351Y399816D01*
G01X635394Y395514D02*
X663239Y417904D01*
G01X643699Y804012D02*
X661080Y789105D01*
G01X648471Y801896D02*
X643699Y804012D01*
X646518Y799618D01*
X648471Y801896D01*
G01X648555Y822055D02*
X660927Y831701D01*
G01X651576Y826312D02*
X648555Y822055D01*
X653420Y823946D01*
X651576Y826312D01*
G01X637244Y844772D02*
G03X617283I-9980J-3040D01*
G02X610358Y831641I-37662J11471D01*
G03X644169I16906J-13531D01*
G02X637244Y844772I30737J24602D01*
G01X635394Y848270D02*
X663239Y870660D01*
G01X638351Y852572D02*
X635394Y848270D01*
X640230Y850234D01*
X638351Y852572D01*
G01X643699Y1256768D02*
X661080Y1241861D01*
G01X648471Y1254652D02*
X643699Y1256768D01*
X646518Y1252374D01*
X648471Y1254652D01*
G01X648555Y1274811D02*
X660927Y1284457D01*
G01X651576Y1279068D02*
X648555Y1274811D01*
X653420Y1276702D01*
X651576Y1279068D01*
G01X637244Y1297528D02*
G03X617283I-9980J-3040D01*
G02X610358Y1284397I-37662J11471D01*
G03X644169I16906J-13531D01*
G02X637244Y1297528I30737J24602D01*
G01X635394Y1301026D02*
X663239Y1323416D01*
G01X638351Y1305328D02*
X635394Y1301026D01*
X640230Y1302990D01*
X638351Y1305328D01*
G01X665460Y336725D02*
G03I-2000J0D01*
G01Y339725D02*
X661460Y333725D01*
G01X667619Y417716D02*
G03I-2000J0D01*
G01Y420716D02*
X663619Y414716D01*
G01X665460Y792481D02*
X661460Y786481D01*
G01X665460Y789481D02*
G03I-2000J0D01*
G01X667619Y873472D02*
X663619Y867472D01*
G01X667619Y870472D02*
G03I-2000J0D01*
G01X665460Y1245237D02*
X661460Y1239237D01*
G01X665460Y1242237D02*
G03I-2000J0D01*
G01X667619Y1326228D02*
X663619Y1320228D01*
G01X667619Y1323228D02*
G03I-2000J0D01*
G01X754448Y-495196D02*
Y-477696D01*
X751828Y-481196D01*
G01Y-495196D02*
X757068D01*
G01X767800Y-487905D02*
X769328Y-485863D01*
X770638Y-484696D01*
X772385Y-484113D01*
X773913Y-484696D01*
X775005Y-485863D01*
X775878Y-487613D01*
X776096Y-489654D01*
X775878Y-491405D01*
X775005Y-493155D01*
X773694Y-494613D01*
X772166Y-495196D01*
X770420Y-494613D01*
X768891Y-492863D01*
X768018Y-490238D01*
X767800Y-487321D01*
X768236Y-483530D01*
X768891Y-481487D01*
X769983Y-479446D01*
X771511Y-477988D01*
X773040Y-477696D01*
X774568Y-478279D01*
X775660Y-479738D01*
G01X784645Y-491696D02*
X785954Y-493738D01*
X787701Y-494904D01*
X789666Y-495196D01*
X791413Y-494904D01*
X793160Y-493446D01*
X794251Y-491696D01*
X794470Y-489946D01*
X794033Y-487905D01*
X792505Y-486446D01*
X790976Y-485863D01*
X789011D01*
G01X790976D02*
X792286Y-484988D01*
X793378Y-483530D01*
X793815Y-481780D01*
X793378Y-480029D01*
X792286Y-478571D01*
X790321Y-477696D01*
X788356Y-477988D01*
X786391Y-479155D01*
G01X806948Y-495196D02*
Y-477696D01*
X804328Y-481196D01*
G01Y-495196D02*
X809568D01*
G01X819645Y-492572D02*
X820954Y-494030D01*
X822483Y-494904D01*
X824448Y-495196D01*
X826413Y-494613D01*
X827941Y-493446D01*
X829033Y-491405D01*
X829251Y-489071D01*
X828815Y-486738D01*
X827723Y-485279D01*
X826194Y-484113D01*
X824666Y-483821D01*
X823138Y-484113D01*
X821173Y-485279D01*
X821828Y-477696D01*
X827723D01*
G01X741331Y-450196D02*
Y-432696D01*
X746571D01*
X748318Y-433571D01*
X749628Y-435613D01*
X750065Y-437946D01*
X749628Y-440279D01*
X748536Y-442029D01*
X746571Y-442905D01*
X741331D01*
G01X768001Y-434155D02*
X766691Y-433279D01*
X765163Y-432696D01*
X763416D01*
X761451Y-433571D01*
X759923Y-435029D01*
X758831Y-436780D01*
X757958Y-439696D01*
X757739Y-442321D01*
X758176Y-444946D01*
X758831Y-446696D01*
X760141Y-448446D01*
X761670Y-449613D01*
X763198Y-450196D01*
X764726D01*
X766255Y-449613D01*
X767565Y-448738D01*
X768657Y-447572D01*
G01X782444Y-440863D02*
X783318Y-439988D01*
X783973Y-438530D01*
X784410Y-436487D01*
X783973Y-434738D01*
X783100Y-433571D01*
X781571Y-432696D01*
X775676D01*
Y-450196D01*
X782881D01*
X784410Y-449030D01*
X785283Y-447279D01*
X785720Y-445238D01*
X785283Y-443196D01*
X783973Y-441446D01*
X782444Y-440863D01*
X775676D01*
G01X791648Y-456029D02*
X804748D01*
G01X810676Y-450196D02*
Y-432696D01*
X820720Y-450196D01*
Y-432696D01*
G01X833198Y-450196D02*
X831451Y-449904D01*
X829923Y-448738D01*
X828613Y-446988D01*
X827739Y-444946D01*
X827303Y-442613D01*
Y-440279D01*
X827739Y-437946D01*
X828613Y-435904D01*
X829923Y-434155D01*
X831451Y-432988D01*
X833198Y-432696D01*
X834944Y-432988D01*
X836473Y-434155D01*
X837783Y-435904D01*
X838657Y-437946D01*
X839093Y-440279D01*
Y-442613D01*
X838657Y-444946D01*
X837783Y-446988D01*
X836473Y-448738D01*
X834944Y-449904D01*
X833198Y-450196D01*
G01X732987Y260322D02*
Y285258D01*
G01X731487Y234549D02*
X732987Y229549D01*
X734487Y234549D01*
X731487D01*
G01X732987Y249722D02*
Y229549D01*
G01X791457D02*
X727987D01*
G01X748626Y256203D02*
X750126Y251203D01*
X751626Y256203D01*
X748626D01*
G01X791457Y251203D02*
X745126D01*
G01X734487Y280258D02*
X732987Y285258D01*
X731487Y280258D01*
X734487D01*
G01X791457Y285258D02*
X727987D01*
G01X751626Y269825D02*
X750126Y274825D01*
X748626Y269825D01*
X751626D01*
G01X791457Y274825D02*
X745126D01*
G01X732987Y732763D02*
Y757699D01*
G01X731487Y706990D02*
X732987Y701990D01*
X734487Y706990D01*
X731487D01*
G01X732987Y722163D02*
Y701990D01*
G01X791457D02*
X727987D01*
G01X751626Y742266D02*
X750126Y747266D01*
X748626Y742266D01*
X751626D01*
G01X748626Y728644D02*
X750126Y723644D01*
X751626Y728644D01*
X748626D01*
G01X791457Y723644D02*
X745126D01*
G01X734487Y752699D02*
X732987Y757699D01*
X731487Y752699D01*
X734487D01*
G01X791457Y757699D02*
X727987D01*
G01X791457Y747266D02*
X745126D01*
G01X750126Y257535D02*
Y251203D01*
G01X806438Y277865D02*
G03X786477I-9980J-3040D01*
G02X779552Y264734I-37662J11471D01*
G03X813363I16905J-13531D01*
G02X806438Y277865I30737J24602D01*
G01X750126Y268135D02*
Y274825D01*
G01Y740576D02*
Y747266D01*
G01Y729976D02*
Y723644D01*
G01X806438Y750306D02*
G03X786477I-9980J-3040D01*
G02X779552Y737175I-37662J11471D01*
G03X813363I16905J-13531D01*
G02X806438Y750306I30737J24602D01*
G01X812893Y237105D02*
X830274Y222198D01*
G01X817665Y234989D02*
X812893Y237105D01*
X815712Y232711D01*
X817665Y234989D01*
G01X834654Y225574D02*
X830654Y219574D01*
G01X834654Y222574D02*
G03I-2000J0D01*
G01X817749Y255148D02*
X830121Y264794D01*
G01X820770Y259405D02*
X817749Y255148D01*
X822614Y257039D01*
X820770Y259405D01*
G01X804588Y281363D02*
X832433Y303753D01*
G01X807545Y285665D02*
X804588Y281363D01*
X809424Y283327D01*
X807545Y285665D01*
G01X836813Y306565D02*
X832813Y300565D01*
G01X836813Y303565D02*
G03I-2000J0D01*
G01X812893Y709546D02*
X830274Y694639D01*
G01X834654Y698015D02*
X830654Y692015D01*
G01X834654Y695015D02*
G03I-2000J0D01*
G01X817665Y707430D02*
X812893Y709546D01*
X815712Y705152D01*
X817665Y707430D01*
G01X817749Y727589D02*
X830121Y737235D01*
G01X820770Y731846D02*
X817749Y727589D01*
X822614Y729480D01*
X820770Y731846D01*
G01X804588Y753804D02*
X832433Y776194D01*
G01X807545Y758106D02*
X804588Y753804D01*
X809424Y755768D01*
X807545Y758106D01*
G01X836813Y779006D02*
X832813Y773006D01*
G01X836813Y776006D02*
G03I-2000J0D01*
G01X884039Y-432696D02*
X889498Y-450196D01*
X894957Y-432696D01*
G01X911365Y-450196D02*
X902631D01*
Y-432696D01*
X911365D01*
G01X907871Y-441154D02*
X902631D01*
G01X920131Y-450196D02*
Y-432696D01*
X925590D01*
X927336Y-433571D01*
X928428Y-434738D01*
X928865Y-437071D01*
X928428Y-439405D01*
X927118Y-440863D01*
X925590Y-441738D01*
X920131D01*
G01X925590D02*
X928865Y-450196D01*
G01X941998Y-450779D02*
X941561Y-450488D01*
Y-449904D01*
X941998Y-449613D01*
X942435Y-449904D01*
Y-450488D01*
X941998Y-450779D01*
G01X884133Y-86731D02*
X885633Y-91731D01*
X887133Y-86731D01*
X884133D01*
G01X885633Y-71059D02*
Y-91731D01*
G01X939883D02*
X880633D01*
G01X887133Y-41022D02*
X885633Y-36022D01*
X884133Y-41022D01*
X887133D01*
G01X885633Y-60459D02*
Y-36022D01*
G01X939883D02*
X880633D01*
G01X956418Y1053959D02*
X892948D01*
G01X956418Y1109668D02*
X892948D01*
G01X956418Y1396478D02*
X892948D01*
G01X956418Y1452187D02*
X892948D01*
G01X915748Y-495196D02*
Y-477696D01*
X913128Y-481196D01*
G01Y-495196D02*
X918368D01*
G01X962732Y-57819D02*
G02X927033I-17849J-12259D01*
G03X935200Y-42570I-64908J44575D01*
G02X954566I9683J-3885D01*
G03X962732Y-57819I73076J29322D01*
G01X896621Y-29541D02*
Y-21641D01*
G02X913221I8300J0D01*
G01Y-29541D01*
G02X896621I-8300J0D01*
G01X903328Y-51455D02*
X901828Y-46455D01*
X900328Y-51455D01*
X903328D01*
G01X901828Y-52737D02*
Y-46455D01*
G01X900328Y-65078D02*
X901828Y-70078D01*
X903328Y-65078D01*
X900328D01*
G01X901828Y-63337D02*
Y-70078D01*
G01X939882D02*
X896828D01*
G01X939883Y-46455D02*
X896828D01*
G01X913221Y-24849D02*
X934871Y-17741D01*
G01X917504Y-21864D02*
X913221Y-24849D01*
X918439Y-24714D01*
X917504Y-21864D01*
G01X896448Y1058959D02*
X897948Y1053959D01*
X899448Y1058959D01*
X896448D01*
G01X897948Y1074132D02*
Y1053959D01*
G01X913587Y1080613D02*
X915087Y1075613D01*
X916587Y1080613D01*
X913587D01*
G01X915087Y1081945D02*
Y1075613D01*
G01X956418D02*
X910087D01*
G01X971399Y1102275D02*
G03X951438I-9981J-3040D01*
G02X944513Y1089144I-37662J11471D01*
G03X978324I16906J-13531D01*
G02X971399Y1102275I30737J24602D01*
G01X899448Y1104668D02*
X897948Y1109668D01*
X896448Y1104668D01*
X899448D01*
G01X897948Y1084732D02*
Y1109668D01*
G01X916587Y1094235D02*
X915087Y1099235D01*
X913587Y1094235D01*
X916587D01*
G01X915087Y1092545D02*
Y1099235D01*
G01X956418D02*
X910087D01*
G01X896448Y1401478D02*
X897948Y1396478D01*
X899448Y1401478D01*
X896448D01*
G01X897948Y1416651D02*
Y1396478D01*
G01X913587Y1423132D02*
X915087Y1418132D01*
X916587Y1423132D01*
X913587D01*
G01X915087Y1424464D02*
Y1418132D01*
G01X956418D02*
X910087D01*
G01X971399Y1444794D02*
G03X951438I-9981J-3040D01*
G02X944513Y1431663I-37662J11471D01*
G03X978324I16906J-13531D01*
G02X971399Y1444794I30737J24602D01*
G01X899448Y1447187D02*
X897948Y1452187D01*
X896448Y1447187D01*
X899448D01*
G01X897948Y1427251D02*
Y1452187D01*
G01X916587Y1436754D02*
X915087Y1441754D01*
X913587Y1436754D01*
X916587D01*
G01X915087Y1435064D02*
Y1441754D01*
G01X956418D02*
X910087D01*
G01X965534Y-76590D02*
X978462Y-80667D01*
X982425D01*
G01X970754Y-76663D02*
X965534Y-76590D01*
X969851Y-79524D01*
X970754Y-76663D01*
G01X989425Y-77667D02*
X985425Y-83667D01*
G01X989425Y-80667D02*
G03I-2000J0D01*
G01X969837Y-29490D02*
Y-21690D01*
G02X981737I5950J0D01*
G01Y-29490D01*
G02X969837I-5950J0D01*
G01X953538Y-40629D02*
X978609Y-23753D01*
X979912Y-23743D01*
G01X956848Y-36593D02*
X953538Y-40629D01*
X958523Y-39081D01*
X956848Y-36593D01*
G01X966527Y-69446D02*
X979209Y-64292D01*
G01X970594Y-66174D02*
X966527Y-69446D01*
X971724Y-68953D01*
X970594Y-66174D01*
G01X981737Y-25498D02*
X1003387Y-18390D01*
G01X986020Y-22513D02*
X981737Y-25498D01*
X986955Y-25363D01*
X986020Y-22513D01*
G01X986912Y-20605D02*
X982912Y-26605D01*
G01X986912Y-23605D02*
G03I-2000J0D01*
G01X977854Y1061515D02*
X995235Y1046608D01*
G01X982626Y1059399D02*
X977854Y1061515D01*
X980673Y1057121D01*
X982626Y1059399D01*
G01X982710Y1079558D02*
X995082Y1089204D01*
G01X985731Y1083815D02*
X982710Y1079558D01*
X987575Y1081449D01*
X985731Y1083815D01*
G01X969549Y1105773D02*
X997394Y1128163D01*
G01X972506Y1110075D02*
X969549Y1105773D01*
X974385Y1107737D01*
X972506Y1110075D01*
G01X977854Y1404034D02*
X995235Y1389127D01*
G01X982626Y1401918D02*
X977854Y1404034D01*
X980673Y1399640D01*
X982626Y1401918D01*
G01X969549Y1448292D02*
X997394Y1470682D01*
G01X972506Y1452594D02*
X969549Y1448292D01*
X974385Y1450256D01*
X972506Y1452594D01*
G01X982710Y1422077D02*
X995082Y1431723D01*
G01X985731Y1426334D02*
X982710Y1422077D01*
X987575Y1423968D01*
X985731Y1426334D01*
G01X999615Y1049984D02*
X995615Y1043984D01*
G01X999615Y1046984D02*
G03I-2000J0D01*
G01X1001774Y1130975D02*
X997774Y1124975D01*
G01X1001774Y1127975D02*
G03I-2000J0D01*
G01X999615Y1392503D02*
X995615Y1386503D01*
G01X999615Y1389503D02*
G03I-2000J0D01*
G01X1001774Y1473494D02*
X997774Y1467494D01*
G01X1001774Y1470494D02*
G03I-2000J0D01*
G01X1082545Y-495196D02*
Y-477696D01*
X1086911D01*
X1088658Y-478571D01*
X1089968Y-479738D01*
X1091060Y-481487D01*
X1091933Y-483530D01*
X1092151Y-486446D01*
X1091933Y-489363D01*
X1091060Y-491405D01*
X1089968Y-493155D01*
X1088658Y-494321D01*
X1086911Y-495196D01*
X1082545D01*
G01X1100481D02*
Y-477696D01*
X1105940D01*
X1107686Y-478571D01*
X1108778Y-479738D01*
X1109215Y-482071D01*
X1108778Y-484405D01*
X1107468Y-485863D01*
X1105940Y-486738D01*
X1100481D01*
G01X1105940D02*
X1109215Y-495196D01*
G01X1119728Y-477696D02*
X1124968D01*
G01X1122348D02*
Y-495196D01*
G01X1119728D02*
X1124968D01*
G01X1135481Y-477696D02*
Y-495196D01*
X1144215D01*
G01X1152981Y-477696D02*
Y-495196D01*
X1161715D01*
G01X1082981Y-432696D02*
Y-450196D01*
X1091715D01*
G01X1108778D02*
Y-438530D01*
G01Y-440571D02*
X1107905Y-439405D01*
X1106594Y-438821D01*
X1105066Y-438530D01*
X1103538Y-439113D01*
X1102228Y-440279D01*
X1101354Y-442029D01*
X1100918Y-444363D01*
X1101354Y-446696D01*
X1102228Y-448446D01*
X1103538Y-449613D01*
X1105066Y-450196D01*
X1106594Y-449904D01*
X1107905Y-449030D01*
X1108778Y-447863D01*
G01X1117763Y-455446D02*
X1119073Y-456029D01*
X1120820Y-455446D01*
X1121911Y-454280D01*
X1122785Y-452821D01*
X1124094Y-448155D01*
X1126933Y-438530D01*
G01X1119946D02*
X1124094Y-448155D01*
G01X1136573Y-442321D02*
X1143560D01*
X1142905Y-440279D01*
X1141813Y-439113D01*
X1140285Y-438530D01*
X1138756Y-438821D01*
X1137446Y-439696D01*
X1136573Y-441738D01*
X1136136Y-443488D01*
Y-445238D01*
X1136573Y-446988D01*
X1137665Y-448738D01*
X1138975Y-449904D01*
X1140503Y-450196D01*
X1142031Y-449613D01*
X1143560Y-447863D01*
G01X1154291Y-450196D02*
Y-438530D01*
G01Y-440863D02*
X1155383Y-439696D01*
X1156475Y-438821D01*
X1158003Y-438530D01*
X1159094Y-438821D01*
X1160405Y-439696D01*
G01X1116920Y527463D02*
X1118420Y522463D01*
X1119920Y527463D01*
X1116920D01*
G01X1118420Y542636D02*
Y522463D01*
G01X1176890D02*
X1113420D01*
G01X1134059Y549117D02*
X1135559Y544117D01*
X1137059Y549117D01*
X1134059D01*
G01X1135559Y550449D02*
Y544117D01*
G01X1176890D02*
X1130559D01*
G01X1119920Y573172D02*
X1118420Y578172D01*
X1116920Y573172D01*
X1119920D01*
G01X1118420Y553236D02*
Y578172D01*
G01X1176890D02*
X1113420D01*
G01X1137059Y562739D02*
X1135559Y567739D01*
X1134059Y562739D01*
X1137059D01*
G01X1135559Y561049D02*
Y567739D01*
G01X1176890D02*
X1130559D01*
G01X1116900Y940826D02*
X1118400Y935826D01*
X1119900Y940826D01*
X1116900D01*
G01X1118400Y955999D02*
Y935826D01*
G01X1176870D02*
X1113400D01*
G01X1118400Y966599D02*
Y991535D01*
G01X1137039Y976102D02*
X1135539Y981102D01*
X1134039Y976102D01*
X1137039D01*
G01X1135539Y974412D02*
Y981102D01*
G01X1134039Y962480D02*
X1135539Y957480D01*
X1137039Y962480D01*
X1134039D01*
G01X1135539Y963812D02*
Y957480D01*
G01X1176870D02*
X1130539D01*
G01X1176870Y981102D02*
X1130539D01*
G01X1119900Y986535D02*
X1118400Y991535D01*
X1116900Y986535D01*
X1119900D01*
G01X1176870Y991535D02*
X1113400D01*
G01X1118420Y1557173D02*
Y1582109D01*
G01X1116920Y1531400D02*
X1118420Y1526400D01*
X1119920Y1531400D01*
X1116920D01*
G01X1118420Y1546573D02*
Y1526400D01*
G01X1176890D02*
X1113420D01*
G01X1135559Y1564986D02*
Y1571676D01*
G01X1134059Y1553054D02*
X1135559Y1548054D01*
X1137059Y1553054D01*
X1134059D01*
G01X1135559Y1554386D02*
Y1548054D01*
G01X1176890D02*
X1130559D01*
G01X1119920Y1577109D02*
X1118420Y1582109D01*
X1116920Y1577109D01*
X1119920D01*
G01X1176890Y1582109D02*
X1113420D01*
G01X1137059Y1566676D02*
X1135559Y1571676D01*
X1134059Y1566676D01*
X1137059D01*
G01X1176890Y1571676D02*
X1130559D01*
G01X1191871Y570779D02*
G03X1171910I-9980J-3040D01*
G02X1164985Y557648I-37662J11471D01*
G03X1198796I16906J-13531D01*
G02X1191871Y570779I30737J24602D01*
G01X1191851Y984142D02*
G03X1171890I-9981J-3040D01*
G02X1164965Y971011I-37662J11471D01*
G03X1198776I16906J-13531D01*
G02X1191851Y984142I30737J24602D01*
G01X1191871Y1574716D02*
G03X1171910I-9980J-3040D01*
G02X1164985Y1561585I-37662J11471D01*
G03X1198796I16906J-13531D01*
G02X1191871Y1574716I30737J24602D01*
G01X1198326Y530019D02*
X1215707Y515112D01*
G01X1203098Y527903D02*
X1198326Y530019D01*
X1201145Y525625D01*
X1203098Y527903D01*
G01X1220087Y518488D02*
X1216087Y512488D01*
G01X1220087Y515488D02*
G03I-2000J0D01*
G01X1203182Y548062D02*
X1215554Y557708D01*
G01X1206203Y552319D02*
X1203182Y548062D01*
X1208047Y549953D01*
X1206203Y552319D01*
G01X1190021Y574277D02*
X1217866Y596667D01*
G01X1192978Y578579D02*
X1190021Y574277D01*
X1194857Y576241D01*
X1192978Y578579D01*
G01X1222246Y599479D02*
X1218246Y593479D01*
G01X1222246Y596479D02*
G03I-2000J0D01*
G01X1198306Y943382D02*
X1215687Y928475D01*
G01X1220067Y931851D02*
X1216067Y925851D01*
G01X1220067Y928851D02*
G03I-2000J0D01*
G01X1203078Y941266D02*
X1198306Y943382D01*
X1201125Y938988D01*
X1203078Y941266D01*
G01X1203162Y961425D02*
X1215534Y971071D01*
G01X1206183Y965682D02*
X1203162Y961425D01*
X1208027Y963316D01*
X1206183Y965682D01*
G01X1190001Y987640D02*
X1217846Y1010030D01*
G01X1192958Y991942D02*
X1190001Y987640D01*
X1194837Y989604D01*
X1192958Y991942D01*
G01X1222226Y1012842D02*
X1218226Y1006842D01*
G01X1222226Y1009842D02*
G03I-2000J0D01*
G01X1220087Y1522425D02*
X1216087Y1516425D01*
G01X1220087Y1519425D02*
G03I-2000J0D01*
G01X1198326Y1533956D02*
X1215707Y1519049D01*
G01X1203098Y1531840D02*
X1198326Y1533956D01*
X1201145Y1529562D01*
X1203098Y1531840D01*
G01X1203182Y1551999D02*
X1215554Y1561645D01*
G01X1206203Y1556256D02*
X1203182Y1551999D01*
X1208047Y1553890D01*
X1206203Y1556256D01*
G01X1190021Y1578214D02*
X1217866Y1600604D01*
G01X1192978Y1582516D02*
X1190021Y1578214D01*
X1194857Y1580178D01*
X1192978Y1582516D01*
G01X1222246Y1603416D02*
X1218246Y1597416D01*
G01X1222246Y1600416D02*
G03I-2000J0D01*
G01X1236900Y348700D02*
X1238400Y343700D01*
X1239900Y348700D01*
X1236900D01*
G01X1238400Y363873D02*
Y343700D01*
G01X1296870D02*
X1233400D01*
G01X1239900Y394409D02*
X1238400Y399409D01*
X1236900Y394409D01*
X1239900D01*
G01X1238400Y374473D02*
Y399409D01*
G01X1296870D02*
X1233400D01*
G01X1257039Y383976D02*
X1255539Y388976D01*
X1254039Y383976D01*
X1257039D01*
G01X1255539Y382286D02*
Y388976D01*
G01X1254039Y370354D02*
X1255539Y365354D01*
X1257039Y370354D01*
X1254039D01*
G01X1255539Y371686D02*
Y365354D01*
G01X1296870D02*
X1250539D01*
G01X1296870Y388976D02*
X1250539D01*
G01X1311851Y392016D02*
G03X1291890I-9980J-3040D01*
G02X1284965Y378885I-37662J11471D01*
G03X1318776I16906J-13531D01*
G02X1311851Y392016I30737J24602D01*
G01X1238400Y827229D02*
Y852165D01*
G01X1236900Y801456D02*
X1238400Y796456D01*
X1239900Y801456D01*
X1236900D01*
G01X1238400Y816629D02*
Y796456D01*
G01X1296870D02*
X1233400D01*
G01X1257039Y836732D02*
X1255539Y841732D01*
X1254039Y836732D01*
X1257039D01*
G01X1255539Y835042D02*
Y841732D01*
G01X1254039Y823110D02*
X1255539Y818110D01*
X1257039Y823110D01*
X1254039D01*
G01X1255539Y824442D02*
Y818110D01*
G01X1296870D02*
X1250539D01*
G01X1311851Y844772D02*
G03X1291890I-9980J-3040D01*
G02X1284965Y831641I-37662J11471D01*
G03X1318776I16906J-13531D01*
G02X1311851Y844772I30737J24602D01*
G01X1239900Y847165D02*
X1238400Y852165D01*
X1236900Y847165D01*
X1239900D01*
G01X1296870Y852165D02*
X1233400D01*
G01X1296870Y841732D02*
X1250539D01*
G01X1236900Y1254212D02*
X1238400Y1249212D01*
X1239900Y1254212D01*
X1236900D01*
G01X1238400Y1269385D02*
Y1249212D01*
G01X1296870D02*
X1233400D01*
G01X1254039Y1275866D02*
X1255539Y1270866D01*
X1257039Y1275866D01*
X1254039D01*
G01X1255539Y1277198D02*
Y1270866D01*
G01X1296870D02*
X1250539D01*
G01X1311851Y1297528D02*
G03X1291890I-9980J-3040D01*
G02X1284965Y1284397I-37662J11471D01*
G03X1318776I16906J-13531D01*
G02X1311851Y1297528I30737J24602D01*
G01X1239900Y1299921D02*
X1238400Y1304921D01*
X1236900Y1299921D01*
X1239900D01*
G01X1238400Y1279985D02*
Y1304921D01*
G01X1296870D02*
X1233400D01*
G01X1257039Y1289488D02*
X1255539Y1294488D01*
X1254039Y1289488D01*
X1257039D01*
G01X1255539Y1287798D02*
Y1294488D01*
G01X1296870D02*
X1250539D01*
G01X1312898Y-495196D02*
X1311151Y-494904D01*
X1309623Y-493738D01*
X1308313Y-491988D01*
X1307439Y-489946D01*
X1307003Y-487613D01*
Y-485279D01*
X1307439Y-482946D01*
X1308313Y-480904D01*
X1309623Y-479155D01*
X1311151Y-477988D01*
X1312898Y-477696D01*
X1314644Y-477988D01*
X1316173Y-479155D01*
X1317483Y-480904D01*
X1318357Y-482946D01*
X1318793Y-485279D01*
Y-487613D01*
X1318357Y-489946D01*
X1317483Y-491988D01*
X1316173Y-493738D01*
X1314644Y-494904D01*
X1312898Y-495196D01*
G01X1314644Y-490529D02*
X1317265Y-495196D01*
G01X1325595Y-477696D02*
Y-490238D01*
X1326468Y-492863D01*
X1328215Y-494613D01*
X1330398Y-495196D01*
X1332581Y-494613D01*
X1334328Y-492863D01*
X1335201Y-490238D01*
Y-477696D01*
G01X1345278D02*
X1350518D01*
G01X1347898D02*
Y-495196D01*
G01X1345278D02*
X1350518D01*
G01X1360376D02*
Y-477696D01*
X1370420Y-495196D01*
Y-477696D01*
G01X1387701Y-479155D02*
X1386391Y-478279D01*
X1384863Y-477696D01*
X1383116D01*
X1381151Y-478571D01*
X1379623Y-480029D01*
X1378531Y-481780D01*
X1377658Y-484696D01*
X1377439Y-487321D01*
X1377876Y-489946D01*
X1378531Y-491696D01*
X1379841Y-493446D01*
X1381370Y-494613D01*
X1382898Y-495196D01*
X1384426D01*
X1385955Y-494613D01*
X1387265Y-493738D01*
X1388357Y-492572D01*
G01X1400398Y-495196D02*
Y-487321D01*
X1396031Y-477696D01*
G01X1404765D02*
X1400398Y-487321D01*
G01X1290595Y-450196D02*
Y-432696D01*
X1294961D01*
X1296708Y-433571D01*
X1298018Y-434738D01*
X1299110Y-436487D01*
X1299983Y-438530D01*
X1300201Y-441446D01*
X1299983Y-444363D01*
X1299110Y-446405D01*
X1298018Y-448155D01*
X1296708Y-449321D01*
X1294961Y-450196D01*
X1290595D01*
G01X1309623Y-442321D02*
X1316610D01*
X1315955Y-440279D01*
X1314863Y-439113D01*
X1313335Y-438530D01*
X1311806Y-438821D01*
X1310496Y-439696D01*
X1309623Y-441738D01*
X1309186Y-443488D01*
Y-445238D01*
X1309623Y-446988D01*
X1310715Y-448738D01*
X1312025Y-449904D01*
X1313553Y-450196D01*
X1315081Y-449613D01*
X1316610Y-447863D01*
G01X1327123Y-448155D02*
X1328215Y-449321D01*
X1329743Y-450196D01*
X1331053D01*
X1332363Y-449613D01*
X1333236Y-448738D01*
X1333673Y-447572D01*
X1333455Y-445821D01*
X1332581Y-444946D01*
X1328651Y-443196D01*
X1327778Y-441154D01*
X1328215Y-439696D01*
X1329088Y-438821D01*
X1330398Y-438530D01*
X1331708Y-438821D01*
X1333018Y-439696D01*
G01X1347898Y-438530D02*
Y-450196D01*
G01Y-433863D02*
X1347461Y-433571D01*
Y-432988D01*
X1347898Y-432696D01*
X1348335Y-432988D01*
Y-433571D01*
X1347898Y-433863D01*
G01X1362341Y-454571D02*
X1363870Y-455738D01*
X1365616Y-456029D01*
X1367144Y-455738D01*
X1368455Y-454280D01*
X1369328Y-452238D01*
Y-438530D01*
G01Y-440863D02*
X1368455Y-439696D01*
X1367144Y-438821D01*
X1365616Y-438530D01*
X1363870Y-439113D01*
X1362778Y-440279D01*
X1361904Y-442321D01*
X1361468Y-444363D01*
X1361686Y-446113D01*
X1362560Y-448155D01*
X1363870Y-449613D01*
X1365616Y-450196D01*
X1366926Y-449904D01*
X1368455Y-448738D01*
X1369328Y-447572D01*
G01X1379186Y-450196D02*
Y-438530D01*
G01Y-441446D02*
X1380060Y-439988D01*
X1381370Y-438821D01*
X1383116Y-438530D01*
X1384644Y-438821D01*
X1385955Y-439988D01*
X1386610Y-442029D01*
Y-450196D01*
G01X1397123Y-442321D02*
X1404110D01*
X1403455Y-440279D01*
X1402363Y-439113D01*
X1400835Y-438530D01*
X1399306Y-438821D01*
X1397996Y-439696D01*
X1397123Y-441738D01*
X1396686Y-443488D01*
Y-445238D01*
X1397123Y-446988D01*
X1398215Y-448738D01*
X1399525Y-449904D01*
X1401053Y-450196D01*
X1402581Y-449613D01*
X1404110Y-447863D01*
G01X1414841Y-450196D02*
Y-438530D01*
G01Y-440863D02*
X1415933Y-439696D01*
X1417025Y-438821D01*
X1418553Y-438530D01*
X1419644Y-438821D01*
X1420955Y-439696D01*
G01X1318306Y351256D02*
X1335687Y336349D01*
G01X1323078Y349140D02*
X1318306Y351256D01*
X1321125Y346862D01*
X1323078Y349140D01*
G01X1310001Y395514D02*
X1337846Y417904D01*
G01X1312958Y399816D02*
X1310001Y395514D01*
X1314837Y397478D01*
X1312958Y399816D01*
G01X1323162Y369299D02*
X1335534Y378945D01*
G01X1326183Y373556D02*
X1323162Y369299D01*
X1328027Y371190D01*
X1326183Y373556D01*
G01X1318306Y804012D02*
X1335687Y789105D01*
G01X1323078Y801896D02*
X1318306Y804012D01*
X1321125Y799618D01*
X1323078Y801896D01*
G01X1323162Y822055D02*
X1335534Y831701D01*
G01X1326183Y826312D02*
X1323162Y822055D01*
X1328027Y823946D01*
X1326183Y826312D01*
G01X1310001Y848270D02*
X1337846Y870660D01*
G01X1312958Y852572D02*
X1310001Y848270D01*
X1314837Y850234D01*
X1312958Y852572D01*
G01X1318306Y1256768D02*
X1335687Y1241861D01*
G01X1323078Y1254652D02*
X1318306Y1256768D01*
X1321125Y1252374D01*
X1323078Y1254652D01*
G01X1323162Y1274811D02*
X1335534Y1284457D01*
G01X1326183Y1279068D02*
X1323162Y1274811D01*
X1328027Y1276702D01*
X1326183Y1279068D01*
G01X1310001Y1301026D02*
X1337846Y1323416D01*
G01X1312958Y1305328D02*
X1310001Y1301026D01*
X1314837Y1302990D01*
X1312958Y1305328D01*
G01X1340067Y339725D02*
X1336067Y333725D01*
G01X1340067Y336725D02*
G03I-2000J0D01*
G01X1342226Y420716D02*
X1338226Y414716D01*
G01X1342226Y417716D02*
G03I-2000J0D01*
G01X1340067Y792481D02*
X1336067Y786481D01*
G01X1340067Y789481D02*
G03I-2000J0D01*
G01X1342226Y873472D02*
X1338226Y867472D01*
G01X1342226Y870472D02*
G03I-2000J0D01*
G01X1340067Y1245237D02*
X1336067Y1239237D01*
G01X1340067Y1242237D02*
G03I-2000J0D01*
G01X1342226Y1326228D02*
X1338226Y1320228D01*
G01X1342226Y1323228D02*
G03I-2000J0D01*
G01X1461598Y-477696D02*
X1459851Y-478279D01*
X1458541Y-479738D01*
X1457668Y-481487D01*
X1457013Y-483821D01*
X1456795Y-486446D01*
X1457013Y-489071D01*
X1457668Y-491405D01*
X1458541Y-493155D01*
X1459851Y-494613D01*
X1461598Y-495196D01*
X1463344Y-494613D01*
X1464655Y-493155D01*
X1465528Y-491405D01*
X1466183Y-489071D01*
X1466401Y-486446D01*
X1466183Y-483821D01*
X1465528Y-481487D01*
X1464655Y-479738D01*
X1463344Y-478279D01*
X1461598Y-477696D01*
G01X1474950Y-487905D02*
X1476478Y-485863D01*
X1477788Y-484696D01*
X1479535Y-484113D01*
X1481063Y-484696D01*
X1482155Y-485863D01*
X1483028Y-487613D01*
X1483246Y-489654D01*
X1483028Y-491405D01*
X1482155Y-493155D01*
X1480844Y-494613D01*
X1479316Y-495196D01*
X1477570Y-494613D01*
X1476041Y-492863D01*
X1475168Y-490238D01*
X1474950Y-487321D01*
X1475386Y-483530D01*
X1476041Y-481487D01*
X1477133Y-479446D01*
X1478661Y-477988D01*
X1480190Y-477696D01*
X1481718Y-478279D01*
X1482810Y-479738D01*
G01X1492668Y-495779D02*
X1500528Y-477696D01*
G01X1514098D02*
X1512351Y-478279D01*
X1511041Y-479738D01*
X1510168Y-481487D01*
X1509513Y-483821D01*
X1509295Y-486446D01*
X1509513Y-489071D01*
X1510168Y-491405D01*
X1511041Y-493155D01*
X1512351Y-494613D01*
X1514098Y-495196D01*
X1515844Y-494613D01*
X1517155Y-493155D01*
X1518028Y-491405D01*
X1518683Y-489071D01*
X1518901Y-486446D01*
X1518683Y-483821D01*
X1518028Y-481487D01*
X1517155Y-479738D01*
X1515844Y-478279D01*
X1514098Y-477696D01*
G01X1527886Y-493155D02*
X1529415Y-494613D01*
X1531161Y-495196D01*
X1532908Y-494613D01*
X1534436Y-492863D01*
X1535528Y-490238D01*
X1535965Y-487613D01*
Y-484405D01*
X1535528Y-481780D01*
X1534436Y-479446D01*
X1533126Y-478279D01*
X1531598Y-477696D01*
X1529851Y-478279D01*
X1528541Y-479446D01*
X1527668Y-481196D01*
X1527231Y-483530D01*
X1527668Y-485571D01*
X1528760Y-487613D01*
X1530070Y-488780D01*
X1531598Y-489071D01*
X1533344Y-488488D01*
X1534655Y-487029D01*
X1535965Y-484405D01*
G01X1545168Y-495779D02*
X1553028Y-477696D01*
G01X1562450Y-480613D02*
X1563760Y-478863D01*
X1565288Y-477988D01*
X1567035Y-477696D01*
X1569218Y-478279D01*
X1570746Y-479738D01*
X1571183Y-481487D01*
X1570965Y-483238D01*
X1570091Y-484696D01*
X1565725Y-487613D01*
X1563760Y-489654D01*
X1562450Y-492572D01*
X1562013Y-495196D01*
X1571183D01*
G01X1584098Y-477696D02*
X1582351Y-478279D01*
X1581041Y-479738D01*
X1580168Y-481487D01*
X1579513Y-483821D01*
X1579295Y-486446D01*
X1579513Y-489071D01*
X1580168Y-491405D01*
X1581041Y-493155D01*
X1582351Y-494613D01*
X1584098Y-495196D01*
X1585844Y-494613D01*
X1587155Y-493155D01*
X1588028Y-491405D01*
X1588683Y-489071D01*
X1588901Y-486446D01*
X1588683Y-483821D01*
X1588028Y-481487D01*
X1587155Y-479738D01*
X1585844Y-478279D01*
X1584098Y-477696D01*
G01X1601598Y-495196D02*
Y-477696D01*
X1598978Y-481196D01*
G01Y-495196D02*
X1604218D01*
G01X1618661D02*
X1619098Y-491405D01*
X1619753Y-488196D01*
X1620626Y-485279D01*
X1621718Y-482071D01*
X1623465Y-477696D01*
X1614731D01*
G01X1509295Y-450196D02*
Y-432696D01*
X1513661D01*
X1515408Y-433571D01*
X1516718Y-434738D01*
X1517810Y-436487D01*
X1518683Y-438530D01*
X1518901Y-441446D01*
X1518683Y-444363D01*
X1517810Y-446405D01*
X1516718Y-448155D01*
X1515408Y-449321D01*
X1513661Y-450196D01*
X1509295D01*
G01X1535528D02*
Y-438530D01*
G01Y-440571D02*
X1534655Y-439405D01*
X1533344Y-438821D01*
X1531816Y-438530D01*
X1530288Y-439113D01*
X1528978Y-440279D01*
X1528104Y-442029D01*
X1527668Y-444363D01*
X1528104Y-446696D01*
X1528978Y-448446D01*
X1530288Y-449613D01*
X1531816Y-450196D01*
X1533344Y-449904D01*
X1534655Y-449030D01*
X1535528Y-447863D01*
G01X1549098Y-432696D02*
Y-450196D01*
G01X1546041Y-438530D02*
X1552155D01*
G01X1563323Y-442321D02*
X1570310D01*
X1569655Y-440279D01*
X1568563Y-439113D01*
X1567035Y-438530D01*
X1565506Y-438821D01*
X1564196Y-439696D01*
X1563323Y-441738D01*
X1562886Y-443488D01*
Y-445238D01*
X1563323Y-446988D01*
X1564415Y-448738D01*
X1565725Y-449904D01*
X1567253Y-450196D01*
X1568781Y-449613D01*
X1570310Y-447863D01*
G01X1484931Y348700D02*
X1486431Y343700D01*
X1487931Y348700D01*
X1484931D01*
G01X1486431Y363873D02*
Y343700D01*
G01X1544901D02*
X1481431D01*
G01X1487931Y394409D02*
X1486431Y399409D01*
X1484931Y394409D01*
X1487931D01*
G01X1486431Y374473D02*
Y399409D01*
G01X1544901D02*
X1481431D01*
G01X1505070Y383976D02*
X1503570Y388976D01*
X1502070Y383976D01*
X1505070D01*
G01X1503570Y382286D02*
Y388976D01*
G01X1502070Y370354D02*
X1503570Y365354D01*
X1505070Y370354D01*
X1502070D01*
G01X1503570Y371686D02*
Y365354D01*
G01X1544901D02*
X1498570D01*
G01X1544901Y388976D02*
X1498570D01*
G01X1486431Y827229D02*
Y852165D01*
G01X1484931Y801456D02*
X1486431Y796456D01*
X1487931Y801456D01*
X1484931D01*
G01X1486431Y816629D02*
Y796456D01*
G01X1544901D02*
X1481431D01*
G01X1505070Y836732D02*
X1503570Y841732D01*
X1502070Y836732D01*
X1505070D01*
G01X1503570Y835042D02*
Y841732D01*
G01X1502070Y823110D02*
X1503570Y818110D01*
X1505070Y823110D01*
X1502070D01*
G01X1503570Y824442D02*
Y818110D01*
G01X1544901D02*
X1498570D01*
G01X1487931Y847165D02*
X1486431Y852165D01*
X1484931Y847165D01*
X1487931D01*
G01X1544901Y852165D02*
X1481431D01*
G01X1544901Y841732D02*
X1498570D01*
G01X1484931Y1254212D02*
X1486431Y1249212D01*
X1487931Y1254212D01*
X1484931D01*
G01X1486431Y1269385D02*
Y1249212D01*
G01X1544901D02*
X1481431D01*
G01X1502070Y1275866D02*
X1503570Y1270866D01*
X1505070Y1275866D01*
X1502070D01*
G01X1503570Y1277198D02*
Y1270866D01*
G01X1544901D02*
X1498570D01*
G01X1487931Y1299921D02*
X1486431Y1304921D01*
X1484931Y1299921D01*
X1487931D01*
G01X1486431Y1279985D02*
Y1304921D01*
G01X1544901D02*
X1481431D01*
G01X1505070Y1289488D02*
X1503570Y1294488D01*
X1502070Y1289488D01*
X1505070D01*
G01X1503570Y1287798D02*
Y1294488D01*
G01X1544901D02*
X1498570D01*
G01X1566337Y351256D02*
X1583718Y336349D01*
G01X1571109Y349140D02*
X1566337Y351256D01*
X1569156Y346862D01*
X1571109Y349140D01*
G01X1559882Y392016D02*
G03X1539921I-9980J-3040D01*
G02X1532996Y378885I-37662J11471D01*
G03X1566807I16906J-13531D01*
G02X1559882Y392016I30737J24602D01*
G01X1558032Y395514D02*
X1585877Y417904D01*
G01X1560989Y399816D02*
X1558032Y395514D01*
X1562868Y397478D01*
X1560989Y399816D01*
G01X1566337Y804012D02*
X1583718Y789105D01*
G01X1571109Y801896D02*
X1566337Y804012D01*
X1569156Y799618D01*
X1571109Y801896D01*
G01X1559882Y844772D02*
G03X1539921I-9980J-3040D01*
G02X1532996Y831641I-37662J11471D01*
G03X1566807I16906J-13531D01*
G02X1559882Y844772I30737J24602D01*
G01X1558032Y848270D02*
X1585877Y870660D01*
G01X1560989Y852572D02*
X1558032Y848270D01*
X1562868Y850234D01*
X1560989Y852572D01*
G01X1566337Y1256768D02*
X1583718Y1241861D01*
G01X1571109Y1254652D02*
X1566337Y1256768D01*
X1569156Y1252374D01*
X1571109Y1254652D01*
G01X1559882Y1297528D02*
G03X1539921I-9980J-3040D01*
G02X1532996Y1284397I-37662J11471D01*
G03X1566807I16906J-13531D01*
G02X1559882Y1297528I30737J24602D01*
G01X1558032Y1301026D02*
X1585877Y1323416D01*
G01X1560989Y1305328D02*
X1558032Y1301026D01*
X1562868Y1302990D01*
X1560989Y1305328D01*
G01X1588098Y339725D02*
X1584098Y333725D01*
G01X1588098Y336725D02*
G03I-2000J0D01*
G01X1571193Y369299D02*
X1583565Y378945D01*
G01X1574214Y373556D02*
X1571193Y369299D01*
X1576058Y371190D01*
X1574214Y373556D01*
G01X1590257Y420716D02*
X1586257Y414716D01*
G01X1590257Y417716D02*
G03I-2000J0D01*
G01X1588098Y792481D02*
X1584098Y786481D01*
G01X1588098Y789481D02*
G03I-2000J0D01*
G01X1571193Y822055D02*
X1583565Y831701D01*
G01X1574214Y826312D02*
X1571193Y822055D01*
X1576058Y823946D01*
X1574214Y826312D01*
G01X1590257Y873472D02*
X1586257Y867472D01*
G01X1590257Y870472D02*
G03I-2000J0D01*
G01X1588098Y1245237D02*
X1584098Y1239237D01*
G01X1588098Y1242237D02*
G03I-2000J0D01*
G01X1571193Y1274811D02*
X1583565Y1284457D01*
G01X1574214Y1279068D02*
X1571193Y1274811D01*
X1576058Y1276702D01*
X1574214Y1279068D01*
G01X1590257Y1326228D02*
X1586257Y1320228D01*
G01X1590257Y1323228D02*
G03I-2000J0D01*
G01X1792933Y343700D02*
X1729463D01*
G01X1734463Y363873D02*
Y343700D01*
G01X1732963Y348700D02*
X1734463Y343700D01*
X1735963Y348700D01*
X1732963D01*
G01X1792933Y388976D02*
X1746602D01*
G01X1792933Y365354D02*
X1746602D01*
G01X1751602Y371686D02*
Y365354D01*
G01X1750102Y370354D02*
X1751602Y365354D01*
X1753102Y370354D01*
X1750102D01*
G01X1751602Y382286D02*
Y388976D01*
G01X1753102Y383976D02*
X1751602Y388976D01*
X1750102Y383976D01*
X1753102D01*
G01X1792933Y399409D02*
X1729463D01*
G01X1734463Y374473D02*
Y399409D01*
G01X1735963Y394409D02*
X1734463Y399409D01*
X1732963Y394409D01*
X1735963D01*
G01X1734463Y827229D02*
Y852165D01*
G01X1732963Y801456D02*
X1734463Y796456D01*
X1735963Y801456D01*
X1732963D01*
G01X1734463Y816629D02*
Y796456D01*
G01X1792933D02*
X1729463D01*
G01X1753102Y836732D02*
X1751602Y841732D01*
X1750102Y836732D01*
X1753102D01*
G01X1751602Y835042D02*
Y841732D01*
G01X1750102Y823110D02*
X1751602Y818110D01*
X1753102Y823110D01*
X1750102D01*
G01X1751602Y824442D02*
Y818110D01*
G01X1792933D02*
X1746602D01*
G01X1735963Y847165D02*
X1734463Y852165D01*
X1732963Y847165D01*
X1735963D01*
G01X1792933Y852165D02*
X1729463D01*
G01X1792933Y841732D02*
X1746602D01*
G01X1792933Y1270866D02*
X1746602D01*
G01X1751602Y1277198D02*
Y1270866D01*
G01X1750102Y1275866D02*
X1751602Y1270866D01*
X1753102Y1275866D01*
X1750102D01*
G01X1792933Y1249212D02*
X1729463D01*
G01X1734463Y1269385D02*
Y1249212D01*
G01X1732963Y1254212D02*
X1734463Y1249212D01*
X1735963Y1254212D01*
X1732963D01*
G01X1792933Y1294488D02*
X1746602D01*
G01X1751602Y1287798D02*
Y1294488D01*
G01X1753102Y1289488D02*
X1751602Y1294488D01*
X1750102Y1289488D01*
X1753102D01*
G01X1792933Y1304921D02*
X1729463D01*
G01X1734463Y1279985D02*
Y1304921D01*
G01X1735963Y1299921D02*
X1734463Y1304921D01*
X1732963Y1299921D01*
X1735963D01*
G01X1807914Y392016D02*
G03X1787953I-9980J-3040D01*
G02X1781028Y378885I-37662J11471D01*
G03X1814839I16906J-13531D01*
G02X1807914Y392016I30737J24602D01*
G01X1809021Y399816D02*
X1806064Y395514D01*
X1810900Y397478D01*
X1809021Y399816D01*
G01X1806064Y395514D02*
X1833909Y417904D01*
G01X1807914Y844772D02*
G03X1787953I-9980J-3040D01*
G02X1781028Y831641I-37662J11471D01*
G03X1814839I16906J-13531D01*
G02X1807914Y844772I30737J24602D01*
G01X1806064Y848270D02*
X1833909Y870660D01*
G01X1809021Y852572D02*
X1806064Y848270D01*
X1810900Y850234D01*
X1809021Y852572D01*
G01X1807914Y1297528D02*
G03X1787953I-9980J-3040D01*
G02X1781028Y1284397I-37662J11471D01*
G03X1814839I16906J-13531D01*
G02X1807914Y1297528I30737J24602D01*
G01X1809021Y1305328D02*
X1806064Y1301026D01*
X1810900Y1302990D01*
X1809021Y1305328D01*
G01X1806064Y1301026D02*
X1833909Y1323416D01*
G01X1836130Y336725D02*
G03I-2000J0D01*
G01Y339725D02*
X1832130Y333725D01*
G01X1819141Y349140D02*
X1814369Y351256D01*
X1817188Y346862D01*
X1819141Y349140D01*
G01X1814369Y351256D02*
X1831750Y336349D01*
G01X1822246Y373556D02*
X1819225Y369299D01*
X1824090Y371190D01*
X1822246Y373556D01*
G01X1819225Y369299D02*
X1831597Y378945D01*
G01X1838289Y417716D02*
G03I-2000J0D01*
G01Y420716D02*
X1834289Y414716D01*
G01X1814369Y804012D02*
X1831750Y789105D01*
G01X1836130Y792481D02*
X1832130Y786481D01*
G01X1836130Y789481D02*
G03I-2000J0D01*
G01X1819141Y801896D02*
X1814369Y804012D01*
X1817188Y799618D01*
X1819141Y801896D01*
G01X1819225Y822055D02*
X1831597Y831701D01*
G01X1822246Y826312D02*
X1819225Y822055D01*
X1824090Y823946D01*
X1822246Y826312D01*
G01X1838289Y873472D02*
X1834289Y867472D01*
G01X1838289Y870472D02*
G03I-2000J0D01*
G01X1822246Y1279068D02*
X1819225Y1274811D01*
X1824090Y1276702D01*
X1822246Y1279068D01*
G01X1819225Y1274811D02*
X1831597Y1284457D01*
G01X1836130Y1242237D02*
G03I-2000J0D01*
G01Y1245237D02*
X1832130Y1239237D01*
G01X1819141Y1254652D02*
X1814369Y1256768D01*
X1817188Y1252374D01*
X1819141Y1254652D01*
G01X1814369Y1256768D02*
X1831750Y1241861D01*
G01X1838289Y1323228D02*
G03I-2000J0D01*
G01Y1326228D02*
X1834289Y1320228D01*
G01X1902984Y475151D02*
X1924634Y482259D01*
G01X1907267Y478136D02*
X1902984Y475151D01*
X1908202Y475286D01*
X1907267Y478136D01*
G01X1886384Y470459D02*
Y478359D01*
G02X1902984I8300J0D01*
G01Y470459D01*
G02X1886384I-8300J0D01*
G01X2389064Y-118734D02*
Y-106234D01*
X2396194Y-118734D01*
Y-106234D01*
G01X2405029Y-118734D02*
X2404099Y-118526D01*
X2403169Y-117693D01*
X2402549Y-116234D01*
X2402239Y-114567D01*
X2402549Y-112901D01*
X2403169Y-111442D01*
X2404099Y-110609D01*
X2405029Y-110401D01*
X2405959Y-110609D01*
X2406889Y-111442D01*
X2407509Y-112901D01*
X2407664Y-114567D01*
X2407509Y-116234D01*
X2406889Y-117693D01*
X2405959Y-118526D01*
X2405029Y-118734D01*
G01X2417429Y-106234D02*
Y-118734D01*
G01X2415259Y-110401D02*
X2419599D01*
G01X2427504Y-113109D02*
X2432464D01*
X2431999Y-111651D01*
X2431224Y-110817D01*
X2430139Y-110401D01*
X2429054Y-110609D01*
X2428124Y-111234D01*
X2427504Y-112692D01*
X2427194Y-113943D01*
Y-115192D01*
X2427504Y-116442D01*
X2428279Y-117693D01*
X2429209Y-118526D01*
X2430294Y-118734D01*
X2431379Y-118317D01*
X2432464Y-117068D01*
G01X2442229Y-119151D02*
X2441919Y-118942D01*
Y-118526D01*
X2442229Y-118317D01*
X2442539Y-118526D01*
Y-118942D01*
X2442229Y-119151D01*
G01Y-113526D02*
X2441919Y-113317D01*
Y-112901D01*
X2442229Y-112692D01*
X2442539Y-112901D01*
Y-113317D01*
X2442229Y-113526D01*
G01X2451529Y-118734D02*
Y-106234D01*
X2455404D01*
X2456644Y-106859D01*
X2457419Y-107692D01*
X2457729Y-109359D01*
X2457419Y-111026D01*
X2456489Y-112067D01*
X2455404Y-112692D01*
X2451529D01*
G01X2455404D02*
X2457729Y-118734D01*
G01X2464704Y-113109D02*
X2469664D01*
X2469199Y-111651D01*
X2468424Y-110817D01*
X2467339Y-110401D01*
X2466254Y-110609D01*
X2465324Y-111234D01*
X2464704Y-112692D01*
X2464394Y-113943D01*
Y-115192D01*
X2464704Y-116442D01*
X2465479Y-117693D01*
X2466409Y-118526D01*
X2467494Y-118734D01*
X2468579Y-118317D01*
X2469664Y-117068D01*
G01X2478499Y-118734D02*
Y-108109D01*
X2478809Y-107068D01*
X2479429Y-106442D01*
X2480359Y-106234D01*
X2481289Y-106651D01*
X2481754Y-107692D01*
G01X2479894Y-111234D02*
X2476794D01*
G01X2489504Y-113109D02*
X2494464D01*
X2493999Y-111651D01*
X2493224Y-110817D01*
X2492139Y-110401D01*
X2491054Y-110609D01*
X2490124Y-111234D01*
X2489504Y-112692D01*
X2489194Y-113943D01*
Y-115192D01*
X2489504Y-116442D01*
X2490279Y-117693D01*
X2491209Y-118526D01*
X2492294Y-118734D01*
X2493379Y-118317D01*
X2494464Y-117068D01*
G01X2502059Y-118734D02*
Y-110401D01*
G01Y-112067D02*
X2502834Y-111234D01*
X2503609Y-110609D01*
X2504694Y-110401D01*
X2505469Y-110609D01*
X2506399Y-111234D01*
G01X2529029Y-106234D02*
Y-118734D01*
G01X2526859Y-110401D02*
X2531199D01*
G01X2541429Y-118734D02*
X2540499Y-118526D01*
X2539569Y-117693D01*
X2538949Y-116234D01*
X2538639Y-114567D01*
X2538949Y-112901D01*
X2539569Y-111442D01*
X2540499Y-110609D01*
X2541429Y-110401D01*
X2542359Y-110609D01*
X2543289Y-111442D01*
X2543909Y-112901D01*
X2544064Y-114567D01*
X2543909Y-116234D01*
X2543289Y-117693D01*
X2542359Y-118526D01*
X2541429Y-118734D01*
G01X2562819D02*
Y-106234D01*
X2565919D01*
X2567159Y-106859D01*
X2568089Y-107692D01*
X2568864Y-108942D01*
X2569484Y-110401D01*
X2569639Y-112484D01*
X2569484Y-114567D01*
X2568864Y-116026D01*
X2568089Y-117276D01*
X2567159Y-118109D01*
X2565919Y-118734D01*
X2562819D01*
G01X2575529D02*
Y-106234D01*
X2579404D01*
X2580644Y-106859D01*
X2581419Y-107692D01*
X2581729Y-109359D01*
X2581419Y-111026D01*
X2580489Y-112067D01*
X2579404Y-112692D01*
X2575529D01*
G01X2579404D02*
X2581729Y-118734D01*
G01X2589169Y-106234D02*
X2592889D01*
G01X2591029D02*
Y-118734D01*
G01X2589169D02*
X2592889D01*
G01X2600329Y-106234D02*
Y-118734D01*
X2606529D01*
G01X2612729Y-106234D02*
Y-118734D01*
X2618929D01*
G01X2640629D02*
Y-106234D01*
G01X2655819Y-118734D02*
Y-110401D01*
G01Y-111859D02*
X2655199Y-111026D01*
X2654269Y-110609D01*
X2653184Y-110401D01*
X2652099Y-110817D01*
X2651169Y-111651D01*
X2650549Y-112901D01*
X2650239Y-114567D01*
X2650549Y-116234D01*
X2651169Y-117484D01*
X2652099Y-118317D01*
X2653184Y-118734D01*
X2654269Y-118526D01*
X2655199Y-117901D01*
X2655819Y-117068D01*
G01X2662174Y-122484D02*
X2663104Y-122901D01*
X2664344Y-122484D01*
X2665119Y-121651D01*
X2665739Y-120609D01*
X2666669Y-117276D01*
X2668684Y-110401D01*
G01X2663724D02*
X2666669Y-117276D01*
G01X2675504Y-113109D02*
X2680464D01*
X2679999Y-111651D01*
X2679224Y-110817D01*
X2678139Y-110401D01*
X2677054Y-110609D01*
X2676124Y-111234D01*
X2675504Y-112692D01*
X2675194Y-113943D01*
Y-115192D01*
X2675504Y-116442D01*
X2676279Y-117693D01*
X2677209Y-118526D01*
X2678294Y-118734D01*
X2679379Y-118317D01*
X2680464Y-117068D01*
G01X2688059Y-118734D02*
Y-110401D01*
G01Y-112067D02*
X2688834Y-111234D01*
X2689609Y-110609D01*
X2690694Y-110401D01*
X2691469Y-110609D01*
X2692399Y-111234D01*
G01X2714099Y-118734D02*
Y-108109D01*
X2714409Y-107068D01*
X2715029Y-106442D01*
X2715959Y-106234D01*
X2716889Y-106651D01*
X2717354Y-107692D01*
G01X2715494Y-111234D02*
X2712394D01*
G01X2727429Y-118734D02*
X2726499Y-118526D01*
X2725569Y-117693D01*
X2724949Y-116234D01*
X2724639Y-114567D01*
X2724949Y-112901D01*
X2725569Y-111442D01*
X2726499Y-110609D01*
X2727429Y-110401D01*
X2728359Y-110609D01*
X2729289Y-111442D01*
X2729909Y-112901D01*
X2730064Y-114567D01*
X2729909Y-116234D01*
X2729289Y-117693D01*
X2728359Y-118526D01*
X2727429Y-118734D01*
G01X2737659D02*
Y-110401D01*
G01Y-112067D02*
X2738434Y-111234D01*
X2739209Y-110609D01*
X2740294Y-110401D01*
X2741069Y-110609D01*
X2741999Y-111234D01*
G01X2767729Y-118734D02*
X2761529D01*
Y-106234D01*
X2767729D01*
G01X2765249Y-112276D02*
X2761529D01*
G01X2773929Y-106234D02*
Y-118734D01*
X2780129D01*
G01X2786329Y-106234D02*
Y-118734D01*
X2792529D01*
G01X2799969Y-106234D02*
X2803689D01*
G01X2801829D02*
Y-118734D01*
G01X2799969D02*
X2803689D01*
G01X2811129D02*
Y-106234D01*
X2814849D01*
X2816089Y-106859D01*
X2817019Y-108317D01*
X2817329Y-109984D01*
X2817019Y-111651D01*
X2816244Y-112901D01*
X2814849Y-113526D01*
X2811129D01*
G01X2823374Y-117068D02*
X2824614Y-118109D01*
X2826009Y-118734D01*
X2827249D01*
X2828489Y-118109D01*
X2829419Y-117068D01*
X2829884Y-115609D01*
X2829574Y-114151D01*
X2828799Y-112901D01*
X2827404Y-112067D01*
X2825544Y-111651D01*
X2824459Y-110817D01*
X2823994Y-109359D01*
X2824304Y-107901D01*
X2825079Y-106859D01*
X2826164Y-106234D01*
X2827249D01*
X2828334Y-106651D01*
X2829264Y-107692D01*
G01X2842129Y-118734D02*
X2835929D01*
Y-106234D01*
X2842129D01*
G01X2839649Y-112276D02*
X2835929D01*
G01X2866619Y-106234D02*
Y-118734D01*
G01Y-116859D02*
X2865999Y-117901D01*
X2865069Y-118526D01*
X2863984Y-118734D01*
X2862744Y-118317D01*
X2861814Y-117276D01*
X2861194Y-116026D01*
X2861039Y-114567D01*
X2861194Y-113109D01*
X2861814Y-111859D01*
X2862744Y-110817D01*
X2863984Y-110401D01*
X2865069Y-110609D01*
X2865844Y-111026D01*
X2866619Y-111859D01*
G01X2874059Y-118734D02*
Y-110401D01*
G01Y-112067D02*
X2874834Y-111234D01*
X2875609Y-110609D01*
X2876694Y-110401D01*
X2877469Y-110609D01*
X2878399Y-111234D01*
G01X2888629Y-110401D02*
Y-118734D01*
G01Y-107068D02*
X2888319Y-106859D01*
Y-106442D01*
X2888629Y-106234D01*
X2888939Y-106442D01*
Y-106859D01*
X2888629Y-107068D01*
G01X2901029Y-118734D02*
Y-106234D01*
G01X2913429Y-118734D02*
Y-106234D01*
G01X2941019D02*
Y-118734D01*
G01Y-116859D02*
X2940399Y-117901D01*
X2939469Y-118526D01*
X2938384Y-118734D01*
X2937144Y-118317D01*
X2936214Y-117276D01*
X2935594Y-116026D01*
X2935439Y-114567D01*
X2935594Y-113109D01*
X2936214Y-111859D01*
X2937144Y-110817D01*
X2938384Y-110401D01*
X2939469Y-110609D01*
X2940244Y-111026D01*
X2941019Y-111859D01*
G01X2950629Y-110401D02*
Y-118734D01*
G01Y-107068D02*
X2950319Y-106859D01*
Y-106442D01*
X2950629Y-106234D01*
X2950939Y-106442D01*
Y-106859D01*
X2950629Y-107068D01*
G01X2960859Y-118734D02*
Y-110401D01*
G01Y-112067D02*
X2961634Y-111234D01*
X2962409Y-110609D01*
X2963494Y-110401D01*
X2964269Y-110609D01*
X2965199Y-111234D01*
G01X2973104Y-113109D02*
X2978064D01*
X2977599Y-111651D01*
X2976824Y-110817D01*
X2975739Y-110401D01*
X2974654Y-110609D01*
X2973724Y-111234D01*
X2973104Y-112692D01*
X2972794Y-113943D01*
Y-115192D01*
X2973104Y-116442D01*
X2973879Y-117693D01*
X2974809Y-118526D01*
X2975894Y-118734D01*
X2976979Y-118317D01*
X2978064Y-117068D01*
G01X2990309Y-111442D02*
X2989224Y-110609D01*
X2988294Y-110401D01*
X2987054Y-110817D01*
X2986124Y-111651D01*
X2985504Y-113109D01*
X2985349Y-114567D01*
X2985504Y-116026D01*
X2986124Y-117276D01*
X2987054Y-118317D01*
X2988294Y-118734D01*
X2989379Y-118317D01*
X2990309Y-117484D01*
G01X3000229Y-106234D02*
Y-118734D01*
G01X2998059Y-110401D02*
X3002399D01*
G01X3012629D02*
Y-118734D01*
G01Y-107068D02*
X3012319Y-106859D01*
Y-106442D01*
X3012629Y-106234D01*
X3012939Y-106442D01*
Y-106859D01*
X3012629Y-107068D01*
G01X3025029Y-118734D02*
X3024099Y-118526D01*
X3023169Y-117693D01*
X3022549Y-116234D01*
X3022239Y-114567D01*
X3022549Y-112901D01*
X3023169Y-111442D01*
X3024099Y-110609D01*
X3025029Y-110401D01*
X3025959Y-110609D01*
X3026889Y-111442D01*
X3027509Y-112901D01*
X3027664Y-114567D01*
X3027509Y-116234D01*
X3026889Y-117693D01*
X3025959Y-118526D01*
X3025029Y-118734D01*
G01X3034794D02*
Y-110401D01*
G01Y-112484D02*
X3035414Y-111442D01*
X3036344Y-110609D01*
X3037584Y-110401D01*
X3038669Y-110609D01*
X3039599Y-111442D01*
X3040064Y-112901D01*
Y-118734D01*
G01X2387979Y-88734D02*
Y1628666D01*
X2871579D01*
Y-88734D01*
X2387979D01*
G01Y-28134D02*
X2871579D01*
G01X2387979Y32466D02*
X2871579D01*
G01X2387979Y93066D02*
X2871579D01*
G01X2387979Y153666D02*
X2871579D01*
G01X2387979Y214266D02*
X2871579D01*
G01X2387979Y274866D02*
X2871579D01*
G01X2387979Y335466D02*
X2871579D01*
G01X2387979Y396066D02*
X2871579D01*
G01X2387979Y456666D02*
X2871579D01*
G01X2387979Y517266D02*
X2871579D01*
G01X2387979Y577866D02*
X2871579D01*
G01X2387979Y638466D02*
X2871579D01*
G01X2387979Y699066D02*
X2871579D01*
G01X2387979Y759666D02*
X2871579D01*
G01X2387979Y820266D02*
X2871579D01*
G01X2387979Y880866D02*
X2871579D01*
G01X2387979Y941466D02*
X2871579D01*
G01X2387979Y1002066D02*
X2871579D01*
G01X2387979Y1062666D02*
X2871579D01*
G01X2387979Y1123266D02*
X2871579D01*
G01X2387979Y1183866D02*
X2871579D01*
G01X2387979Y1244466D02*
X2871579D01*
G01X2387979Y1305066D02*
X2871579D01*
G01X2387979Y1365666D02*
X2871579D01*
G01X2387979Y1426266D02*
X2871579D01*
G01X2387979Y1486866D02*
X2871579D01*
G01X2387979Y1547466D02*
X2871579D01*
G01X2387979Y1603666D02*
X2871579D01*
G01X2387979Y1575566D02*
X2871579D01*
G01X2398984Y1556816D02*
Y1569316D01*
X2404874D01*
G01X2402704Y1563274D02*
X2398984D01*
G01X2412469Y1569316D02*
X2416189D01*
G01X2414329D02*
Y1556816D01*
G01X2412469D02*
X2416189D01*
G01X2427659Y1563066D02*
X2430759D01*
Y1559316D01*
X2429829Y1558066D01*
X2428744Y1557233D01*
X2427194Y1556816D01*
X2425644Y1557233D01*
X2424559Y1558066D01*
X2423629Y1559316D01*
X2423009Y1560774D01*
X2422699Y1562441D01*
Y1563899D01*
X2423009Y1565149D01*
X2423629Y1566608D01*
X2424559Y1567858D01*
X2425489Y1568691D01*
X2426729Y1569316D01*
X2427814D01*
X2429054Y1568899D01*
X2429984Y1568066D01*
G01X2435719Y1569316D02*
Y1560358D01*
X2436339Y1558482D01*
X2437579Y1557233D01*
X2439129Y1556816D01*
X2440679Y1557233D01*
X2441919Y1558482D01*
X2442539Y1560358D01*
Y1569316D01*
G01X2448429Y1556816D02*
Y1569316D01*
X2452304D01*
X2453544Y1568691D01*
X2454319Y1567858D01*
X2454629Y1566191D01*
X2454319Y1564524D01*
X2453389Y1563483D01*
X2452304Y1562858D01*
X2448429D01*
G01X2452304D02*
X2454629Y1556816D01*
G01X2467029D02*
X2460829D01*
Y1569316D01*
X2467029D01*
G01X2464549Y1563274D02*
X2460829D01*
G01X2477879Y1575566D02*
Y-88734D01*
G01X2471369Y1609916D02*
Y1622416D01*
X2474469D01*
X2475709Y1621791D01*
X2476639Y1620958D01*
X2477414Y1619708D01*
X2478034Y1618249D01*
X2478189Y1616166D01*
X2478034Y1614083D01*
X2477414Y1612624D01*
X2476639Y1611374D01*
X2475709Y1610541D01*
X2474469Y1609916D01*
X2471369D01*
G01X2484079D02*
Y1622416D01*
X2487954D01*
X2489194Y1621791D01*
X2489969Y1620958D01*
X2490279Y1619291D01*
X2489969Y1617624D01*
X2489039Y1616583D01*
X2487954Y1615958D01*
X2484079D01*
G01X2487954D02*
X2490279Y1609916D01*
G01X2497719Y1622416D02*
X2501439D01*
G01X2499579D02*
Y1609916D01*
G01X2497719D02*
X2501439D01*
G01X2508879Y1622416D02*
Y1609916D01*
X2515079D01*
G01X2521279Y1622416D02*
Y1609916D01*
X2527479D01*
G01X2552589Y1621374D02*
X2551659Y1621999D01*
X2550574Y1622416D01*
X2549334D01*
X2547939Y1621791D01*
X2546854Y1620749D01*
X2546079Y1619499D01*
X2545459Y1617416D01*
X2545304Y1615541D01*
X2545614Y1613666D01*
X2546079Y1612416D01*
X2547009Y1611166D01*
X2548094Y1610333D01*
X2549179Y1609916D01*
X2550264D01*
X2551349Y1610333D01*
X2552279Y1610957D01*
X2553054Y1611791D01*
G01X2558324Y1609916D02*
Y1622416D01*
G01X2564834D02*
Y1609916D01*
G01Y1616166D02*
X2558324D01*
G01X2570104Y1609916D02*
X2573979Y1622416D01*
X2577854Y1609916D01*
G01X2576459Y1614291D02*
X2571499D01*
G01X2583279Y1609916D02*
Y1622416D01*
X2587154D01*
X2588394Y1621791D01*
X2589169Y1620958D01*
X2589479Y1619291D01*
X2589169Y1617624D01*
X2588239Y1616583D01*
X2587154Y1615958D01*
X2583279D01*
G01X2587154D02*
X2589479Y1609916D01*
G01X2598779Y1622416D02*
Y1609916D01*
G01X2595214Y1622416D02*
X2602344D01*
G01X2611179Y1609499D02*
X2610869Y1609708D01*
Y1610124D01*
X2611179Y1610333D01*
X2611489Y1610124D01*
Y1609708D01*
X2611179Y1609499D01*
G01Y1615124D02*
X2610869Y1615333D01*
Y1615749D01*
X2611179Y1615958D01*
X2611489Y1615749D01*
Y1615333D01*
X2611179Y1615124D01*
G01X2635979Y1622416D02*
Y1609916D01*
G01X2632414Y1622416D02*
X2639544D01*
G01X2648379Y1609916D02*
X2647139Y1610124D01*
X2646054Y1610957D01*
X2645124Y1612208D01*
X2644504Y1613666D01*
X2644194Y1615333D01*
Y1616999D01*
X2644504Y1618666D01*
X2645124Y1620124D01*
X2646054Y1621374D01*
X2647139Y1622208D01*
X2648379Y1622416D01*
X2649619Y1622208D01*
X2650704Y1621374D01*
X2651634Y1620124D01*
X2652254Y1618666D01*
X2652564Y1616999D01*
Y1615333D01*
X2652254Y1613666D01*
X2651634Y1612208D01*
X2650704Y1610957D01*
X2649619Y1610124D01*
X2648379Y1609916D01*
G01X2657679D02*
Y1622416D01*
X2661399D01*
X2662639Y1621791D01*
X2663569Y1620333D01*
X2663879Y1618666D01*
X2663569Y1616999D01*
X2662794Y1615749D01*
X2661399Y1615124D01*
X2657679D01*
G01X2685579Y1622416D02*
Y1609916D01*
G01X2683409Y1618249D02*
X2687749D01*
G01X2697979Y1609916D02*
X2697049Y1610124D01*
X2696119Y1610957D01*
X2695499Y1612416D01*
X2695189Y1614083D01*
X2695499Y1615749D01*
X2696119Y1617208D01*
X2697049Y1618041D01*
X2697979Y1618249D01*
X2698909Y1618041D01*
X2699839Y1617208D01*
X2700459Y1615749D01*
X2700614Y1614083D01*
X2700459Y1612416D01*
X2699839Y1610957D01*
X2698909Y1610124D01*
X2697979Y1609916D01*
G01X2724019Y1616583D02*
X2724639Y1617208D01*
X2725104Y1618249D01*
X2725414Y1619708D01*
X2725104Y1620958D01*
X2724484Y1621791D01*
X2723399Y1622416D01*
X2719214D01*
Y1609916D01*
X2724329D01*
X2725414Y1610749D01*
X2726034Y1611999D01*
X2726344Y1613458D01*
X2726034Y1614916D01*
X2725104Y1616166D01*
X2724019Y1616583D01*
X2719214D01*
G01X2735179Y1609916D02*
X2733939Y1610124D01*
X2732854Y1610957D01*
X2731924Y1612208D01*
X2731304Y1613666D01*
X2730994Y1615333D01*
Y1616999D01*
X2731304Y1618666D01*
X2731924Y1620124D01*
X2732854Y1621374D01*
X2733939Y1622208D01*
X2735179Y1622416D01*
X2736419Y1622208D01*
X2737504Y1621374D01*
X2738434Y1620124D01*
X2739054Y1618666D01*
X2739364Y1616999D01*
Y1615333D01*
X2739054Y1613666D01*
X2738434Y1612208D01*
X2737504Y1610957D01*
X2736419Y1610124D01*
X2735179Y1609916D01*
G01X2747579Y1622416D02*
Y1609916D01*
G01X2744014Y1622416D02*
X2751144D01*
G01X2759979D02*
Y1609916D01*
G01X2756414Y1622416D02*
X2763544D01*
G01X2772379Y1609916D02*
X2771139Y1610124D01*
X2770054Y1610957D01*
X2769124Y1612208D01*
X2768504Y1613666D01*
X2768194Y1615333D01*
Y1616999D01*
X2768504Y1618666D01*
X2769124Y1620124D01*
X2770054Y1621374D01*
X2771139Y1622208D01*
X2772379Y1622416D01*
X2773619Y1622208D01*
X2774704Y1621374D01*
X2775634Y1620124D01*
X2776254Y1618666D01*
X2776564Y1616999D01*
Y1615333D01*
X2776254Y1613666D01*
X2775634Y1612208D01*
X2774704Y1610957D01*
X2773619Y1610124D01*
X2772379Y1609916D01*
G01X2780749D02*
Y1622416D01*
X2784779Y1611999D01*
X2788809Y1622416D01*
Y1609916D01*
G01X2507484Y-54267D02*
X2508414Y-53018D01*
X2509499Y-52392D01*
X2510739Y-52184D01*
X2512289Y-52601D01*
X2513374Y-53642D01*
X2513684Y-54892D01*
X2513529Y-56143D01*
X2512909Y-57184D01*
X2509809Y-59267D01*
X2508414Y-60726D01*
X2507484Y-62809D01*
X2507174Y-64684D01*
X2513684D01*
G01X2524689D02*
Y-52184D01*
X2518954Y-61142D01*
X2526704D01*
G01X2531819Y-62809D02*
X2532749Y-63851D01*
X2533834Y-64476D01*
X2535229Y-64684D01*
X2536624Y-64267D01*
X2537709Y-63434D01*
X2538484Y-61976D01*
X2538639Y-60309D01*
X2538329Y-58642D01*
X2537554Y-57601D01*
X2536469Y-56767D01*
X2535384Y-56559D01*
X2534299Y-56767D01*
X2532904Y-57601D01*
X2533369Y-52184D01*
X2537554D01*
G01X2547629Y-65101D02*
X2547319Y-64892D01*
Y-64476D01*
X2547629Y-64267D01*
X2547939Y-64476D01*
Y-64892D01*
X2547629Y-65101D01*
G01X2560029Y-52184D02*
X2558789Y-52601D01*
X2557859Y-53642D01*
X2557239Y-54892D01*
X2556774Y-56559D01*
X2556619Y-58434D01*
X2556774Y-60309D01*
X2557239Y-61976D01*
X2557859Y-63226D01*
X2558789Y-64267D01*
X2560029Y-64684D01*
X2561269Y-64267D01*
X2562199Y-63226D01*
X2562819Y-61976D01*
X2563284Y-60309D01*
X2563439Y-58434D01*
X2563284Y-56559D01*
X2562819Y-54892D01*
X2562199Y-53642D01*
X2561269Y-52601D01*
X2560029Y-52184D01*
G01X2570104Y-56351D02*
X2574754Y-64684D01*
G01Y-56351D02*
X2570104Y-64684D01*
G01X2584829D02*
Y-52184D01*
X2582969Y-54684D01*
G01Y-64684D02*
X2586689D01*
G01X2594284Y-59476D02*
X2595369Y-58017D01*
X2596299Y-57184D01*
X2597539Y-56767D01*
X2598624Y-57184D01*
X2599399Y-58017D01*
X2600019Y-59267D01*
X2600174Y-60726D01*
X2600019Y-61976D01*
X2599399Y-63226D01*
X2598469Y-64267D01*
X2597384Y-64684D01*
X2596144Y-64267D01*
X2595059Y-63018D01*
X2594439Y-61142D01*
X2594284Y-59059D01*
X2594594Y-56351D01*
X2595059Y-54892D01*
X2595834Y-53434D01*
X2596919Y-52392D01*
X2598004Y-52184D01*
X2599089Y-52601D01*
X2599864Y-53642D01*
G01X2606684Y-59476D02*
X2607769Y-58017D01*
X2608699Y-57184D01*
X2609939Y-56767D01*
X2611024Y-57184D01*
X2611799Y-58017D01*
X2612419Y-59267D01*
X2612574Y-60726D01*
X2612419Y-61976D01*
X2611799Y-63226D01*
X2610869Y-64267D01*
X2609784Y-64684D01*
X2608544Y-64267D01*
X2607459Y-63018D01*
X2606839Y-61142D01*
X2606684Y-59059D01*
X2606994Y-56351D01*
X2607459Y-54892D01*
X2608234Y-53434D01*
X2609319Y-52392D01*
X2610404Y-52184D01*
X2611489Y-52601D01*
X2612264Y-53642D01*
G01X2622029Y-65101D02*
X2621719Y-64892D01*
Y-64476D01*
X2622029Y-64267D01*
X2622339Y-64476D01*
Y-64892D01*
X2622029Y-65101D01*
G01X2634429Y-52184D02*
X2633189Y-52601D01*
X2632259Y-53642D01*
X2631639Y-54892D01*
X2631174Y-56559D01*
X2631019Y-58434D01*
X2631174Y-60309D01*
X2631639Y-61976D01*
X2632259Y-63226D01*
X2633189Y-64267D01*
X2634429Y-64684D01*
X2635669Y-64267D01*
X2636599Y-63226D01*
X2637219Y-61976D01*
X2637684Y-60309D01*
X2637839Y-58434D01*
X2637684Y-56559D01*
X2637219Y-54892D01*
X2636599Y-53642D01*
X2635669Y-52601D01*
X2634429Y-52184D01*
G01X2510429Y-4084D02*
Y8416D01*
X2508569Y5916D01*
G01Y-4084D02*
X2512289D01*
G01X2520194Y-2626D02*
X2521279Y-3667D01*
X2522519Y-4084D01*
X2523759Y-3667D01*
X2524844Y-2418D01*
X2525619Y-542D01*
X2525929Y1333D01*
Y3624D01*
X2525619Y5499D01*
X2524844Y7166D01*
X2523914Y7999D01*
X2522829Y8416D01*
X2521589Y7999D01*
X2520659Y7166D01*
X2520039Y5916D01*
X2519729Y4249D01*
X2520039Y2791D01*
X2520814Y1333D01*
X2521744Y499D01*
X2522829Y291D01*
X2524069Y707D01*
X2524999Y1749D01*
X2525929Y3624D01*
G01X2534919Y-4084D02*
X2535229Y-1376D01*
X2535694Y916D01*
X2536314Y2999D01*
X2537089Y5291D01*
X2538329Y8416D01*
X2532129D01*
G01X2547629Y-4501D02*
X2547319Y-4292D01*
Y-3876D01*
X2547629Y-3667D01*
X2547939Y-3876D01*
Y-4292D01*
X2547629Y-4501D01*
G01X2560029Y8416D02*
X2558789Y7999D01*
X2557859Y6958D01*
X2557239Y5708D01*
X2556774Y4041D01*
X2556619Y2166D01*
X2556774Y291D01*
X2557239Y-1376D01*
X2557859Y-2626D01*
X2558789Y-3667D01*
X2560029Y-4084D01*
X2561269Y-3667D01*
X2562199Y-2626D01*
X2562819Y-1376D01*
X2563284Y291D01*
X2563439Y2166D01*
X2563284Y4041D01*
X2562819Y5708D01*
X2562199Y6958D01*
X2561269Y7999D01*
X2560029Y8416D01*
G01X2570104Y4249D02*
X2574754Y-4084D01*
G01Y4249D02*
X2570104Y-4084D01*
G01X2584829D02*
Y8416D01*
X2582969Y5916D01*
G01Y-4084D02*
X2586689D01*
G01X2597229D02*
Y8416D01*
X2595369Y5916D01*
G01Y-4084D02*
X2599089D01*
G01X2606994Y-2626D02*
X2608079Y-3667D01*
X2609319Y-4084D01*
X2610559Y-3667D01*
X2611644Y-2418D01*
X2612419Y-542D01*
X2612729Y1333D01*
Y3624D01*
X2612419Y5499D01*
X2611644Y7166D01*
X2610714Y7999D01*
X2609629Y8416D01*
X2608389Y7999D01*
X2607459Y7166D01*
X2606839Y5916D01*
X2606529Y4249D01*
X2606839Y2791D01*
X2607614Y1333D01*
X2608544Y499D01*
X2609629Y291D01*
X2610869Y707D01*
X2611799Y1749D01*
X2612729Y3624D01*
G01X2622029Y-4501D02*
X2621719Y-4292D01*
Y-3876D01*
X2622029Y-3667D01*
X2622339Y-3876D01*
Y-4292D01*
X2622029Y-4501D01*
G01X2634429Y8416D02*
X2633189Y7999D01*
X2632259Y6958D01*
X2631639Y5708D01*
X2631174Y4041D01*
X2631019Y2166D01*
X2631174Y291D01*
X2631639Y-1376D01*
X2632259Y-2626D01*
X2633189Y-3667D01*
X2634429Y-4084D01*
X2635669Y-3667D01*
X2636599Y-2626D01*
X2637219Y-1376D01*
X2637684Y291D01*
X2637839Y2166D01*
X2637684Y4041D01*
X2637219Y5708D01*
X2636599Y6958D01*
X2635669Y7999D01*
X2634429Y8416D01*
G01X2538329Y1510916D02*
X2532129D01*
Y1523416D01*
X2538329D01*
G01X2535849Y1517374D02*
X2532129D01*
G01X2544529Y1523416D02*
Y1510916D01*
X2550729D01*
G01X2556929Y1523416D02*
Y1510916D01*
X2563129D01*
G01X2570569Y1523416D02*
X2574289D01*
G01X2572429D02*
Y1510916D01*
G01X2570569D02*
X2574289D01*
G01X2581729D02*
Y1523416D01*
X2585449D01*
X2586689Y1522791D01*
X2587619Y1521333D01*
X2587929Y1519666D01*
X2587619Y1517999D01*
X2586844Y1516749D01*
X2585449Y1516124D01*
X2581729D01*
G01X2593974Y1512582D02*
X2595214Y1511541D01*
X2596609Y1510916D01*
X2597849D01*
X2599089Y1511541D01*
X2600019Y1512582D01*
X2600484Y1514041D01*
X2600174Y1515499D01*
X2599399Y1516749D01*
X2598004Y1517583D01*
X2596144Y1517999D01*
X2595059Y1518833D01*
X2594594Y1520291D01*
X2594904Y1521749D01*
X2595679Y1522791D01*
X2596764Y1523416D01*
X2597849D01*
X2598934Y1522999D01*
X2599864Y1521958D01*
G01X2612729Y1510916D02*
X2606529D01*
Y1523416D01*
X2612729D01*
G01X2610249Y1517374D02*
X2606529D01*
G01X2501904Y1584916D02*
X2505779Y1597416D01*
X2509654Y1584916D01*
G01X2508259Y1589291D02*
X2503299D01*
G01X2515079Y1597416D02*
Y1584916D01*
X2521279D01*
G01X2527479Y1597416D02*
Y1584916D01*
X2533679D01*
G01X2551969Y1597416D02*
Y1588458D01*
X2552589Y1586582D01*
X2553829Y1585333D01*
X2555379Y1584916D01*
X2556929Y1585333D01*
X2558169Y1586582D01*
X2558789Y1588458D01*
Y1597416D01*
G01X2564214Y1584916D02*
Y1597416D01*
X2571344Y1584916D01*
Y1597416D01*
G01X2578319D02*
X2582039D01*
G01X2580179D02*
Y1584916D01*
G01X2578319D02*
X2582039D01*
G01X2592579Y1597416D02*
Y1584916D01*
G01X2589014Y1597416D02*
X2596144D01*
G01X2601724Y1586582D02*
X2602964Y1585541D01*
X2604359Y1584916D01*
X2605599D01*
X2606839Y1585541D01*
X2607769Y1586582D01*
X2608234Y1588041D01*
X2607924Y1589499D01*
X2607149Y1590749D01*
X2605754Y1591583D01*
X2603894Y1591999D01*
X2602809Y1592833D01*
X2602344Y1594291D01*
X2602654Y1595749D01*
X2603429Y1596791D01*
X2604514Y1597416D01*
X2605599D01*
X2606684Y1596999D01*
X2607614Y1595958D01*
G01X2625904Y1584916D02*
X2629779Y1597416D01*
X2633654Y1584916D01*
G01X2632259Y1589291D02*
X2627299D01*
G01X2639079Y1584916D02*
Y1597416D01*
X2642954D01*
X2644194Y1596791D01*
X2644969Y1595958D01*
X2645279Y1594291D01*
X2644969Y1592624D01*
X2644039Y1591583D01*
X2642954Y1590958D01*
X2639079D01*
G01X2642954D02*
X2645279Y1584916D01*
G01X2657679D02*
X2651479D01*
Y1597416D01*
X2657679D01*
G01X2655199Y1591374D02*
X2651479D01*
G01X2677519Y1597416D02*
X2681239D01*
G01X2679379D02*
Y1584916D01*
G01X2677519D02*
X2681239D01*
G01X2688214D02*
Y1597416D01*
X2695344Y1584916D01*
Y1597416D01*
G01X2712549Y1584916D02*
Y1597416D01*
X2716579Y1586999D01*
X2720609Y1597416D01*
Y1584916D01*
G01X2727119Y1597416D02*
X2730839D01*
G01X2728979D02*
Y1584916D01*
G01X2727119D02*
X2730839D01*
G01X2738279Y1597416D02*
Y1584916D01*
X2744479D01*
G01X2750524Y1586582D02*
X2751764Y1585541D01*
X2753159Y1584916D01*
X2754399D01*
X2755639Y1585541D01*
X2756569Y1586582D01*
X2757034Y1588041D01*
X2756724Y1589499D01*
X2755949Y1590749D01*
X2754554Y1591583D01*
X2752694Y1591999D01*
X2751609Y1592833D01*
X2751144Y1594291D01*
X2751454Y1595749D01*
X2752229Y1596791D01*
X2753314Y1597416D01*
X2754399D01*
X2755484Y1596999D01*
X2756414Y1595958D01*
G01X2549489Y56516D02*
Y69016D01*
X2543754Y60058D01*
X2551504D01*
G01X2560029Y69016D02*
X2558789Y68599D01*
X2557859Y67558D01*
X2557239Y66308D01*
X2556774Y64641D01*
X2556619Y62766D01*
X2556774Y60891D01*
X2557239Y59224D01*
X2557859Y57974D01*
X2558789Y56933D01*
X2560029Y56516D01*
X2561269Y56933D01*
X2562199Y57974D01*
X2562819Y59224D01*
X2563284Y60891D01*
X2563439Y62766D01*
X2563284Y64641D01*
X2562819Y66308D01*
X2562199Y67558D01*
X2561269Y68599D01*
X2560029Y69016D01*
G01X2574289Y56516D02*
Y69016D01*
X2568554Y60058D01*
X2576304D01*
G01X2584829Y56099D02*
X2584519Y56308D01*
Y56724D01*
X2584829Y56933D01*
X2585139Y56724D01*
Y56308D01*
X2584829Y56099D01*
G01X2597229Y69016D02*
X2595989Y68599D01*
X2595059Y67558D01*
X2594439Y66308D01*
X2593974Y64641D01*
X2593819Y62766D01*
X2593974Y60891D01*
X2594439Y59224D01*
X2595059Y57974D01*
X2595989Y56933D01*
X2597229Y56516D01*
X2598469Y56933D01*
X2599399Y57974D01*
X2600019Y59224D01*
X2600484Y60891D01*
X2600639Y62766D01*
X2600484Y64641D01*
X2600019Y66308D01*
X2599399Y67558D01*
X2598469Y68599D01*
X2597229Y69016D01*
G01X2547629Y117116D02*
Y129616D01*
X2545769Y127116D01*
G01Y117116D02*
X2549489D01*
G01X2560029D02*
Y129616D01*
X2558169Y127116D01*
G01Y117116D02*
X2561889D01*
G01X2572429D02*
Y129616D01*
X2570569Y127116D01*
G01Y117116D02*
X2574289D01*
G01X2584829Y116699D02*
X2584519Y116908D01*
Y117324D01*
X2584829Y117533D01*
X2585139Y117324D01*
Y116908D01*
X2584829Y116699D01*
G01X2597229Y129616D02*
X2595989Y129199D01*
X2595059Y128158D01*
X2594439Y126908D01*
X2593974Y125241D01*
X2593819Y123366D01*
X2593974Y121491D01*
X2594439Y119824D01*
X2595059Y118574D01*
X2595989Y117533D01*
X2597229Y117116D01*
X2598469Y117533D01*
X2599399Y118574D01*
X2600019Y119824D01*
X2600484Y121491D01*
X2600639Y123366D01*
X2600484Y125241D01*
X2600019Y126908D01*
X2599399Y128158D01*
X2598469Y129199D01*
X2597229Y129616D01*
G01X2551194Y179174D02*
X2552279Y178133D01*
X2553519Y177716D01*
X2554759Y178133D01*
X2555844Y179382D01*
X2556619Y181258D01*
X2556929Y183133D01*
Y185424D01*
X2556619Y187299D01*
X2555844Y188966D01*
X2554914Y189799D01*
X2553829Y190216D01*
X2552589Y189799D01*
X2551659Y188966D01*
X2551039Y187716D01*
X2550729Y186049D01*
X2551039Y184591D01*
X2551814Y183133D01*
X2552744Y182299D01*
X2553829Y182091D01*
X2555069Y182507D01*
X2555999Y183549D01*
X2556929Y185424D01*
G01X2565919Y177716D02*
X2566229Y180424D01*
X2566694Y182716D01*
X2567314Y184799D01*
X2568089Y187091D01*
X2569329Y190216D01*
X2563129D01*
G01X2578629Y177299D02*
X2578319Y177508D01*
Y177924D01*
X2578629Y178133D01*
X2578939Y177924D01*
Y177508D01*
X2578629Y177299D01*
G01X2591029Y190216D02*
X2589789Y189799D01*
X2588859Y188758D01*
X2588239Y187508D01*
X2587774Y185841D01*
X2587619Y183966D01*
X2587774Y182091D01*
X2588239Y180424D01*
X2588859Y179174D01*
X2589789Y178133D01*
X2591029Y177716D01*
X2592269Y178133D01*
X2593199Y179174D01*
X2593819Y180424D01*
X2594284Y182091D01*
X2594439Y183966D01*
X2594284Y185841D01*
X2593819Y187508D01*
X2593199Y188758D01*
X2592269Y189799D01*
X2591029Y190216D01*
G01X2551194Y239774D02*
X2552279Y238733D01*
X2553519Y238316D01*
X2554759Y238733D01*
X2555844Y239982D01*
X2556619Y241858D01*
X2556929Y243733D01*
Y246024D01*
X2556619Y247899D01*
X2555844Y249566D01*
X2554914Y250399D01*
X2553829Y250816D01*
X2552589Y250399D01*
X2551659Y249566D01*
X2551039Y248316D01*
X2550729Y246649D01*
X2551039Y245191D01*
X2551814Y243733D01*
X2552744Y242899D01*
X2553829Y242691D01*
X2555069Y243107D01*
X2555999Y244149D01*
X2556929Y246024D01*
G01X2568089Y238316D02*
Y250816D01*
X2562354Y241858D01*
X2570104D01*
G01X2578629Y237899D02*
X2578319Y238108D01*
Y238524D01*
X2578629Y238733D01*
X2578939Y238524D01*
Y238108D01*
X2578629Y237899D01*
G01X2591029Y250816D02*
X2589789Y250399D01*
X2588859Y249358D01*
X2588239Y248108D01*
X2587774Y246441D01*
X2587619Y244566D01*
X2587774Y242691D01*
X2588239Y241024D01*
X2588859Y239774D01*
X2589789Y238733D01*
X2591029Y238316D01*
X2592269Y238733D01*
X2593199Y239774D01*
X2593819Y241024D01*
X2594284Y242691D01*
X2594439Y244566D01*
X2594284Y246441D01*
X2593819Y248108D01*
X2593199Y249358D01*
X2592269Y250399D01*
X2591029Y250816D01*
G01X2551194Y300374D02*
X2552279Y299333D01*
X2553519Y298916D01*
X2554759Y299333D01*
X2555844Y300582D01*
X2556619Y302458D01*
X2556929Y304333D01*
Y306624D01*
X2556619Y308499D01*
X2555844Y310166D01*
X2554914Y310999D01*
X2553829Y311416D01*
X2552589Y310999D01*
X2551659Y310166D01*
X2551039Y308916D01*
X2550729Y307249D01*
X2551039Y305791D01*
X2551814Y304333D01*
X2552744Y303499D01*
X2553829Y303291D01*
X2555069Y303707D01*
X2555999Y304749D01*
X2556929Y306624D01*
G01X2562819Y301416D02*
X2563749Y299957D01*
X2564989Y299124D01*
X2566384Y298916D01*
X2567624Y299124D01*
X2568864Y300166D01*
X2569639Y301416D01*
X2569794Y302666D01*
X2569484Y304124D01*
X2568399Y305166D01*
X2567314Y305583D01*
X2565919D01*
G01X2567314D02*
X2568244Y306208D01*
X2569019Y307249D01*
X2569329Y308499D01*
X2569019Y309749D01*
X2568244Y310791D01*
X2566849Y311416D01*
X2565454Y311208D01*
X2564059Y310374D01*
G01X2578629Y298499D02*
X2578319Y298708D01*
Y299124D01*
X2578629Y299333D01*
X2578939Y299124D01*
Y298708D01*
X2578629Y298499D01*
G01X2591029Y311416D02*
X2589789Y310999D01*
X2588859Y309958D01*
X2588239Y308708D01*
X2587774Y307041D01*
X2587619Y305166D01*
X2587774Y303291D01*
X2588239Y301624D01*
X2588859Y300374D01*
X2589789Y299333D01*
X2591029Y298916D01*
X2592269Y299333D01*
X2593199Y300374D01*
X2593819Y301624D01*
X2594284Y303291D01*
X2594439Y305166D01*
X2594284Y307041D01*
X2593819Y308708D01*
X2593199Y309958D01*
X2592269Y310999D01*
X2591029Y311416D01*
G01X2553829Y359516D02*
X2554914Y359724D01*
X2556154Y360349D01*
X2556929Y361391D01*
X2557239Y362849D01*
X2556929Y364307D01*
X2555999Y365558D01*
X2554604Y366183D01*
X2553054D01*
X2552124Y366599D01*
X2551349Y367641D01*
X2551039Y369099D01*
X2551504Y370558D01*
X2552589Y371599D01*
X2553829Y372016D01*
X2555069Y371599D01*
X2556154Y370558D01*
X2556619Y369099D01*
X2556309Y367641D01*
X2555534Y366599D01*
X2554604Y366183D01*
X2553054D01*
X2551659Y365558D01*
X2550729Y364307D01*
X2550419Y362849D01*
X2550729Y361391D01*
X2551504Y360349D01*
X2552744Y359724D01*
X2553829Y359516D01*
G01X2565919D02*
X2566229Y362224D01*
X2566694Y364516D01*
X2567314Y366599D01*
X2568089Y368891D01*
X2569329Y372016D01*
X2563129D01*
G01X2578629Y359099D02*
X2578319Y359308D01*
Y359724D01*
X2578629Y359933D01*
X2578939Y359724D01*
Y359308D01*
X2578629Y359099D01*
G01X2591029Y372016D02*
X2589789Y371599D01*
X2588859Y370558D01*
X2588239Y369308D01*
X2587774Y367641D01*
X2587619Y365766D01*
X2587774Y363891D01*
X2588239Y362224D01*
X2588859Y360974D01*
X2589789Y359933D01*
X2591029Y359516D01*
X2592269Y359933D01*
X2593199Y360974D01*
X2593819Y362224D01*
X2594284Y363891D01*
X2594439Y365766D01*
X2594284Y367641D01*
X2593819Y369308D01*
X2593199Y370558D01*
X2592269Y371599D01*
X2591029Y372016D01*
G01X2553829Y420116D02*
X2554914Y420324D01*
X2556154Y420949D01*
X2556929Y421991D01*
X2557239Y423449D01*
X2556929Y424907D01*
X2555999Y426158D01*
X2554604Y426783D01*
X2553054D01*
X2552124Y427199D01*
X2551349Y428241D01*
X2551039Y429699D01*
X2551504Y431158D01*
X2552589Y432199D01*
X2553829Y432616D01*
X2555069Y432199D01*
X2556154Y431158D01*
X2556619Y429699D01*
X2556309Y428241D01*
X2555534Y427199D01*
X2554604Y426783D01*
X2553054D01*
X2551659Y426158D01*
X2550729Y424907D01*
X2550419Y423449D01*
X2550729Y421991D01*
X2551504Y420949D01*
X2552744Y420324D01*
X2553829Y420116D01*
G01X2563284Y425324D02*
X2564369Y426783D01*
X2565299Y427616D01*
X2566539Y428033D01*
X2567624Y427616D01*
X2568399Y426783D01*
X2569019Y425533D01*
X2569174Y424074D01*
X2569019Y422824D01*
X2568399Y421574D01*
X2567469Y420533D01*
X2566384Y420116D01*
X2565144Y420533D01*
X2564059Y421782D01*
X2563439Y423658D01*
X2563284Y425741D01*
X2563594Y428449D01*
X2564059Y429908D01*
X2564834Y431366D01*
X2565919Y432408D01*
X2567004Y432616D01*
X2568089Y432199D01*
X2568864Y431158D01*
G01X2578629Y419699D02*
X2578319Y419908D01*
Y420324D01*
X2578629Y420533D01*
X2578939Y420324D01*
Y419908D01*
X2578629Y419699D01*
G01X2591029Y432616D02*
X2589789Y432199D01*
X2588859Y431158D01*
X2588239Y429908D01*
X2587774Y428241D01*
X2587619Y426366D01*
X2587774Y424491D01*
X2588239Y422824D01*
X2588859Y421574D01*
X2589789Y420533D01*
X2591029Y420116D01*
X2592269Y420533D01*
X2593199Y421574D01*
X2593819Y422824D01*
X2594284Y424491D01*
X2594439Y426366D01*
X2594284Y428241D01*
X2593819Y429908D01*
X2593199Y431158D01*
X2592269Y432199D01*
X2591029Y432616D01*
G01X2550419Y482591D02*
X2551349Y481549D01*
X2552434Y480924D01*
X2553829Y480716D01*
X2555224Y481133D01*
X2556309Y481966D01*
X2557084Y483424D01*
X2557239Y485091D01*
X2556929Y486758D01*
X2556154Y487799D01*
X2555069Y488633D01*
X2553984Y488841D01*
X2552899Y488633D01*
X2551504Y487799D01*
X2551969Y493216D01*
X2556154D01*
G01X2562819Y483216D02*
X2563749Y481757D01*
X2564989Y480924D01*
X2566384Y480716D01*
X2567624Y480924D01*
X2568864Y481966D01*
X2569639Y483216D01*
X2569794Y484466D01*
X2569484Y485924D01*
X2568399Y486966D01*
X2567314Y487383D01*
X2565919D01*
G01X2567314D02*
X2568244Y488008D01*
X2569019Y489049D01*
X2569329Y490299D01*
X2569019Y491549D01*
X2568244Y492591D01*
X2566849Y493216D01*
X2565454Y493008D01*
X2564059Y492174D01*
G01X2578629Y480299D02*
X2578319Y480508D01*
Y480924D01*
X2578629Y481133D01*
X2578939Y480924D01*
Y480508D01*
X2578629Y480299D01*
G01X2591029Y493216D02*
X2589789Y492799D01*
X2588859Y491758D01*
X2588239Y490508D01*
X2587774Y488841D01*
X2587619Y486966D01*
X2587774Y485091D01*
X2588239Y483424D01*
X2588859Y482174D01*
X2589789Y481133D01*
X2591029Y480716D01*
X2592269Y481133D01*
X2593199Y482174D01*
X2593819Y483424D01*
X2594284Y485091D01*
X2594439Y486966D01*
X2594284Y488841D01*
X2593819Y490508D01*
X2593199Y491758D01*
X2592269Y492799D01*
X2591029Y493216D01*
G01X2550419Y543816D02*
X2551349Y542357D01*
X2552589Y541524D01*
X2553984Y541316D01*
X2555224Y541524D01*
X2556464Y542566D01*
X2557239Y543816D01*
X2557394Y545066D01*
X2557084Y546524D01*
X2555999Y547566D01*
X2554914Y547983D01*
X2553519D01*
G01X2554914D02*
X2555844Y548608D01*
X2556619Y549649D01*
X2556929Y550899D01*
X2556619Y552149D01*
X2555844Y553191D01*
X2554449Y553816D01*
X2553054Y553608D01*
X2551659Y552774D01*
G01X2565919Y541316D02*
X2566229Y544024D01*
X2566694Y546316D01*
X2567314Y548399D01*
X2568089Y550691D01*
X2569329Y553816D01*
X2563129D01*
G01X2578629Y540899D02*
X2578319Y541108D01*
Y541524D01*
X2578629Y541733D01*
X2578939Y541524D01*
Y541108D01*
X2578629Y540899D01*
G01X2591029Y553816D02*
X2589789Y553399D01*
X2588859Y552358D01*
X2588239Y551108D01*
X2587774Y549441D01*
X2587619Y547566D01*
X2587774Y545691D01*
X2588239Y544024D01*
X2588859Y542774D01*
X2589789Y541733D01*
X2591029Y541316D01*
X2592269Y541733D01*
X2593199Y542774D01*
X2593819Y544024D01*
X2594284Y545691D01*
X2594439Y547566D01*
X2594284Y549441D01*
X2593819Y551108D01*
X2593199Y552358D01*
X2592269Y553399D01*
X2591029Y553816D01*
G01X2544684Y612333D02*
X2545614Y613582D01*
X2546699Y614208D01*
X2547939Y614416D01*
X2549489Y613999D01*
X2550574Y612958D01*
X2550884Y611708D01*
X2550729Y610457D01*
X2550109Y609416D01*
X2547009Y607333D01*
X2545614Y605874D01*
X2544684Y603791D01*
X2544374Y601916D01*
X2550884D01*
G01X2557084Y612333D02*
X2558014Y613582D01*
X2559099Y614208D01*
X2560339Y614416D01*
X2561889Y613999D01*
X2562974Y612958D01*
X2563284Y611708D01*
X2563129Y610457D01*
X2562509Y609416D01*
X2559409Y607333D01*
X2558014Y605874D01*
X2557084Y603791D01*
X2556774Y601916D01*
X2563284D01*
G01X2569019Y603791D02*
X2569949Y602749D01*
X2571034Y602124D01*
X2572429Y601916D01*
X2573824Y602333D01*
X2574909Y603166D01*
X2575684Y604624D01*
X2575839Y606291D01*
X2575529Y607958D01*
X2574754Y608999D01*
X2573669Y609833D01*
X2572584Y610041D01*
X2571499Y609833D01*
X2570104Y608999D01*
X2570569Y614416D01*
X2574754D01*
G01X2584829Y601499D02*
X2584519Y601708D01*
Y602124D01*
X2584829Y602333D01*
X2585139Y602124D01*
Y601708D01*
X2584829Y601499D01*
G01X2597229Y614416D02*
X2595989Y613999D01*
X2595059Y612958D01*
X2594439Y611708D01*
X2593974Y610041D01*
X2593819Y608166D01*
X2593974Y606291D01*
X2594439Y604624D01*
X2595059Y603374D01*
X2595989Y602333D01*
X2597229Y601916D01*
X2598469Y602333D01*
X2599399Y603374D01*
X2600019Y604624D01*
X2600484Y606291D01*
X2600639Y608166D01*
X2600484Y610041D01*
X2600019Y611708D01*
X2599399Y612958D01*
X2598469Y613999D01*
X2597229Y614416D01*
G01X2547629Y662516D02*
Y675016D01*
X2545769Y672516D01*
G01Y662516D02*
X2549489D01*
G01X2557084Y667724D02*
X2558169Y669183D01*
X2559099Y670016D01*
X2560339Y670433D01*
X2561424Y670016D01*
X2562199Y669183D01*
X2562819Y667933D01*
X2562974Y666474D01*
X2562819Y665224D01*
X2562199Y663974D01*
X2561269Y662933D01*
X2560184Y662516D01*
X2558944Y662933D01*
X2557859Y664182D01*
X2557239Y666058D01*
X2557084Y668141D01*
X2557394Y670849D01*
X2557859Y672308D01*
X2558634Y673766D01*
X2559719Y674808D01*
X2560804Y675016D01*
X2561889Y674599D01*
X2562664Y673558D01*
G01X2572429Y662516D02*
X2573514Y662724D01*
X2574754Y663349D01*
X2575529Y664391D01*
X2575839Y665849D01*
X2575529Y667307D01*
X2574599Y668558D01*
X2573204Y669183D01*
X2571654D01*
X2570724Y669599D01*
X2569949Y670641D01*
X2569639Y672099D01*
X2570104Y673558D01*
X2571189Y674599D01*
X2572429Y675016D01*
X2573669Y674599D01*
X2574754Y673558D01*
X2575219Y672099D01*
X2574909Y670641D01*
X2574134Y669599D01*
X2573204Y669183D01*
X2571654D01*
X2570259Y668558D01*
X2569329Y667307D01*
X2569019Y665849D01*
X2569329Y664391D01*
X2570104Y663349D01*
X2571344Y662724D01*
X2572429Y662516D01*
G01X2584829Y662099D02*
X2584519Y662308D01*
Y662724D01*
X2584829Y662933D01*
X2585139Y662724D01*
Y662308D01*
X2584829Y662099D01*
G01X2597229Y675016D02*
X2595989Y674599D01*
X2595059Y673558D01*
X2594439Y672308D01*
X2593974Y670641D01*
X2593819Y668766D01*
X2593974Y666891D01*
X2594439Y665224D01*
X2595059Y663974D01*
X2595989Y662933D01*
X2597229Y662516D01*
X2598469Y662933D01*
X2599399Y663974D01*
X2600019Y665224D01*
X2600484Y666891D01*
X2600639Y668766D01*
X2600484Y670641D01*
X2600019Y672308D01*
X2599399Y673558D01*
X2598469Y674599D01*
X2597229Y675016D01*
G01X2547629Y723116D02*
Y735616D01*
X2545769Y733116D01*
G01Y723116D02*
X2549489D01*
G01X2557084Y728324D02*
X2558169Y729783D01*
X2559099Y730616D01*
X2560339Y731033D01*
X2561424Y730616D01*
X2562199Y729783D01*
X2562819Y728533D01*
X2562974Y727074D01*
X2562819Y725824D01*
X2562199Y724574D01*
X2561269Y723533D01*
X2560184Y723116D01*
X2558944Y723533D01*
X2557859Y724782D01*
X2557239Y726658D01*
X2557084Y728741D01*
X2557394Y731449D01*
X2557859Y732908D01*
X2558634Y734366D01*
X2559719Y735408D01*
X2560804Y735616D01*
X2561889Y735199D01*
X2562664Y734158D01*
G01X2569484Y728324D02*
X2570569Y729783D01*
X2571499Y730616D01*
X2572739Y731033D01*
X2573824Y730616D01*
X2574599Y729783D01*
X2575219Y728533D01*
X2575374Y727074D01*
X2575219Y725824D01*
X2574599Y724574D01*
X2573669Y723533D01*
X2572584Y723116D01*
X2571344Y723533D01*
X2570259Y724782D01*
X2569639Y726658D01*
X2569484Y728741D01*
X2569794Y731449D01*
X2570259Y732908D01*
X2571034Y734366D01*
X2572119Y735408D01*
X2573204Y735616D01*
X2574289Y735199D01*
X2575064Y734158D01*
G01X2584829Y722699D02*
X2584519Y722908D01*
Y723324D01*
X2584829Y723533D01*
X2585139Y723324D01*
Y722908D01*
X2584829Y722699D01*
G01X2597229Y735616D02*
X2595989Y735199D01*
X2595059Y734158D01*
X2594439Y732908D01*
X2593974Y731241D01*
X2593819Y729366D01*
X2593974Y727491D01*
X2594439Y725824D01*
X2595059Y724574D01*
X2595989Y723533D01*
X2597229Y723116D01*
X2598469Y723533D01*
X2599399Y724574D01*
X2600019Y725824D01*
X2600484Y727491D01*
X2600639Y729366D01*
X2600484Y731241D01*
X2600019Y732908D01*
X2599399Y734158D01*
X2598469Y735199D01*
X2597229Y735616D01*
G01X2547629Y783716D02*
Y796216D01*
X2545769Y793716D01*
G01Y783716D02*
X2549489D01*
G01X2561889D02*
Y796216D01*
X2556154Y787258D01*
X2563904D01*
G01X2572429Y796216D02*
X2571189Y795799D01*
X2570259Y794758D01*
X2569639Y793508D01*
X2569174Y791841D01*
X2569019Y789966D01*
X2569174Y788091D01*
X2569639Y786424D01*
X2570259Y785174D01*
X2571189Y784133D01*
X2572429Y783716D01*
X2573669Y784133D01*
X2574599Y785174D01*
X2575219Y786424D01*
X2575684Y788091D01*
X2575839Y789966D01*
X2575684Y791841D01*
X2575219Y793508D01*
X2574599Y794758D01*
X2573669Y795799D01*
X2572429Y796216D01*
G01X2584829Y783299D02*
X2584519Y783508D01*
Y783924D01*
X2584829Y784133D01*
X2585139Y783924D01*
Y783508D01*
X2584829Y783299D01*
G01X2597229Y796216D02*
X2595989Y795799D01*
X2595059Y794758D01*
X2594439Y793508D01*
X2593974Y791841D01*
X2593819Y789966D01*
X2593974Y788091D01*
X2594439Y786424D01*
X2595059Y785174D01*
X2595989Y784133D01*
X2597229Y783716D01*
X2598469Y784133D01*
X2599399Y785174D01*
X2600019Y786424D01*
X2600484Y788091D01*
X2600639Y789966D01*
X2600484Y791841D01*
X2600019Y793508D01*
X2599399Y794758D01*
X2598469Y795799D01*
X2597229Y796216D01*
G01X2547629Y844316D02*
Y856816D01*
X2545769Y854316D01*
G01Y844316D02*
X2549489D01*
G01X2556619Y846816D02*
X2557549Y845357D01*
X2558789Y844524D01*
X2560184Y844316D01*
X2561424Y844524D01*
X2562664Y845566D01*
X2563439Y846816D01*
X2563594Y848066D01*
X2563284Y849524D01*
X2562199Y850566D01*
X2561114Y850983D01*
X2559719D01*
G01X2561114D02*
X2562044Y851608D01*
X2562819Y852649D01*
X2563129Y853899D01*
X2562819Y855149D01*
X2562044Y856191D01*
X2560649Y856816D01*
X2559254Y856608D01*
X2557859Y855774D01*
G01X2572429Y844316D02*
X2573514Y844524D01*
X2574754Y845149D01*
X2575529Y846191D01*
X2575839Y847649D01*
X2575529Y849107D01*
X2574599Y850358D01*
X2573204Y850983D01*
X2571654D01*
X2570724Y851399D01*
X2569949Y852441D01*
X2569639Y853899D01*
X2570104Y855358D01*
X2571189Y856399D01*
X2572429Y856816D01*
X2573669Y856399D01*
X2574754Y855358D01*
X2575219Y853899D01*
X2574909Y852441D01*
X2574134Y851399D01*
X2573204Y850983D01*
X2571654D01*
X2570259Y850358D01*
X2569329Y849107D01*
X2569019Y847649D01*
X2569329Y846191D01*
X2570104Y845149D01*
X2571344Y844524D01*
X2572429Y844316D01*
G01X2584829Y843899D02*
X2584519Y844108D01*
Y844524D01*
X2584829Y844733D01*
X2585139Y844524D01*
Y844108D01*
X2584829Y843899D01*
G01X2597229Y856816D02*
X2595989Y856399D01*
X2595059Y855358D01*
X2594439Y854108D01*
X2593974Y852441D01*
X2593819Y850566D01*
X2593974Y848691D01*
X2594439Y847024D01*
X2595059Y845774D01*
X2595989Y844733D01*
X2597229Y844316D01*
X2598469Y844733D01*
X2599399Y845774D01*
X2600019Y847024D01*
X2600484Y848691D01*
X2600639Y850566D01*
X2600484Y852441D01*
X2600019Y854108D01*
X2599399Y855358D01*
X2598469Y856399D01*
X2597229Y856816D01*
G01X2547629Y904916D02*
Y917416D01*
X2545769Y914916D01*
G01Y904916D02*
X2549489D01*
G01X2560029D02*
Y917416D01*
X2558169Y914916D01*
G01Y904916D02*
X2561889D01*
G01X2569794Y906374D02*
X2570879Y905333D01*
X2572119Y904916D01*
X2573359Y905333D01*
X2574444Y906582D01*
X2575219Y908458D01*
X2575529Y910333D01*
Y912624D01*
X2575219Y914499D01*
X2574444Y916166D01*
X2573514Y916999D01*
X2572429Y917416D01*
X2571189Y916999D01*
X2570259Y916166D01*
X2569639Y914916D01*
X2569329Y913249D01*
X2569639Y911791D01*
X2570414Y910333D01*
X2571344Y909499D01*
X2572429Y909291D01*
X2573669Y909707D01*
X2574599Y910749D01*
X2575529Y912624D01*
G01X2584829Y904499D02*
X2584519Y904708D01*
Y905124D01*
X2584829Y905333D01*
X2585139Y905124D01*
Y904708D01*
X2584829Y904499D01*
G01X2597229Y917416D02*
X2595989Y916999D01*
X2595059Y915958D01*
X2594439Y914708D01*
X2593974Y913041D01*
X2593819Y911166D01*
X2593974Y909291D01*
X2594439Y907624D01*
X2595059Y906374D01*
X2595989Y905333D01*
X2597229Y904916D01*
X2598469Y905333D01*
X2599399Y906374D01*
X2600019Y907624D01*
X2600484Y909291D01*
X2600639Y911166D01*
X2600484Y913041D01*
X2600019Y914708D01*
X2599399Y915958D01*
X2598469Y916999D01*
X2597229Y917416D01*
G01X2544684Y975933D02*
X2545614Y977182D01*
X2546699Y977808D01*
X2547939Y978016D01*
X2549489Y977599D01*
X2550574Y976558D01*
X2550884Y975308D01*
X2550729Y974057D01*
X2550109Y973016D01*
X2547009Y970933D01*
X2545614Y969474D01*
X2544684Y967391D01*
X2544374Y965516D01*
X2550884D01*
G01X2557394Y966974D02*
X2558479Y965933D01*
X2559719Y965516D01*
X2560959Y965933D01*
X2562044Y967182D01*
X2562819Y969058D01*
X2563129Y970933D01*
Y973224D01*
X2562819Y975099D01*
X2562044Y976766D01*
X2561114Y977599D01*
X2560029Y978016D01*
X2558789Y977599D01*
X2557859Y976766D01*
X2557239Y975516D01*
X2556929Y973849D01*
X2557239Y972391D01*
X2558014Y970933D01*
X2558944Y970099D01*
X2560029Y969891D01*
X2561269Y970307D01*
X2562199Y971349D01*
X2563129Y973224D01*
G01X2572429Y965099D02*
X2572119Y965308D01*
Y965724D01*
X2572429Y965933D01*
X2572739Y965724D01*
Y965308D01*
X2572429Y965099D01*
G01X2584829Y965516D02*
Y978016D01*
X2582969Y975516D01*
G01Y965516D02*
X2586689D01*
G01X2593819Y968016D02*
X2594749Y966557D01*
X2595989Y965724D01*
X2597384Y965516D01*
X2598624Y965724D01*
X2599864Y966766D01*
X2600639Y968016D01*
X2600794Y969266D01*
X2600484Y970724D01*
X2599399Y971766D01*
X2598314Y972183D01*
X2596919D01*
G01X2598314D02*
X2599244Y972808D01*
X2600019Y973849D01*
X2600329Y975099D01*
X2600019Y976349D01*
X2599244Y977391D01*
X2597849Y978016D01*
X2596454Y977808D01*
X2595059Y976974D01*
G01X2544684Y1036533D02*
X2545614Y1037782D01*
X2546699Y1038408D01*
X2547939Y1038616D01*
X2549489Y1038199D01*
X2550574Y1037158D01*
X2550884Y1035908D01*
X2550729Y1034657D01*
X2550109Y1033616D01*
X2547009Y1031533D01*
X2545614Y1030074D01*
X2544684Y1027991D01*
X2544374Y1026116D01*
X2550884D01*
G01X2560029D02*
X2561114Y1026324D01*
X2562354Y1026949D01*
X2563129Y1027991D01*
X2563439Y1029449D01*
X2563129Y1030907D01*
X2562199Y1032158D01*
X2560804Y1032783D01*
X2559254D01*
X2558324Y1033199D01*
X2557549Y1034241D01*
X2557239Y1035699D01*
X2557704Y1037158D01*
X2558789Y1038199D01*
X2560029Y1038616D01*
X2561269Y1038199D01*
X2562354Y1037158D01*
X2562819Y1035699D01*
X2562509Y1034241D01*
X2561734Y1033199D01*
X2560804Y1032783D01*
X2559254D01*
X2557859Y1032158D01*
X2556929Y1030907D01*
X2556619Y1029449D01*
X2556929Y1027991D01*
X2557704Y1026949D01*
X2558944Y1026324D01*
X2560029Y1026116D01*
G01X2572429Y1025699D02*
X2572119Y1025908D01*
Y1026324D01*
X2572429Y1026533D01*
X2572739Y1026324D01*
Y1025908D01*
X2572429Y1025699D01*
G01X2581419Y1028616D02*
X2582349Y1027157D01*
X2583589Y1026324D01*
X2584984Y1026116D01*
X2586224Y1026324D01*
X2587464Y1027366D01*
X2588239Y1028616D01*
X2588394Y1029866D01*
X2588084Y1031324D01*
X2586999Y1032366D01*
X2585914Y1032783D01*
X2584519D01*
G01X2585914D02*
X2586844Y1033408D01*
X2587619Y1034449D01*
X2587929Y1035699D01*
X2587619Y1036949D01*
X2586844Y1037991D01*
X2585449Y1038616D01*
X2584054Y1038408D01*
X2582659Y1037574D01*
G01X2599089Y1026116D02*
Y1038616D01*
X2593354Y1029658D01*
X2601104D01*
G01X2550884Y1097133D02*
X2551814Y1098382D01*
X2552899Y1099008D01*
X2554139Y1099216D01*
X2555689Y1098799D01*
X2556774Y1097758D01*
X2557084Y1096508D01*
X2556929Y1095257D01*
X2556309Y1094216D01*
X2553209Y1092133D01*
X2551814Y1090674D01*
X2550884Y1088591D01*
X2550574Y1086716D01*
X2557084D01*
G01X2566229D02*
X2567314Y1086924D01*
X2568554Y1087549D01*
X2569329Y1088591D01*
X2569639Y1090049D01*
X2569329Y1091507D01*
X2568399Y1092758D01*
X2567004Y1093383D01*
X2565454D01*
X2564524Y1093799D01*
X2563749Y1094841D01*
X2563439Y1096299D01*
X2563904Y1097758D01*
X2564989Y1098799D01*
X2566229Y1099216D01*
X2567469Y1098799D01*
X2568554Y1097758D01*
X2569019Y1096299D01*
X2568709Y1094841D01*
X2567934Y1093799D01*
X2567004Y1093383D01*
X2565454D01*
X2564059Y1092758D01*
X2563129Y1091507D01*
X2562819Y1090049D01*
X2563129Y1088591D01*
X2563904Y1087549D01*
X2565144Y1086924D01*
X2566229Y1086716D01*
G01X2578629Y1086299D02*
X2578319Y1086508D01*
Y1086924D01*
X2578629Y1087133D01*
X2578939Y1086924D01*
Y1086508D01*
X2578629Y1086299D01*
G01X2591029Y1099216D02*
X2589789Y1098799D01*
X2588859Y1097758D01*
X2588239Y1096508D01*
X2587774Y1094841D01*
X2587619Y1092966D01*
X2587774Y1091091D01*
X2588239Y1089424D01*
X2588859Y1088174D01*
X2589789Y1087133D01*
X2591029Y1086716D01*
X2592269Y1087133D01*
X2593199Y1088174D01*
X2593819Y1089424D01*
X2594284Y1091091D01*
X2594439Y1092966D01*
X2594284Y1094841D01*
X2593819Y1096508D01*
X2593199Y1097758D01*
X2592269Y1098799D01*
X2591029Y1099216D01*
G01X2550884Y1157733D02*
X2551814Y1158982D01*
X2552899Y1159608D01*
X2554139Y1159816D01*
X2555689Y1159399D01*
X2556774Y1158358D01*
X2557084Y1157108D01*
X2556929Y1155857D01*
X2556309Y1154816D01*
X2553209Y1152733D01*
X2551814Y1151274D01*
X2550884Y1149191D01*
X2550574Y1147316D01*
X2557084D01*
G01X2566229Y1159816D02*
X2564989Y1159399D01*
X2564059Y1158358D01*
X2563439Y1157108D01*
X2562974Y1155441D01*
X2562819Y1153566D01*
X2562974Y1151691D01*
X2563439Y1150024D01*
X2564059Y1148774D01*
X2564989Y1147733D01*
X2566229Y1147316D01*
X2567469Y1147733D01*
X2568399Y1148774D01*
X2569019Y1150024D01*
X2569484Y1151691D01*
X2569639Y1153566D01*
X2569484Y1155441D01*
X2569019Y1157108D01*
X2568399Y1158358D01*
X2567469Y1159399D01*
X2566229Y1159816D01*
G01X2578629Y1146899D02*
X2578319Y1147108D01*
Y1147524D01*
X2578629Y1147733D01*
X2578939Y1147524D01*
Y1147108D01*
X2578629Y1146899D01*
G01X2591029Y1159816D02*
X2589789Y1159399D01*
X2588859Y1158358D01*
X2588239Y1157108D01*
X2587774Y1155441D01*
X2587619Y1153566D01*
X2587774Y1151691D01*
X2588239Y1150024D01*
X2588859Y1148774D01*
X2589789Y1147733D01*
X2591029Y1147316D01*
X2592269Y1147733D01*
X2593199Y1148774D01*
X2593819Y1150024D01*
X2594284Y1151691D01*
X2594439Y1153566D01*
X2594284Y1155441D01*
X2593819Y1157108D01*
X2593199Y1158358D01*
X2592269Y1159399D01*
X2591029Y1159816D01*
G01X2553829Y1207916D02*
Y1220416D01*
X2551969Y1217916D01*
G01Y1207916D02*
X2555689D01*
G01X2563284Y1213124D02*
X2564369Y1214583D01*
X2565299Y1215416D01*
X2566539Y1215833D01*
X2567624Y1215416D01*
X2568399Y1214583D01*
X2569019Y1213333D01*
X2569174Y1211874D01*
X2569019Y1210624D01*
X2568399Y1209374D01*
X2567469Y1208333D01*
X2566384Y1207916D01*
X2565144Y1208333D01*
X2564059Y1209582D01*
X2563439Y1211458D01*
X2563284Y1213541D01*
X2563594Y1216249D01*
X2564059Y1217708D01*
X2564834Y1219166D01*
X2565919Y1220208D01*
X2567004Y1220416D01*
X2568089Y1219999D01*
X2568864Y1218958D01*
G01X2578629Y1207499D02*
X2578319Y1207708D01*
Y1208124D01*
X2578629Y1208333D01*
X2578939Y1208124D01*
Y1207708D01*
X2578629Y1207499D01*
G01X2591029Y1220416D02*
X2589789Y1219999D01*
X2588859Y1218958D01*
X2588239Y1217708D01*
X2587774Y1216041D01*
X2587619Y1214166D01*
X2587774Y1212291D01*
X2588239Y1210624D01*
X2588859Y1209374D01*
X2589789Y1208333D01*
X2591029Y1207916D01*
X2592269Y1208333D01*
X2593199Y1209374D01*
X2593819Y1210624D01*
X2594284Y1212291D01*
X2594439Y1214166D01*
X2594284Y1216041D01*
X2593819Y1217708D01*
X2593199Y1218958D01*
X2592269Y1219999D01*
X2591029Y1220416D01*
G01X2547629Y1268516D02*
Y1281016D01*
X2545769Y1278516D01*
G01Y1268516D02*
X2549489D01*
G01X2561889D02*
Y1281016D01*
X2556154Y1272058D01*
X2563904D01*
G01X2572429Y1268099D02*
X2572119Y1268308D01*
Y1268724D01*
X2572429Y1268933D01*
X2572739Y1268724D01*
Y1268308D01*
X2572429Y1268099D01*
G01X2584829Y1268516D02*
Y1281016D01*
X2582969Y1278516D01*
G01Y1268516D02*
X2586689D01*
G01X2596919D02*
X2597229Y1271224D01*
X2597694Y1273516D01*
X2598314Y1275599D01*
X2599089Y1277891D01*
X2600329Y1281016D01*
X2594129D01*
G01X2553829Y1329116D02*
Y1341616D01*
X2551969Y1339116D01*
G01Y1329116D02*
X2555689D01*
G01X2568089D02*
Y1341616D01*
X2562354Y1332658D01*
X2570104D01*
G01X2578629Y1328699D02*
X2578319Y1328908D01*
Y1329324D01*
X2578629Y1329533D01*
X2578939Y1329324D01*
Y1328908D01*
X2578629Y1328699D01*
G01X2591029Y1341616D02*
X2589789Y1341199D01*
X2588859Y1340158D01*
X2588239Y1338908D01*
X2587774Y1337241D01*
X2587619Y1335366D01*
X2587774Y1333491D01*
X2588239Y1331824D01*
X2588859Y1330574D01*
X2589789Y1329533D01*
X2591029Y1329116D01*
X2592269Y1329533D01*
X2593199Y1330574D01*
X2593819Y1331824D01*
X2594284Y1333491D01*
X2594439Y1335366D01*
X2594284Y1337241D01*
X2593819Y1338908D01*
X2593199Y1340158D01*
X2592269Y1341199D01*
X2591029Y1341616D01*
G01X2553829Y1389716D02*
Y1402216D01*
X2551969Y1399716D01*
G01Y1389716D02*
X2555689D01*
G01X2563284Y1400133D02*
X2564214Y1401382D01*
X2565299Y1402008D01*
X2566539Y1402216D01*
X2568089Y1401799D01*
X2569174Y1400758D01*
X2569484Y1399508D01*
X2569329Y1398257D01*
X2568709Y1397216D01*
X2565609Y1395133D01*
X2564214Y1393674D01*
X2563284Y1391591D01*
X2562974Y1389716D01*
X2569484D01*
G01X2578629Y1389299D02*
X2578319Y1389508D01*
Y1389924D01*
X2578629Y1390133D01*
X2578939Y1389924D01*
Y1389508D01*
X2578629Y1389299D01*
G01X2591029Y1402216D02*
X2589789Y1401799D01*
X2588859Y1400758D01*
X2588239Y1399508D01*
X2587774Y1397841D01*
X2587619Y1395966D01*
X2587774Y1394091D01*
X2588239Y1392424D01*
X2588859Y1391174D01*
X2589789Y1390133D01*
X2591029Y1389716D01*
X2592269Y1390133D01*
X2593199Y1391174D01*
X2593819Y1392424D01*
X2594284Y1394091D01*
X2594439Y1395966D01*
X2594284Y1397841D01*
X2593819Y1399508D01*
X2593199Y1400758D01*
X2592269Y1401799D01*
X2591029Y1402216D01*
G01X2553829Y1450316D02*
Y1462816D01*
X2551969Y1460316D01*
G01Y1450316D02*
X2555689D01*
G01X2566229Y1462816D02*
X2564989Y1462399D01*
X2564059Y1461358D01*
X2563439Y1460108D01*
X2562974Y1458441D01*
X2562819Y1456566D01*
X2562974Y1454691D01*
X2563439Y1453024D01*
X2564059Y1451774D01*
X2564989Y1450733D01*
X2566229Y1450316D01*
X2567469Y1450733D01*
X2568399Y1451774D01*
X2569019Y1453024D01*
X2569484Y1454691D01*
X2569639Y1456566D01*
X2569484Y1458441D01*
X2569019Y1460108D01*
X2568399Y1461358D01*
X2567469Y1462399D01*
X2566229Y1462816D01*
G01X2578629Y1449899D02*
X2578319Y1450108D01*
Y1450524D01*
X2578629Y1450733D01*
X2578939Y1450524D01*
Y1450108D01*
X2578629Y1449899D01*
G01X2591029Y1462816D02*
X2589789Y1462399D01*
X2588859Y1461358D01*
X2588239Y1460108D01*
X2587774Y1458441D01*
X2587619Y1456566D01*
X2587774Y1454691D01*
X2588239Y1453024D01*
X2588859Y1451774D01*
X2589789Y1450733D01*
X2591029Y1450316D01*
X2592269Y1450733D01*
X2593199Y1451774D01*
X2593819Y1453024D01*
X2594284Y1454691D01*
X2594439Y1456566D01*
X2594284Y1458441D01*
X2593819Y1460108D01*
X2593199Y1461358D01*
X2592269Y1462399D01*
X2591029Y1462816D01*
G01X2550574Y1558482D02*
X2551814Y1557441D01*
X2553209Y1556816D01*
X2554449D01*
X2555689Y1557441D01*
X2556619Y1558482D01*
X2557084Y1559941D01*
X2556774Y1561399D01*
X2555999Y1562649D01*
X2554604Y1563483D01*
X2552744Y1563899D01*
X2551659Y1564733D01*
X2551194Y1566191D01*
X2551504Y1567649D01*
X2552279Y1568691D01*
X2553364Y1569316D01*
X2554449D01*
X2555534Y1568899D01*
X2556464Y1567858D01*
G01X2564369Y1569316D02*
X2568089D01*
G01X2566229D02*
Y1556816D01*
G01X2564369D02*
X2568089D01*
G01X2575684Y1569316D02*
X2581574D01*
X2575684Y1556816D01*
X2581574D01*
G01X2594129D02*
X2587929D01*
Y1569316D01*
X2594129D01*
G01X2591649Y1563274D02*
X2587929D01*
G01X2666979Y1575566D02*
Y-88734D01*
G01X2671164Y56516D02*
Y69016D01*
X2678294Y56516D01*
Y69016D01*
G01X2687129Y56516D02*
X2685889Y56724D01*
X2684804Y57557D01*
X2683874Y58808D01*
X2683254Y60266D01*
X2682944Y61933D01*
Y63599D01*
X2683254Y65266D01*
X2683874Y66724D01*
X2684804Y67974D01*
X2685889Y68808D01*
X2687129Y69016D01*
X2688369Y68808D01*
X2689454Y67974D01*
X2690384Y66724D01*
X2691004Y65266D01*
X2691314Y63599D01*
Y61933D01*
X2691004Y60266D01*
X2690384Y58808D01*
X2689454Y57557D01*
X2688369Y56724D01*
X2687129Y56516D01*
G01X2695964D02*
Y69016D01*
X2703094Y56516D01*
Y69016D01*
G01X2709914Y60683D02*
X2713944D01*
G01X2721229Y56516D02*
Y69016D01*
X2724949D01*
X2726189Y68391D01*
X2727119Y66933D01*
X2727429Y65266D01*
X2727119Y63599D01*
X2726344Y62349D01*
X2724949Y61724D01*
X2721229D01*
G01X2733629Y69016D02*
Y56516D01*
X2739829D01*
G01X2745254D02*
X2749129Y69016D01*
X2753004Y56516D01*
G01X2751609Y60891D02*
X2746649D01*
G01X2761529Y69016D02*
Y56516D01*
G01X2757964Y69016D02*
X2765094D01*
G01X2777029Y56516D02*
X2770829D01*
Y69016D01*
X2777029D01*
G01X2774549Y62974D02*
X2770829D01*
G01X2782919Y56516D02*
Y69016D01*
X2786019D01*
X2787259Y68391D01*
X2788189Y67558D01*
X2788964Y66308D01*
X2789584Y64849D01*
X2789739Y62766D01*
X2789584Y60683D01*
X2788964Y59224D01*
X2788189Y57974D01*
X2787259Y57141D01*
X2786019Y56516D01*
X2782919D01*
G01X2671164Y117116D02*
Y129616D01*
X2678294Y117116D01*
Y129616D01*
G01X2687129Y117116D02*
X2685889Y117324D01*
X2684804Y118157D01*
X2683874Y119408D01*
X2683254Y120866D01*
X2682944Y122533D01*
Y124199D01*
X2683254Y125866D01*
X2683874Y127324D01*
X2684804Y128574D01*
X2685889Y129408D01*
X2687129Y129616D01*
X2688369Y129408D01*
X2689454Y128574D01*
X2690384Y127324D01*
X2691004Y125866D01*
X2691314Y124199D01*
Y122533D01*
X2691004Y120866D01*
X2690384Y119408D01*
X2689454Y118157D01*
X2688369Y117324D01*
X2687129Y117116D01*
G01X2695964D02*
Y129616D01*
X2703094Y117116D01*
Y129616D01*
G01X2709914Y121283D02*
X2713944D01*
G01X2721229Y117116D02*
Y129616D01*
X2724949D01*
X2726189Y128991D01*
X2727119Y127533D01*
X2727429Y125866D01*
X2727119Y124199D01*
X2726344Y122949D01*
X2724949Y122324D01*
X2721229D01*
G01X2733629Y129616D02*
Y117116D01*
X2739829D01*
G01X2745254D02*
X2749129Y129616D01*
X2753004Y117116D01*
G01X2751609Y121491D02*
X2746649D01*
G01X2761529Y129616D02*
Y117116D01*
G01X2757964Y129616D02*
X2765094D01*
G01X2777029Y117116D02*
X2770829D01*
Y129616D01*
X2777029D01*
G01X2774549Y123574D02*
X2770829D01*
G01X2782919Y117116D02*
Y129616D01*
X2786019D01*
X2787259Y128991D01*
X2788189Y128158D01*
X2788964Y126908D01*
X2789584Y125449D01*
X2789739Y123366D01*
X2789584Y121283D01*
X2788964Y119824D01*
X2788189Y118574D01*
X2787259Y117741D01*
X2786019Y117116D01*
X2782919D01*
G01X2671164Y177716D02*
Y190216D01*
X2678294Y177716D01*
Y190216D01*
G01X2687129Y177716D02*
X2685889Y177924D01*
X2684804Y178757D01*
X2683874Y180008D01*
X2683254Y181466D01*
X2682944Y183133D01*
Y184799D01*
X2683254Y186466D01*
X2683874Y187924D01*
X2684804Y189174D01*
X2685889Y190008D01*
X2687129Y190216D01*
X2688369Y190008D01*
X2689454Y189174D01*
X2690384Y187924D01*
X2691004Y186466D01*
X2691314Y184799D01*
Y183133D01*
X2691004Y181466D01*
X2690384Y180008D01*
X2689454Y178757D01*
X2688369Y177924D01*
X2687129Y177716D01*
G01X2695964D02*
Y190216D01*
X2703094Y177716D01*
Y190216D01*
G01X2709914Y181883D02*
X2713944D01*
G01X2721229Y177716D02*
Y190216D01*
X2724949D01*
X2726189Y189591D01*
X2727119Y188133D01*
X2727429Y186466D01*
X2727119Y184799D01*
X2726344Y183549D01*
X2724949Y182924D01*
X2721229D01*
G01X2733629Y190216D02*
Y177716D01*
X2739829D01*
G01X2745254D02*
X2749129Y190216D01*
X2753004Y177716D01*
G01X2751609Y182091D02*
X2746649D01*
G01X2761529Y190216D02*
Y177716D01*
G01X2757964Y190216D02*
X2765094D01*
G01X2777029Y177716D02*
X2770829D01*
Y190216D01*
X2777029D01*
G01X2774549Y184174D02*
X2770829D01*
G01X2782919Y177716D02*
Y190216D01*
X2786019D01*
X2787259Y189591D01*
X2788189Y188758D01*
X2788964Y187508D01*
X2789584Y186049D01*
X2789739Y183966D01*
X2789584Y181883D01*
X2788964Y180424D01*
X2788189Y179174D01*
X2787259Y178341D01*
X2786019Y177716D01*
X2782919D01*
G01X2671164Y238316D02*
Y250816D01*
X2678294Y238316D01*
Y250816D01*
G01X2687129Y238316D02*
X2685889Y238524D01*
X2684804Y239357D01*
X2683874Y240608D01*
X2683254Y242066D01*
X2682944Y243733D01*
Y245399D01*
X2683254Y247066D01*
X2683874Y248524D01*
X2684804Y249774D01*
X2685889Y250608D01*
X2687129Y250816D01*
X2688369Y250608D01*
X2689454Y249774D01*
X2690384Y248524D01*
X2691004Y247066D01*
X2691314Y245399D01*
Y243733D01*
X2691004Y242066D01*
X2690384Y240608D01*
X2689454Y239357D01*
X2688369Y238524D01*
X2687129Y238316D01*
G01X2695964D02*
Y250816D01*
X2703094Y238316D01*
Y250816D01*
G01X2709914Y242483D02*
X2713944D01*
G01X2721229Y238316D02*
Y250816D01*
X2724949D01*
X2726189Y250191D01*
X2727119Y248733D01*
X2727429Y247066D01*
X2727119Y245399D01*
X2726344Y244149D01*
X2724949Y243524D01*
X2721229D01*
G01X2733629Y250816D02*
Y238316D01*
X2739829D01*
G01X2745254D02*
X2749129Y250816D01*
X2753004Y238316D01*
G01X2751609Y242691D02*
X2746649D01*
G01X2761529Y250816D02*
Y238316D01*
G01X2757964Y250816D02*
X2765094D01*
G01X2777029Y238316D02*
X2770829D01*
Y250816D01*
X2777029D01*
G01X2774549Y244774D02*
X2770829D01*
G01X2782919Y238316D02*
Y250816D01*
X2786019D01*
X2787259Y250191D01*
X2788189Y249358D01*
X2788964Y248108D01*
X2789584Y246649D01*
X2789739Y244566D01*
X2789584Y242483D01*
X2788964Y241024D01*
X2788189Y239774D01*
X2787259Y238941D01*
X2786019Y238316D01*
X2782919D01*
G01X2671164Y298916D02*
Y311416D01*
X2678294Y298916D01*
Y311416D01*
G01X2687129Y298916D02*
X2685889Y299124D01*
X2684804Y299957D01*
X2683874Y301208D01*
X2683254Y302666D01*
X2682944Y304333D01*
Y305999D01*
X2683254Y307666D01*
X2683874Y309124D01*
X2684804Y310374D01*
X2685889Y311208D01*
X2687129Y311416D01*
X2688369Y311208D01*
X2689454Y310374D01*
X2690384Y309124D01*
X2691004Y307666D01*
X2691314Y305999D01*
Y304333D01*
X2691004Y302666D01*
X2690384Y301208D01*
X2689454Y299957D01*
X2688369Y299124D01*
X2687129Y298916D01*
G01X2695964D02*
Y311416D01*
X2703094Y298916D01*
Y311416D01*
G01X2709914Y303083D02*
X2713944D01*
G01X2721229Y298916D02*
Y311416D01*
X2724949D01*
X2726189Y310791D01*
X2727119Y309333D01*
X2727429Y307666D01*
X2727119Y305999D01*
X2726344Y304749D01*
X2724949Y304124D01*
X2721229D01*
G01X2733629Y311416D02*
Y298916D01*
X2739829D01*
G01X2745254D02*
X2749129Y311416D01*
X2753004Y298916D01*
G01X2751609Y303291D02*
X2746649D01*
G01X2761529Y311416D02*
Y298916D01*
G01X2757964Y311416D02*
X2765094D01*
G01X2777029Y298916D02*
X2770829D01*
Y311416D01*
X2777029D01*
G01X2774549Y305374D02*
X2770829D01*
G01X2782919Y298916D02*
Y311416D01*
X2786019D01*
X2787259Y310791D01*
X2788189Y309958D01*
X2788964Y308708D01*
X2789584Y307249D01*
X2789739Y305166D01*
X2789584Y303083D01*
X2788964Y301624D01*
X2788189Y300374D01*
X2787259Y299541D01*
X2786019Y298916D01*
X2782919D01*
G01X2671164Y359516D02*
Y372016D01*
X2678294Y359516D01*
Y372016D01*
G01X2687129Y359516D02*
X2685889Y359724D01*
X2684804Y360557D01*
X2683874Y361808D01*
X2683254Y363266D01*
X2682944Y364933D01*
Y366599D01*
X2683254Y368266D01*
X2683874Y369724D01*
X2684804Y370974D01*
X2685889Y371808D01*
X2687129Y372016D01*
X2688369Y371808D01*
X2689454Y370974D01*
X2690384Y369724D01*
X2691004Y368266D01*
X2691314Y366599D01*
Y364933D01*
X2691004Y363266D01*
X2690384Y361808D01*
X2689454Y360557D01*
X2688369Y359724D01*
X2687129Y359516D01*
G01X2695964D02*
Y372016D01*
X2703094Y359516D01*
Y372016D01*
G01X2709914Y363683D02*
X2713944D01*
G01X2721229Y359516D02*
Y372016D01*
X2724949D01*
X2726189Y371391D01*
X2727119Y369933D01*
X2727429Y368266D01*
X2727119Y366599D01*
X2726344Y365349D01*
X2724949Y364724D01*
X2721229D01*
G01X2733629Y372016D02*
Y359516D01*
X2739829D01*
G01X2745254D02*
X2749129Y372016D01*
X2753004Y359516D01*
G01X2751609Y363891D02*
X2746649D01*
G01X2761529Y372016D02*
Y359516D01*
G01X2757964Y372016D02*
X2765094D01*
G01X2777029Y359516D02*
X2770829D01*
Y372016D01*
X2777029D01*
G01X2774549Y365974D02*
X2770829D01*
G01X2782919Y359516D02*
Y372016D01*
X2786019D01*
X2787259Y371391D01*
X2788189Y370558D01*
X2788964Y369308D01*
X2789584Y367849D01*
X2789739Y365766D01*
X2789584Y363683D01*
X2788964Y362224D01*
X2788189Y360974D01*
X2787259Y360141D01*
X2786019Y359516D01*
X2782919D01*
G01X2671164Y420116D02*
Y432616D01*
X2678294Y420116D01*
Y432616D01*
G01X2687129Y420116D02*
X2685889Y420324D01*
X2684804Y421157D01*
X2683874Y422408D01*
X2683254Y423866D01*
X2682944Y425533D01*
Y427199D01*
X2683254Y428866D01*
X2683874Y430324D01*
X2684804Y431574D01*
X2685889Y432408D01*
X2687129Y432616D01*
X2688369Y432408D01*
X2689454Y431574D01*
X2690384Y430324D01*
X2691004Y428866D01*
X2691314Y427199D01*
Y425533D01*
X2691004Y423866D01*
X2690384Y422408D01*
X2689454Y421157D01*
X2688369Y420324D01*
X2687129Y420116D01*
G01X2695964D02*
Y432616D01*
X2703094Y420116D01*
Y432616D01*
G01X2709914Y424283D02*
X2713944D01*
G01X2721229Y420116D02*
Y432616D01*
X2724949D01*
X2726189Y431991D01*
X2727119Y430533D01*
X2727429Y428866D01*
X2727119Y427199D01*
X2726344Y425949D01*
X2724949Y425324D01*
X2721229D01*
G01X2733629Y432616D02*
Y420116D01*
X2739829D01*
G01X2745254D02*
X2749129Y432616D01*
X2753004Y420116D01*
G01X2751609Y424491D02*
X2746649D01*
G01X2761529Y432616D02*
Y420116D01*
G01X2757964Y432616D02*
X2765094D01*
G01X2777029Y420116D02*
X2770829D01*
Y432616D01*
X2777029D01*
G01X2774549Y426574D02*
X2770829D01*
G01X2782919Y420116D02*
Y432616D01*
X2786019D01*
X2787259Y431991D01*
X2788189Y431158D01*
X2788964Y429908D01*
X2789584Y428449D01*
X2789739Y426366D01*
X2789584Y424283D01*
X2788964Y422824D01*
X2788189Y421574D01*
X2787259Y420741D01*
X2786019Y420116D01*
X2782919D01*
G01X2671164Y480716D02*
Y493216D01*
X2678294Y480716D01*
Y493216D01*
G01X2687129Y480716D02*
X2685889Y480924D01*
X2684804Y481757D01*
X2683874Y483008D01*
X2683254Y484466D01*
X2682944Y486133D01*
Y487799D01*
X2683254Y489466D01*
X2683874Y490924D01*
X2684804Y492174D01*
X2685889Y493008D01*
X2687129Y493216D01*
X2688369Y493008D01*
X2689454Y492174D01*
X2690384Y490924D01*
X2691004Y489466D01*
X2691314Y487799D01*
Y486133D01*
X2691004Y484466D01*
X2690384Y483008D01*
X2689454Y481757D01*
X2688369Y480924D01*
X2687129Y480716D01*
G01X2695964D02*
Y493216D01*
X2703094Y480716D01*
Y493216D01*
G01X2709914Y484883D02*
X2713944D01*
G01X2721229Y480716D02*
Y493216D01*
X2724949D01*
X2726189Y492591D01*
X2727119Y491133D01*
X2727429Y489466D01*
X2727119Y487799D01*
X2726344Y486549D01*
X2724949Y485924D01*
X2721229D01*
G01X2733629Y493216D02*
Y480716D01*
X2739829D01*
G01X2745254D02*
X2749129Y493216D01*
X2753004Y480716D01*
G01X2751609Y485091D02*
X2746649D01*
G01X2761529Y493216D02*
Y480716D01*
G01X2757964Y493216D02*
X2765094D01*
G01X2777029Y480716D02*
X2770829D01*
Y493216D01*
X2777029D01*
G01X2774549Y487174D02*
X2770829D01*
G01X2782919Y480716D02*
Y493216D01*
X2786019D01*
X2787259Y492591D01*
X2788189Y491758D01*
X2788964Y490508D01*
X2789584Y489049D01*
X2789739Y486966D01*
X2789584Y484883D01*
X2788964Y483424D01*
X2788189Y482174D01*
X2787259Y481341D01*
X2786019Y480716D01*
X2782919D01*
G01X2671164Y541316D02*
Y553816D01*
X2678294Y541316D01*
Y553816D01*
G01X2687129Y541316D02*
X2685889Y541524D01*
X2684804Y542357D01*
X2683874Y543608D01*
X2683254Y545066D01*
X2682944Y546733D01*
Y548399D01*
X2683254Y550066D01*
X2683874Y551524D01*
X2684804Y552774D01*
X2685889Y553608D01*
X2687129Y553816D01*
X2688369Y553608D01*
X2689454Y552774D01*
X2690384Y551524D01*
X2691004Y550066D01*
X2691314Y548399D01*
Y546733D01*
X2691004Y545066D01*
X2690384Y543608D01*
X2689454Y542357D01*
X2688369Y541524D01*
X2687129Y541316D01*
G01X2695964D02*
Y553816D01*
X2703094Y541316D01*
Y553816D01*
G01X2709914Y545483D02*
X2713944D01*
G01X2721229Y541316D02*
Y553816D01*
X2724949D01*
X2726189Y553191D01*
X2727119Y551733D01*
X2727429Y550066D01*
X2727119Y548399D01*
X2726344Y547149D01*
X2724949Y546524D01*
X2721229D01*
G01X2733629Y553816D02*
Y541316D01*
X2739829D01*
G01X2745254D02*
X2749129Y553816D01*
X2753004Y541316D01*
G01X2751609Y545691D02*
X2746649D01*
G01X2761529Y553816D02*
Y541316D01*
G01X2757964Y553816D02*
X2765094D01*
G01X2777029Y541316D02*
X2770829D01*
Y553816D01*
X2777029D01*
G01X2774549Y547774D02*
X2770829D01*
G01X2782919Y541316D02*
Y553816D01*
X2786019D01*
X2787259Y553191D01*
X2788189Y552358D01*
X2788964Y551108D01*
X2789584Y549649D01*
X2789739Y547566D01*
X2789584Y545483D01*
X2788964Y544024D01*
X2788189Y542774D01*
X2787259Y541941D01*
X2786019Y541316D01*
X2782919D01*
G01X2696429Y-64684D02*
Y-52184D01*
X2700149D01*
X2701389Y-52809D01*
X2702319Y-54267D01*
X2702629Y-55934D01*
X2702319Y-57601D01*
X2701544Y-58851D01*
X2700149Y-59476D01*
X2696429D01*
G01X2708829Y-52184D02*
Y-64684D01*
X2715029D01*
G01X2720454D02*
X2724329Y-52184D01*
X2728204Y-64684D01*
G01X2726809Y-60309D02*
X2721849D01*
G01X2736729Y-52184D02*
Y-64684D01*
G01X2733164Y-52184D02*
X2740294D01*
G01X2752229Y-64684D02*
X2746029D01*
Y-52184D01*
X2752229D01*
G01X2749749Y-58226D02*
X2746029D01*
G01X2758119Y-64684D02*
Y-52184D01*
X2761219D01*
X2762459Y-52809D01*
X2763389Y-53642D01*
X2764164Y-54892D01*
X2764784Y-56351D01*
X2764939Y-58434D01*
X2764784Y-60517D01*
X2764164Y-61976D01*
X2763389Y-63226D01*
X2762459Y-64059D01*
X2761219Y-64684D01*
X2758119D01*
G01X2696429Y-4084D02*
Y8416D01*
X2700149D01*
X2701389Y7791D01*
X2702319Y6333D01*
X2702629Y4666D01*
X2702319Y2999D01*
X2701544Y1749D01*
X2700149Y1124D01*
X2696429D01*
G01X2708829Y8416D02*
Y-4084D01*
X2715029D01*
G01X2720454D02*
X2724329Y8416D01*
X2728204Y-4084D01*
G01X2726809Y291D02*
X2721849D01*
G01X2736729Y8416D02*
Y-4084D01*
G01X2733164Y8416D02*
X2740294D01*
G01X2752229Y-4084D02*
X2746029D01*
Y8416D01*
X2752229D01*
G01X2749749Y2374D02*
X2746029D01*
G01X2758119Y-4084D02*
Y8416D01*
X2761219D01*
X2762459Y7791D01*
X2763389Y6958D01*
X2764164Y5708D01*
X2764784Y4249D01*
X2764939Y2166D01*
X2764784Y83D01*
X2764164Y-1376D01*
X2763389Y-2626D01*
X2762459Y-3459D01*
X2761219Y-4084D01*
X2758119D01*
G01X2696429Y601916D02*
Y614416D01*
X2700149D01*
X2701389Y613791D01*
X2702319Y612333D01*
X2702629Y610666D01*
X2702319Y608999D01*
X2701544Y607749D01*
X2700149Y607124D01*
X2696429D01*
G01X2708829Y614416D02*
Y601916D01*
X2715029D01*
G01X2720454D02*
X2724329Y614416D01*
X2728204Y601916D01*
G01X2726809Y606291D02*
X2721849D01*
G01X2736729Y614416D02*
Y601916D01*
G01X2733164Y614416D02*
X2740294D01*
G01X2752229Y601916D02*
X2746029D01*
Y614416D01*
X2752229D01*
G01X2749749Y608374D02*
X2746029D01*
G01X2758119Y601916D02*
Y614416D01*
X2761219D01*
X2762459Y613791D01*
X2763389Y612958D01*
X2764164Y611708D01*
X2764784Y610249D01*
X2764939Y608166D01*
X2764784Y606083D01*
X2764164Y604624D01*
X2763389Y603374D01*
X2762459Y602541D01*
X2761219Y601916D01*
X2758119D01*
G01X2696429Y662516D02*
Y675016D01*
X2700149D01*
X2701389Y674391D01*
X2702319Y672933D01*
X2702629Y671266D01*
X2702319Y669599D01*
X2701544Y668349D01*
X2700149Y667724D01*
X2696429D01*
G01X2708829Y675016D02*
Y662516D01*
X2715029D01*
G01X2720454D02*
X2724329Y675016D01*
X2728204Y662516D01*
G01X2726809Y666891D02*
X2721849D01*
G01X2736729Y675016D02*
Y662516D01*
G01X2733164Y675016D02*
X2740294D01*
G01X2752229Y662516D02*
X2746029D01*
Y675016D01*
X2752229D01*
G01X2749749Y668974D02*
X2746029D01*
G01X2758119Y662516D02*
Y675016D01*
X2761219D01*
X2762459Y674391D01*
X2763389Y673558D01*
X2764164Y672308D01*
X2764784Y670849D01*
X2764939Y668766D01*
X2764784Y666683D01*
X2764164Y665224D01*
X2763389Y663974D01*
X2762459Y663141D01*
X2761219Y662516D01*
X2758119D01*
G01X2696429Y723116D02*
Y735616D01*
X2700149D01*
X2701389Y734991D01*
X2702319Y733533D01*
X2702629Y731866D01*
X2702319Y730199D01*
X2701544Y728949D01*
X2700149Y728324D01*
X2696429D01*
G01X2708829Y735616D02*
Y723116D01*
X2715029D01*
G01X2720454D02*
X2724329Y735616D01*
X2728204Y723116D01*
G01X2726809Y727491D02*
X2721849D01*
G01X2736729Y735616D02*
Y723116D01*
G01X2733164Y735616D02*
X2740294D01*
G01X2752229Y723116D02*
X2746029D01*
Y735616D01*
X2752229D01*
G01X2749749Y729574D02*
X2746029D01*
G01X2758119Y723116D02*
Y735616D01*
X2761219D01*
X2762459Y734991D01*
X2763389Y734158D01*
X2764164Y732908D01*
X2764784Y731449D01*
X2764939Y729366D01*
X2764784Y727283D01*
X2764164Y725824D01*
X2763389Y724574D01*
X2762459Y723741D01*
X2761219Y723116D01*
X2758119D01*
G01X2696429Y783716D02*
Y796216D01*
X2700149D01*
X2701389Y795591D01*
X2702319Y794133D01*
X2702629Y792466D01*
X2702319Y790799D01*
X2701544Y789549D01*
X2700149Y788924D01*
X2696429D01*
G01X2708829Y796216D02*
Y783716D01*
X2715029D01*
G01X2720454D02*
X2724329Y796216D01*
X2728204Y783716D01*
G01X2726809Y788091D02*
X2721849D01*
G01X2736729Y796216D02*
Y783716D01*
G01X2733164Y796216D02*
X2740294D01*
G01X2752229Y783716D02*
X2746029D01*
Y796216D01*
X2752229D01*
G01X2749749Y790174D02*
X2746029D01*
G01X2758119Y783716D02*
Y796216D01*
X2761219D01*
X2762459Y795591D01*
X2763389Y794758D01*
X2764164Y793508D01*
X2764784Y792049D01*
X2764939Y789966D01*
X2764784Y787883D01*
X2764164Y786424D01*
X2763389Y785174D01*
X2762459Y784341D01*
X2761219Y783716D01*
X2758119D01*
G01X2696429Y844316D02*
Y856816D01*
X2700149D01*
X2701389Y856191D01*
X2702319Y854733D01*
X2702629Y853066D01*
X2702319Y851399D01*
X2701544Y850149D01*
X2700149Y849524D01*
X2696429D01*
G01X2708829Y856816D02*
Y844316D01*
X2715029D01*
G01X2720454D02*
X2724329Y856816D01*
X2728204Y844316D01*
G01X2726809Y848691D02*
X2721849D01*
G01X2736729Y856816D02*
Y844316D01*
G01X2733164Y856816D02*
X2740294D01*
G01X2752229Y844316D02*
X2746029D01*
Y856816D01*
X2752229D01*
G01X2749749Y850774D02*
X2746029D01*
G01X2758119Y844316D02*
Y856816D01*
X2761219D01*
X2762459Y856191D01*
X2763389Y855358D01*
X2764164Y854108D01*
X2764784Y852649D01*
X2764939Y850566D01*
X2764784Y848483D01*
X2764164Y847024D01*
X2763389Y845774D01*
X2762459Y844941D01*
X2761219Y844316D01*
X2758119D01*
G01X2696429Y904916D02*
Y917416D01*
X2700149D01*
X2701389Y916791D01*
X2702319Y915333D01*
X2702629Y913666D01*
X2702319Y911999D01*
X2701544Y910749D01*
X2700149Y910124D01*
X2696429D01*
G01X2708829Y917416D02*
Y904916D01*
X2715029D01*
G01X2720454D02*
X2724329Y917416D01*
X2728204Y904916D01*
G01X2726809Y909291D02*
X2721849D01*
G01X2736729Y917416D02*
Y904916D01*
G01X2733164Y917416D02*
X2740294D01*
G01X2752229Y904916D02*
X2746029D01*
Y917416D01*
X2752229D01*
G01X2749749Y911374D02*
X2746029D01*
G01X2758119Y904916D02*
Y917416D01*
X2761219D01*
X2762459Y916791D01*
X2763389Y915958D01*
X2764164Y914708D01*
X2764784Y913249D01*
X2764939Y911166D01*
X2764784Y909083D01*
X2764164Y907624D01*
X2763389Y906374D01*
X2762459Y905541D01*
X2761219Y904916D01*
X2758119D01*
G01X2696429Y965516D02*
Y978016D01*
X2700149D01*
X2701389Y977391D01*
X2702319Y975933D01*
X2702629Y974266D01*
X2702319Y972599D01*
X2701544Y971349D01*
X2700149Y970724D01*
X2696429D01*
G01X2708829Y978016D02*
Y965516D01*
X2715029D01*
G01X2720454D02*
X2724329Y978016D01*
X2728204Y965516D01*
G01X2726809Y969891D02*
X2721849D01*
G01X2736729Y978016D02*
Y965516D01*
G01X2733164Y978016D02*
X2740294D01*
G01X2752229Y965516D02*
X2746029D01*
Y978016D01*
X2752229D01*
G01X2749749Y971974D02*
X2746029D01*
G01X2758119Y965516D02*
Y978016D01*
X2761219D01*
X2762459Y977391D01*
X2763389Y976558D01*
X2764164Y975308D01*
X2764784Y973849D01*
X2764939Y971766D01*
X2764784Y969683D01*
X2764164Y968224D01*
X2763389Y966974D01*
X2762459Y966141D01*
X2761219Y965516D01*
X2758119D01*
G01X2696429Y1026116D02*
Y1038616D01*
X2700149D01*
X2701389Y1037991D01*
X2702319Y1036533D01*
X2702629Y1034866D01*
X2702319Y1033199D01*
X2701544Y1031949D01*
X2700149Y1031324D01*
X2696429D01*
G01X2708829Y1038616D02*
Y1026116D01*
X2715029D01*
G01X2720454D02*
X2724329Y1038616D01*
X2728204Y1026116D01*
G01X2726809Y1030491D02*
X2721849D01*
G01X2736729Y1038616D02*
Y1026116D01*
G01X2733164Y1038616D02*
X2740294D01*
G01X2752229Y1026116D02*
X2746029D01*
Y1038616D01*
X2752229D01*
G01X2749749Y1032574D02*
X2746029D01*
G01X2758119Y1026116D02*
Y1038616D01*
X2761219D01*
X2762459Y1037991D01*
X2763389Y1037158D01*
X2764164Y1035908D01*
X2764784Y1034449D01*
X2764939Y1032366D01*
X2764784Y1030283D01*
X2764164Y1028824D01*
X2763389Y1027574D01*
X2762459Y1026741D01*
X2761219Y1026116D01*
X2758119D01*
G01X2696429Y1086716D02*
Y1099216D01*
X2700149D01*
X2701389Y1098591D01*
X2702319Y1097133D01*
X2702629Y1095466D01*
X2702319Y1093799D01*
X2701544Y1092549D01*
X2700149Y1091924D01*
X2696429D01*
G01X2708829Y1099216D02*
Y1086716D01*
X2715029D01*
G01X2720454D02*
X2724329Y1099216D01*
X2728204Y1086716D01*
G01X2726809Y1091091D02*
X2721849D01*
G01X2736729Y1099216D02*
Y1086716D01*
G01X2733164Y1099216D02*
X2740294D01*
G01X2752229Y1086716D02*
X2746029D01*
Y1099216D01*
X2752229D01*
G01X2749749Y1093174D02*
X2746029D01*
G01X2758119Y1086716D02*
Y1099216D01*
X2761219D01*
X2762459Y1098591D01*
X2763389Y1097758D01*
X2764164Y1096508D01*
X2764784Y1095049D01*
X2764939Y1092966D01*
X2764784Y1090883D01*
X2764164Y1089424D01*
X2763389Y1088174D01*
X2762459Y1087341D01*
X2761219Y1086716D01*
X2758119D01*
G01X2696429Y1147316D02*
Y1159816D01*
X2700149D01*
X2701389Y1159191D01*
X2702319Y1157733D01*
X2702629Y1156066D01*
X2702319Y1154399D01*
X2701544Y1153149D01*
X2700149Y1152524D01*
X2696429D01*
G01X2708829Y1159816D02*
Y1147316D01*
X2715029D01*
G01X2720454D02*
X2724329Y1159816D01*
X2728204Y1147316D01*
G01X2726809Y1151691D02*
X2721849D01*
G01X2736729Y1159816D02*
Y1147316D01*
G01X2733164Y1159816D02*
X2740294D01*
G01X2752229Y1147316D02*
X2746029D01*
Y1159816D01*
X2752229D01*
G01X2749749Y1153774D02*
X2746029D01*
G01X2758119Y1147316D02*
Y1159816D01*
X2761219D01*
X2762459Y1159191D01*
X2763389Y1158358D01*
X2764164Y1157108D01*
X2764784Y1155649D01*
X2764939Y1153566D01*
X2764784Y1151483D01*
X2764164Y1150024D01*
X2763389Y1148774D01*
X2762459Y1147941D01*
X2761219Y1147316D01*
X2758119D01*
G01X2696429Y1207916D02*
Y1220416D01*
X2700149D01*
X2701389Y1219791D01*
X2702319Y1218333D01*
X2702629Y1216666D01*
X2702319Y1214999D01*
X2701544Y1213749D01*
X2700149Y1213124D01*
X2696429D01*
G01X2708829Y1220416D02*
Y1207916D01*
X2715029D01*
G01X2720454D02*
X2724329Y1220416D01*
X2728204Y1207916D01*
G01X2726809Y1212291D02*
X2721849D01*
G01X2736729Y1220416D02*
Y1207916D01*
G01X2733164Y1220416D02*
X2740294D01*
G01X2752229Y1207916D02*
X2746029D01*
Y1220416D01*
X2752229D01*
G01X2749749Y1214374D02*
X2746029D01*
G01X2758119Y1207916D02*
Y1220416D01*
X2761219D01*
X2762459Y1219791D01*
X2763389Y1218958D01*
X2764164Y1217708D01*
X2764784Y1216249D01*
X2764939Y1214166D01*
X2764784Y1212083D01*
X2764164Y1210624D01*
X2763389Y1209374D01*
X2762459Y1208541D01*
X2761219Y1207916D01*
X2758119D01*
G01X2696429Y1268516D02*
Y1281016D01*
X2700149D01*
X2701389Y1280391D01*
X2702319Y1278933D01*
X2702629Y1277266D01*
X2702319Y1275599D01*
X2701544Y1274349D01*
X2700149Y1273724D01*
X2696429D01*
G01X2708829Y1281016D02*
Y1268516D01*
X2715029D01*
G01X2720454D02*
X2724329Y1281016D01*
X2728204Y1268516D01*
G01X2726809Y1272891D02*
X2721849D01*
G01X2736729Y1281016D02*
Y1268516D01*
G01X2733164Y1281016D02*
X2740294D01*
G01X2752229Y1268516D02*
X2746029D01*
Y1281016D01*
X2752229D01*
G01X2749749Y1274974D02*
X2746029D01*
G01X2758119Y1268516D02*
Y1281016D01*
X2761219D01*
X2762459Y1280391D01*
X2763389Y1279558D01*
X2764164Y1278308D01*
X2764784Y1276849D01*
X2764939Y1274766D01*
X2764784Y1272683D01*
X2764164Y1271224D01*
X2763389Y1269974D01*
X2762459Y1269141D01*
X2761219Y1268516D01*
X2758119D01*
G01X2696429Y1329116D02*
Y1341616D01*
X2700149D01*
X2701389Y1340991D01*
X2702319Y1339533D01*
X2702629Y1337866D01*
X2702319Y1336199D01*
X2701544Y1334949D01*
X2700149Y1334324D01*
X2696429D01*
G01X2708829Y1341616D02*
Y1329116D01*
X2715029D01*
G01X2720454D02*
X2724329Y1341616D01*
X2728204Y1329116D01*
G01X2726809Y1333491D02*
X2721849D01*
G01X2736729Y1341616D02*
Y1329116D01*
G01X2733164Y1341616D02*
X2740294D01*
G01X2752229Y1329116D02*
X2746029D01*
Y1341616D01*
X2752229D01*
G01X2749749Y1335574D02*
X2746029D01*
G01X2758119Y1329116D02*
Y1341616D01*
X2761219D01*
X2762459Y1340991D01*
X2763389Y1340158D01*
X2764164Y1338908D01*
X2764784Y1337449D01*
X2764939Y1335366D01*
X2764784Y1333283D01*
X2764164Y1331824D01*
X2763389Y1330574D01*
X2762459Y1329741D01*
X2761219Y1329116D01*
X2758119D01*
G01X2696429Y1389716D02*
Y1402216D01*
X2700149D01*
X2701389Y1401591D01*
X2702319Y1400133D01*
X2702629Y1398466D01*
X2702319Y1396799D01*
X2701544Y1395549D01*
X2700149Y1394924D01*
X2696429D01*
G01X2708829Y1402216D02*
Y1389716D01*
X2715029D01*
G01X2720454D02*
X2724329Y1402216D01*
X2728204Y1389716D01*
G01X2726809Y1394091D02*
X2721849D01*
G01X2736729Y1402216D02*
Y1389716D01*
G01X2733164Y1402216D02*
X2740294D01*
G01X2752229Y1389716D02*
X2746029D01*
Y1402216D01*
X2752229D01*
G01X2749749Y1396174D02*
X2746029D01*
G01X2758119Y1389716D02*
Y1402216D01*
X2761219D01*
X2762459Y1401591D01*
X2763389Y1400758D01*
X2764164Y1399508D01*
X2764784Y1398049D01*
X2764939Y1395966D01*
X2764784Y1393883D01*
X2764164Y1392424D01*
X2763389Y1391174D01*
X2762459Y1390341D01*
X2761219Y1389716D01*
X2758119D01*
G01X2696429Y1450316D02*
Y1462816D01*
X2700149D01*
X2701389Y1462191D01*
X2702319Y1460733D01*
X2702629Y1459066D01*
X2702319Y1457399D01*
X2701544Y1456149D01*
X2700149Y1455524D01*
X2696429D01*
G01X2708829Y1462816D02*
Y1450316D01*
X2715029D01*
G01X2720454D02*
X2724329Y1462816D01*
X2728204Y1450316D01*
G01X2726809Y1454691D02*
X2721849D01*
G01X2736729Y1462816D02*
Y1450316D01*
G01X2733164Y1462816D02*
X2740294D01*
G01X2752229Y1450316D02*
X2746029D01*
Y1462816D01*
X2752229D01*
G01X2749749Y1456774D02*
X2746029D01*
G01X2758119Y1450316D02*
Y1462816D01*
X2761219D01*
X2762459Y1462191D01*
X2763389Y1461358D01*
X2764164Y1460108D01*
X2764784Y1458649D01*
X2764939Y1456566D01*
X2764784Y1454483D01*
X2764164Y1453024D01*
X2763389Y1451774D01*
X2762459Y1450941D01*
X2761219Y1450316D01*
X2758119D01*
G01X2696429Y1510916D02*
Y1523416D01*
X2700149D01*
X2701389Y1522791D01*
X2702319Y1521333D01*
X2702629Y1519666D01*
X2702319Y1517999D01*
X2701544Y1516749D01*
X2700149Y1516124D01*
X2696429D01*
G01X2708829Y1523416D02*
Y1510916D01*
X2715029D01*
G01X2720454D02*
X2724329Y1523416D01*
X2728204Y1510916D01*
G01X2726809Y1515291D02*
X2721849D01*
G01X2736729Y1523416D02*
Y1510916D01*
G01X2733164Y1523416D02*
X2740294D01*
G01X2752229Y1510916D02*
X2746029D01*
Y1523416D01*
X2752229D01*
G01X2749749Y1517374D02*
X2746029D01*
G01X2758119Y1510916D02*
Y1523416D01*
X2761219D01*
X2762459Y1522791D01*
X2763389Y1521958D01*
X2764164Y1520708D01*
X2764784Y1519249D01*
X2764939Y1517166D01*
X2764784Y1515083D01*
X2764164Y1513624D01*
X2763389Y1512374D01*
X2762459Y1511541D01*
X2761219Y1510916D01*
X2758119D01*
G01X2696429Y1556816D02*
Y1569316D01*
X2700149D01*
X2701389Y1568691D01*
X2702319Y1567233D01*
X2702629Y1565566D01*
X2702319Y1563899D01*
X2701544Y1562649D01*
X2700149Y1562024D01*
X2696429D01*
G01X2708829Y1569316D02*
Y1556816D01*
X2715029D01*
G01X2720454D02*
X2724329Y1569316D01*
X2728204Y1556816D01*
G01X2726809Y1561191D02*
X2721849D01*
G01X2736729Y1569316D02*
Y1556816D01*
G01X2733164Y1569316D02*
X2740294D01*
G01X2752229Y1556816D02*
X2746029D01*
Y1569316D01*
X2752229D01*
G01X2749749Y1563274D02*
X2746029D01*
G01X2758119Y1556816D02*
Y1569316D01*
X2761219D01*
X2762459Y1568691D01*
X2763389Y1567858D01*
X2764164Y1566608D01*
X2764784Y1565149D01*
X2764939Y1563066D01*
X2764784Y1560983D01*
X2764164Y1559524D01*
X2763389Y1558274D01*
X2762459Y1557441D01*
X2761219Y1556816D01*
X2758119D01*
G01X2794079Y1575566D02*
Y-88734D01*
G01X2829419Y-62184D02*
X2830349Y-63643D01*
X2831589Y-64476D01*
X2832984Y-64684D01*
X2834224Y-64476D01*
X2835464Y-63434D01*
X2836239Y-62184D01*
X2836394Y-60934D01*
X2836084Y-59476D01*
X2834999Y-58434D01*
X2833914Y-58017D01*
X2832519D01*
G01X2833914D02*
X2834844Y-57392D01*
X2835619Y-56351D01*
X2835929Y-55101D01*
X2835619Y-53851D01*
X2834844Y-52809D01*
X2833449Y-52184D01*
X2832054Y-52392D01*
X2830659Y-53226D01*
G01X2832829Y-4084D02*
Y8416D01*
X2830969Y5916D01*
G01Y-4084D02*
X2834689D01*
G01X2829884Y66933D02*
X2830814Y68182D01*
X2831899Y68808D01*
X2833139Y69016D01*
X2834689Y68599D01*
X2835774Y67558D01*
X2836084Y66308D01*
X2835929Y65057D01*
X2835309Y64016D01*
X2832209Y61933D01*
X2830814Y60474D01*
X2829884Y58391D01*
X2829574Y56516D01*
X2836084D01*
G01X2834689Y117116D02*
Y129616D01*
X2828954Y120658D01*
X2836704D01*
G01X2829884Y188133D02*
X2830814Y189382D01*
X2831899Y190008D01*
X2833139Y190216D01*
X2834689Y189799D01*
X2835774Y188758D01*
X2836084Y187508D01*
X2835929Y186257D01*
X2835309Y185216D01*
X2832209Y183133D01*
X2830814Y181674D01*
X2829884Y179591D01*
X2829574Y177716D01*
X2836084D01*
G01X2829884Y248733D02*
X2830814Y249982D01*
X2831899Y250608D01*
X2833139Y250816D01*
X2834689Y250399D01*
X2835774Y249358D01*
X2836084Y248108D01*
X2835929Y246857D01*
X2835309Y245816D01*
X2832209Y243733D01*
X2830814Y242274D01*
X2829884Y240191D01*
X2829574Y238316D01*
X2836084D01*
G01X2832829Y298916D02*
X2833914Y299124D01*
X2835154Y299749D01*
X2835929Y300791D01*
X2836239Y302249D01*
X2835929Y303707D01*
X2834999Y304958D01*
X2833604Y305583D01*
X2832054D01*
X2831124Y305999D01*
X2830349Y307041D01*
X2830039Y308499D01*
X2830504Y309958D01*
X2831589Y310999D01*
X2832829Y311416D01*
X2834069Y310999D01*
X2835154Y309958D01*
X2835619Y308499D01*
X2835309Y307041D01*
X2834534Y305999D01*
X2833604Y305583D01*
X2832054D01*
X2830659Y304958D01*
X2829729Y303707D01*
X2829419Y302249D01*
X2829729Y300791D01*
X2830504Y299749D01*
X2831744Y299124D01*
X2832829Y298916D01*
G01Y359516D02*
X2833914Y359724D01*
X2835154Y360349D01*
X2835929Y361391D01*
X2836239Y362849D01*
X2835929Y364307D01*
X2834999Y365558D01*
X2833604Y366183D01*
X2832054D01*
X2831124Y366599D01*
X2830349Y367641D01*
X2830039Y369099D01*
X2830504Y370558D01*
X2831589Y371599D01*
X2832829Y372016D01*
X2834069Y371599D01*
X2835154Y370558D01*
X2835619Y369099D01*
X2835309Y367641D01*
X2834534Y366599D01*
X2833604Y366183D01*
X2832054D01*
X2830659Y365558D01*
X2829729Y364307D01*
X2829419Y362849D01*
X2829729Y361391D01*
X2830504Y360349D01*
X2831744Y359724D01*
X2832829Y359516D01*
G01X2832519Y420116D02*
X2832829Y422824D01*
X2833294Y425116D01*
X2833914Y427199D01*
X2834689Y429491D01*
X2835929Y432616D01*
X2829729D01*
G01X2823219Y483216D02*
X2824149Y481757D01*
X2825389Y480924D01*
X2826784Y480716D01*
X2828024Y480924D01*
X2829264Y481966D01*
X2830039Y483216D01*
X2830194Y484466D01*
X2829884Y485924D01*
X2828799Y486966D01*
X2827714Y487383D01*
X2826319D01*
G01X2827714D02*
X2828644Y488008D01*
X2829419Y489049D01*
X2829729Y490299D01*
X2829419Y491549D01*
X2828644Y492591D01*
X2827249Y493216D01*
X2825854Y493008D01*
X2824459Y492174D01*
G01X2838719Y480716D02*
X2839029Y483424D01*
X2839494Y485716D01*
X2840114Y487799D01*
X2840889Y490091D01*
X2842129Y493216D01*
X2835929D01*
G01X2823219Y543816D02*
X2824149Y542357D01*
X2825389Y541524D01*
X2826784Y541316D01*
X2828024Y541524D01*
X2829264Y542566D01*
X2830039Y543816D01*
X2830194Y545066D01*
X2829884Y546524D01*
X2828799Y547566D01*
X2827714Y547983D01*
X2826319D01*
G01X2827714D02*
X2828644Y548608D01*
X2829419Y549649D01*
X2829729Y550899D01*
X2829419Y552149D01*
X2828644Y553191D01*
X2827249Y553816D01*
X2825854Y553608D01*
X2824459Y552774D01*
G01X2838719Y541316D02*
X2839029Y544024D01*
X2839494Y546316D01*
X2840114Y548399D01*
X2840889Y550691D01*
X2842129Y553816D01*
X2835929D01*
G01X2834689Y601916D02*
Y614416D01*
X2828954Y605458D01*
X2836704D01*
G01X2832829Y662516D02*
X2833914Y662724D01*
X2835154Y663349D01*
X2835929Y664391D01*
X2836239Y665849D01*
X2835929Y667307D01*
X2834999Y668558D01*
X2833604Y669183D01*
X2832054D01*
X2831124Y669599D01*
X2830349Y670641D01*
X2830039Y672099D01*
X2830504Y673558D01*
X2831589Y674599D01*
X2832829Y675016D01*
X2834069Y674599D01*
X2835154Y673558D01*
X2835619Y672099D01*
X2835309Y670641D01*
X2834534Y669599D01*
X2833604Y669183D01*
X2832054D01*
X2830659Y668558D01*
X2829729Y667307D01*
X2829419Y665849D01*
X2829729Y664391D01*
X2830504Y663349D01*
X2831744Y662724D01*
X2832829Y662516D01*
G01X2829419Y725616D02*
X2830349Y724157D01*
X2831589Y723324D01*
X2832984Y723116D01*
X2834224Y723324D01*
X2835464Y724366D01*
X2836239Y725616D01*
X2836394Y726866D01*
X2836084Y728324D01*
X2834999Y729366D01*
X2833914Y729783D01*
X2832519D01*
G01X2833914D02*
X2834844Y730408D01*
X2835619Y731449D01*
X2835929Y732699D01*
X2835619Y733949D01*
X2834844Y734991D01*
X2833449Y735616D01*
X2832054Y735408D01*
X2830659Y734574D01*
G01X2829884Y788924D02*
X2830969Y790383D01*
X2831899Y791216D01*
X2833139Y791633D01*
X2834224Y791216D01*
X2834999Y790383D01*
X2835619Y789133D01*
X2835774Y787674D01*
X2835619Y786424D01*
X2834999Y785174D01*
X2834069Y784133D01*
X2832984Y783716D01*
X2831744Y784133D01*
X2830659Y785382D01*
X2830039Y787258D01*
X2829884Y789341D01*
X2830194Y792049D01*
X2830659Y793508D01*
X2831434Y794966D01*
X2832519Y796008D01*
X2833604Y796216D01*
X2834689Y795799D01*
X2835464Y794758D01*
G01X2832829Y844316D02*
Y856816D01*
X2830969Y854316D01*
G01Y844316D02*
X2834689D01*
G01X2832829Y904916D02*
Y917416D01*
X2830969Y914916D01*
G01Y904916D02*
X2834689D01*
G01X2823684Y970724D02*
X2824769Y972183D01*
X2825699Y973016D01*
X2826939Y973433D01*
X2828024Y973016D01*
X2828799Y972183D01*
X2829419Y970933D01*
X2829574Y969474D01*
X2829419Y968224D01*
X2828799Y966974D01*
X2827869Y965933D01*
X2826784Y965516D01*
X2825544Y965933D01*
X2824459Y967182D01*
X2823839Y969058D01*
X2823684Y971141D01*
X2823994Y973849D01*
X2824459Y975308D01*
X2825234Y976766D01*
X2826319Y977808D01*
X2827404Y978016D01*
X2828489Y977599D01*
X2829264Y976558D01*
G01X2836084Y975933D02*
X2837014Y977182D01*
X2838099Y977808D01*
X2839339Y978016D01*
X2840889Y977599D01*
X2841974Y976558D01*
X2842284Y975308D01*
X2842129Y974057D01*
X2841509Y973016D01*
X2838409Y970933D01*
X2837014Y969474D01*
X2836084Y967391D01*
X2835774Y965516D01*
X2842284D01*
G01X2817484Y1031324D02*
X2818569Y1032783D01*
X2819499Y1033616D01*
X2820739Y1034033D01*
X2821824Y1033616D01*
X2822599Y1032783D01*
X2823219Y1031533D01*
X2823374Y1030074D01*
X2823219Y1028824D01*
X2822599Y1027574D01*
X2821669Y1026533D01*
X2820584Y1026116D01*
X2819344Y1026533D01*
X2818259Y1027782D01*
X2817639Y1029658D01*
X2817484Y1031741D01*
X2817794Y1034449D01*
X2818259Y1035908D01*
X2819034Y1037366D01*
X2820119Y1038408D01*
X2821204Y1038616D01*
X2822289Y1038199D01*
X2823064Y1037158D01*
G01X2829419Y1027991D02*
X2830349Y1026949D01*
X2831434Y1026324D01*
X2832829Y1026116D01*
X2834224Y1026533D01*
X2835309Y1027366D01*
X2836084Y1028824D01*
X2836239Y1030491D01*
X2835929Y1032158D01*
X2835154Y1033199D01*
X2834069Y1034033D01*
X2832984Y1034241D01*
X2831899Y1034033D01*
X2830504Y1033199D01*
X2830969Y1038616D01*
X2835154D01*
G01X2842284Y1031324D02*
X2843369Y1032783D01*
X2844299Y1033616D01*
X2845539Y1034033D01*
X2846624Y1033616D01*
X2847399Y1032783D01*
X2848019Y1031533D01*
X2848174Y1030074D01*
X2848019Y1028824D01*
X2847399Y1027574D01*
X2846469Y1026533D01*
X2845384Y1026116D01*
X2844144Y1026533D01*
X2843059Y1027782D01*
X2842439Y1029658D01*
X2842284Y1031741D01*
X2842594Y1034449D01*
X2843059Y1035908D01*
X2843834Y1037366D01*
X2844919Y1038408D01*
X2846004Y1038616D01*
X2847089Y1038199D01*
X2847864Y1037158D01*
G01X2823684Y1091924D02*
X2824769Y1093383D01*
X2825699Y1094216D01*
X2826939Y1094633D01*
X2828024Y1094216D01*
X2828799Y1093383D01*
X2829419Y1092133D01*
X2829574Y1090674D01*
X2829419Y1089424D01*
X2828799Y1088174D01*
X2827869Y1087133D01*
X2826784Y1086716D01*
X2825544Y1087133D01*
X2824459Y1088382D01*
X2823839Y1090258D01*
X2823684Y1092341D01*
X2823994Y1095049D01*
X2824459Y1096508D01*
X2825234Y1097966D01*
X2826319Y1099008D01*
X2827404Y1099216D01*
X2828489Y1098799D01*
X2829264Y1097758D01*
G01X2839029Y1099216D02*
X2837789Y1098799D01*
X2836859Y1097758D01*
X2836239Y1096508D01*
X2835774Y1094841D01*
X2835619Y1092966D01*
X2835774Y1091091D01*
X2836239Y1089424D01*
X2836859Y1088174D01*
X2837789Y1087133D01*
X2839029Y1086716D01*
X2840269Y1087133D01*
X2841199Y1088174D01*
X2841819Y1089424D01*
X2842284Y1091091D01*
X2842439Y1092966D01*
X2842284Y1094841D01*
X2841819Y1096508D01*
X2841199Y1097758D01*
X2840269Y1098799D01*
X2839029Y1099216D01*
G01X2823994Y1148774D02*
X2825079Y1147733D01*
X2826319Y1147316D01*
X2827559Y1147733D01*
X2828644Y1148982D01*
X2829419Y1150858D01*
X2829729Y1152733D01*
Y1155024D01*
X2829419Y1156899D01*
X2828644Y1158566D01*
X2827714Y1159399D01*
X2826629Y1159816D01*
X2825389Y1159399D01*
X2824459Y1158566D01*
X2823839Y1157316D01*
X2823529Y1155649D01*
X2823839Y1154191D01*
X2824614Y1152733D01*
X2825544Y1151899D01*
X2826629Y1151691D01*
X2827869Y1152107D01*
X2828799Y1153149D01*
X2829729Y1155024D01*
G01X2839029Y1147316D02*
Y1159816D01*
X2837169Y1157316D01*
G01Y1147316D02*
X2840889D01*
G01X2814229Y1207916D02*
Y1220416D01*
X2812369Y1217916D01*
G01Y1207916D02*
X2816089D01*
G01X2823219Y1209791D02*
X2824149Y1208749D01*
X2825234Y1208124D01*
X2826629Y1207916D01*
X2828024Y1208333D01*
X2829109Y1209166D01*
X2829884Y1210624D01*
X2830039Y1212291D01*
X2829729Y1213958D01*
X2828954Y1214999D01*
X2827869Y1215833D01*
X2826784Y1216041D01*
X2825699Y1215833D01*
X2824304Y1214999D01*
X2824769Y1220416D01*
X2828954D01*
G01X2836084Y1213124D02*
X2837169Y1214583D01*
X2838099Y1215416D01*
X2839339Y1215833D01*
X2840424Y1215416D01*
X2841199Y1214583D01*
X2841819Y1213333D01*
X2841974Y1211874D01*
X2841819Y1210624D01*
X2841199Y1209374D01*
X2840269Y1208333D01*
X2839184Y1207916D01*
X2837944Y1208333D01*
X2836859Y1209582D01*
X2836239Y1211458D01*
X2836084Y1213541D01*
X2836394Y1216249D01*
X2836859Y1217708D01*
X2837634Y1219166D01*
X2838719Y1220208D01*
X2839804Y1220416D01*
X2840889Y1219999D01*
X2841664Y1218958D01*
G01X2851119Y1207916D02*
X2851429Y1210624D01*
X2851894Y1212916D01*
X2852514Y1214999D01*
X2853289Y1217291D01*
X2854529Y1220416D01*
X2848329D01*
G01X2817794Y1269974D02*
X2818879Y1268933D01*
X2820119Y1268516D01*
X2821359Y1268933D01*
X2822444Y1270182D01*
X2823219Y1272058D01*
X2823529Y1273933D01*
Y1276224D01*
X2823219Y1278099D01*
X2822444Y1279766D01*
X2821514Y1280599D01*
X2820429Y1281016D01*
X2819189Y1280599D01*
X2818259Y1279766D01*
X2817639Y1278516D01*
X2817329Y1276849D01*
X2817639Y1275391D01*
X2818414Y1273933D01*
X2819344Y1273099D01*
X2820429Y1272891D01*
X2821669Y1273307D01*
X2822599Y1274349D01*
X2823529Y1276224D01*
G01X2829884Y1273724D02*
X2830969Y1275183D01*
X2831899Y1276016D01*
X2833139Y1276433D01*
X2834224Y1276016D01*
X2834999Y1275183D01*
X2835619Y1273933D01*
X2835774Y1272474D01*
X2835619Y1271224D01*
X2834999Y1269974D01*
X2834069Y1268933D01*
X2832984Y1268516D01*
X2831744Y1268933D01*
X2830659Y1270182D01*
X2830039Y1272058D01*
X2829884Y1274141D01*
X2830194Y1276849D01*
X2830659Y1278308D01*
X2831434Y1279766D01*
X2832519Y1280808D01*
X2833604Y1281016D01*
X2834689Y1280599D01*
X2835464Y1279558D01*
G01X2845229Y1268516D02*
X2846314Y1268724D01*
X2847554Y1269349D01*
X2848329Y1270391D01*
X2848639Y1271849D01*
X2848329Y1273307D01*
X2847399Y1274558D01*
X2846004Y1275183D01*
X2844454D01*
X2843524Y1275599D01*
X2842749Y1276641D01*
X2842439Y1278099D01*
X2842904Y1279558D01*
X2843989Y1280599D01*
X2845229Y1281016D01*
X2846469Y1280599D01*
X2847554Y1279558D01*
X2848019Y1278099D01*
X2847709Y1276641D01*
X2846934Y1275599D01*
X2846004Y1275183D01*
X2844454D01*
X2843059Y1274558D01*
X2842129Y1273307D01*
X2841819Y1271849D01*
X2842129Y1270391D01*
X2842904Y1269349D01*
X2844144Y1268724D01*
X2845229Y1268516D01*
G01X2823219Y1331616D02*
X2824149Y1330157D01*
X2825389Y1329324D01*
X2826784Y1329116D01*
X2828024Y1329324D01*
X2829264Y1330366D01*
X2830039Y1331616D01*
X2830194Y1332866D01*
X2829884Y1334324D01*
X2828799Y1335366D01*
X2827714Y1335783D01*
X2826319D01*
G01X2827714D02*
X2828644Y1336408D01*
X2829419Y1337449D01*
X2829729Y1338699D01*
X2829419Y1339949D01*
X2828644Y1340991D01*
X2827249Y1341616D01*
X2825854Y1341408D01*
X2824459Y1340574D01*
G01X2835619Y1330991D02*
X2836549Y1329949D01*
X2837634Y1329324D01*
X2839029Y1329116D01*
X2840424Y1329533D01*
X2841509Y1330366D01*
X2842284Y1331824D01*
X2842439Y1333491D01*
X2842129Y1335158D01*
X2841354Y1336199D01*
X2840269Y1337033D01*
X2839184Y1337241D01*
X2838099Y1337033D01*
X2836704Y1336199D01*
X2837169Y1341616D01*
X2841354D01*
G01X2816089Y1389716D02*
Y1402216D01*
X2810354Y1393258D01*
X2818104D01*
G01X2823684Y1400133D02*
X2824614Y1401382D01*
X2825699Y1402008D01*
X2826939Y1402216D01*
X2828489Y1401799D01*
X2829574Y1400758D01*
X2829884Y1399508D01*
X2829729Y1398257D01*
X2829109Y1397216D01*
X2826009Y1395133D01*
X2824614Y1393674D01*
X2823684Y1391591D01*
X2823374Y1389716D01*
X2829884D01*
G01X2835619Y1392216D02*
X2836549Y1390757D01*
X2837789Y1389924D01*
X2839184Y1389716D01*
X2840424Y1389924D01*
X2841664Y1390966D01*
X2842439Y1392216D01*
X2842594Y1393466D01*
X2842284Y1394924D01*
X2841199Y1395966D01*
X2840114Y1396383D01*
X2838719D01*
G01X2840114D02*
X2841044Y1397008D01*
X2841819Y1398049D01*
X2842129Y1399299D01*
X2841819Y1400549D01*
X2841044Y1401591D01*
X2839649Y1402216D01*
X2838254Y1402008D01*
X2836859Y1401174D01*
G01X2848019Y1392216D02*
X2848949Y1390757D01*
X2850189Y1389924D01*
X2851584Y1389716D01*
X2852824Y1389924D01*
X2854064Y1390966D01*
X2854839Y1392216D01*
X2854994Y1393466D01*
X2854684Y1394924D01*
X2853599Y1395966D01*
X2852514Y1396383D01*
X2851119D01*
G01X2852514D02*
X2853444Y1397008D01*
X2854219Y1398049D01*
X2854529Y1399299D01*
X2854219Y1400549D01*
X2853444Y1401591D01*
X2852049Y1402216D01*
X2850654Y1402008D01*
X2849259Y1401174D01*
G01X2817484Y1460733D02*
X2818414Y1461982D01*
X2819499Y1462608D01*
X2820739Y1462816D01*
X2822289Y1462399D01*
X2823374Y1461358D01*
X2823684Y1460108D01*
X2823529Y1458857D01*
X2822909Y1457816D01*
X2819809Y1455733D01*
X2818414Y1454274D01*
X2817484Y1452191D01*
X2817174Y1450316D01*
X2823684D01*
G01X2832829D02*
X2833914Y1450524D01*
X2835154Y1451149D01*
X2835929Y1452191D01*
X2836239Y1453649D01*
X2835929Y1455107D01*
X2834999Y1456358D01*
X2833604Y1456983D01*
X2832054D01*
X2831124Y1457399D01*
X2830349Y1458441D01*
X2830039Y1459899D01*
X2830504Y1461358D01*
X2831589Y1462399D01*
X2832829Y1462816D01*
X2834069Y1462399D01*
X2835154Y1461358D01*
X2835619Y1459899D01*
X2835309Y1458441D01*
X2834534Y1457399D01*
X2833604Y1456983D01*
X2832054D01*
X2830659Y1456358D01*
X2829729Y1455107D01*
X2829419Y1453649D01*
X2829729Y1452191D01*
X2830504Y1451149D01*
X2831744Y1450524D01*
X2832829Y1450316D01*
G01X2845229D02*
X2846314Y1450524D01*
X2847554Y1451149D01*
X2848329Y1452191D01*
X2848639Y1453649D01*
X2848329Y1455107D01*
X2847399Y1456358D01*
X2846004Y1456983D01*
X2844454D01*
X2843524Y1457399D01*
X2842749Y1458441D01*
X2842439Y1459899D01*
X2842904Y1461358D01*
X2843989Y1462399D01*
X2845229Y1462816D01*
X2846469Y1462399D01*
X2847554Y1461358D01*
X2848019Y1459899D01*
X2847709Y1458441D01*
X2846934Y1457399D01*
X2846004Y1456983D01*
X2844454D01*
X2843059Y1456358D01*
X2842129Y1455107D01*
X2841819Y1453649D01*
X2842129Y1452191D01*
X2842904Y1451149D01*
X2844144Y1450524D01*
X2845229Y1450316D01*
G01X2823684Y1521333D02*
X2824614Y1522582D01*
X2825699Y1523208D01*
X2826939Y1523416D01*
X2828489Y1522999D01*
X2829574Y1521958D01*
X2829884Y1520708D01*
X2829729Y1519457D01*
X2829109Y1518416D01*
X2826009Y1516333D01*
X2824614Y1514874D01*
X2823684Y1512791D01*
X2823374Y1510916D01*
X2829884D01*
G01X2836084Y1516124D02*
X2837169Y1517583D01*
X2838099Y1518416D01*
X2839339Y1518833D01*
X2840424Y1518416D01*
X2841199Y1517583D01*
X2841819Y1516333D01*
X2841974Y1514874D01*
X2841819Y1513624D01*
X2841199Y1512374D01*
X2840269Y1511333D01*
X2839184Y1510916D01*
X2837944Y1511333D01*
X2836859Y1512582D01*
X2836239Y1514458D01*
X2836084Y1516541D01*
X2836394Y1519249D01*
X2836859Y1520708D01*
X2837634Y1522166D01*
X2838719Y1523208D01*
X2839804Y1523416D01*
X2840889Y1522999D01*
X2841664Y1521958D01*
G01X2820429Y1556816D02*
X2819189Y1557024D01*
X2818104Y1557857D01*
X2817174Y1559108D01*
X2816554Y1560566D01*
X2816244Y1562233D01*
Y1563899D01*
X2816554Y1565566D01*
X2817174Y1567024D01*
X2818104Y1568274D01*
X2819189Y1569108D01*
X2820429Y1569316D01*
X2821669Y1569108D01*
X2822754Y1568274D01*
X2823684Y1567024D01*
X2824304Y1565566D01*
X2824614Y1563899D01*
Y1562233D01*
X2824304Y1560566D01*
X2823684Y1559108D01*
X2822754Y1557857D01*
X2821669Y1557024D01*
X2820429Y1556816D01*
G01X2821669Y1560149D02*
X2823529Y1556816D01*
G01X2832829Y1569316D02*
Y1556816D01*
G01X2829264Y1569316D02*
X2836394D01*
G01X2845229Y1556816D02*
Y1562441D01*
X2842129Y1569316D01*
G01X2848329D02*
X2845229Y1562441D01*
G01X0Y-137756D02*
G03X15000Y-152756I15000J0D01*
G01X0Y-137756D02*
G03X15000Y-152756I15000J0D01*
G01X0Y-11811D02*
Y-137756D01*
G01Y-11811D02*
Y-137756D01*
G01X854331Y-152756D02*
X15000D01*
G01X854331D02*
X15000D01*
G01X23622Y-7874D02*
G03Y0I0J3937D01*
G01Y-7874D02*
G03Y0I0J3937D01*
G01X0Y3937D02*
G03X3937Y0I3937J0D01*
G01Y-7874D02*
X23622D01*
G01X0Y3937D02*
G03X3937Y0I3937J0D01*
G01Y-7874D02*
X23622D01*
G01X3937D02*
G03X0Y-11811I0J-3937D01*
G01X3937Y-7874D02*
G03X0Y-11811I0J-3937D01*
G01X3937Y0D02*
X397638D01*
G01X3937D02*
X397638D01*
G01X0Y1370866D02*
Y3937D01*
G01Y1370866D02*
Y3937D01*
G01X3937Y1374803D02*
G03X0Y1370866I0J-3937D01*
G01X3937Y1374803D02*
G03X0Y1370866I0J-3937D01*
G01X23622Y1374803D02*
G03Y1382677I0J3937D01*
G01Y1374803D02*
G03Y1382677I0J3937D01*
G01X3937D02*
X23622D01*
G01X0Y1386614D02*
G03X3937Y1382677I3937J0D01*
G01D02*
X23622D01*
G01X0Y1386614D02*
G03X3937Y1382677I3937J0D01*
G01Y1374803D02*
X746850D01*
G01D02*
X3937D01*
G01X0Y1386614D02*
Y1643268D01*
G01Y1386614D02*
Y1643268D01*
G01X15000Y1658268D02*
G03X0Y1643268I0J-15000D01*
G01X15000Y1658268D02*
G03X0Y1643268I0J-15000D01*
G01X775591Y1658268D02*
X15000D01*
G01X775591D02*
X15000D01*
G01X54331Y-7874D02*
X323228D01*
G01X54331D02*
X323228D01*
G01X54331Y0D02*
G03Y-7874I0J-3937D01*
G01Y0D02*
G03Y-7874I0J-3937D01*
G01X54764Y367773D02*
X55164Y367440D01*
X55631Y367240D01*
X56231Y367173D01*
X56831Y367306D01*
X57298Y367573D01*
X57631Y368040D01*
X57698Y368573D01*
X57564Y369106D01*
X57231Y369440D01*
X56764Y369706D01*
X56298Y369773D01*
X55831Y369706D01*
X55231Y369440D01*
X55431Y371173D01*
X57231D01*
G01X59364Y367773D02*
X59764Y367440D01*
X60231Y367240D01*
X60831Y367173D01*
X61431Y367306D01*
X61898Y367573D01*
X62231Y368040D01*
X62298Y368573D01*
X62164Y369106D01*
X61831Y369440D01*
X61364Y369706D01*
X60898Y369773D01*
X60431Y369706D01*
X59831Y369440D01*
X60031Y371173D01*
X61831D01*
G01X65298Y367173D02*
X65431Y368040D01*
X65631Y368773D01*
X65898Y369440D01*
X66231Y370173D01*
X66764Y371173D01*
X64098D01*
G01X70031Y367040D02*
X69898Y367106D01*
Y367240D01*
X70031Y367306D01*
X70164Y367240D01*
Y367106D01*
X70031Y367040D01*
G01X74631Y371173D02*
X74098Y371040D01*
X73698Y370706D01*
X73431Y370306D01*
X73231Y369773D01*
X73164Y369173D01*
X73231Y368573D01*
X73431Y368040D01*
X73698Y367640D01*
X74098Y367306D01*
X74631Y367173D01*
X75164Y367306D01*
X75564Y367640D01*
X75831Y368040D01*
X76031Y368573D01*
X76098Y369173D01*
X76031Y369773D01*
X75831Y370306D01*
X75564Y370706D01*
X75164Y371040D01*
X74631Y371173D01*
G01X78098Y367640D02*
X78564Y367306D01*
X79098Y367173D01*
X79631Y367306D01*
X80098Y367706D01*
X80431Y368306D01*
X80564Y368906D01*
Y369640D01*
X80431Y370240D01*
X80098Y370773D01*
X79698Y371040D01*
X79231Y371173D01*
X78698Y371040D01*
X78298Y370773D01*
X78031Y370373D01*
X77898Y369840D01*
X78031Y369373D01*
X78364Y368906D01*
X78764Y368640D01*
X79231Y368573D01*
X79764Y368706D01*
X80164Y369040D01*
X80564Y369640D01*
G01X72103Y378319D02*
X72503Y378719D01*
X72970Y378919D01*
X73503Y378986D01*
X74170Y378853D01*
X74637Y378519D01*
X74770Y378119D01*
X74703Y377719D01*
X74437Y377386D01*
X73103Y376719D01*
X72503Y376253D01*
X72103Y375586D01*
X71970Y374986D01*
X74770D01*
G01X76503Y375786D02*
X76903Y375319D01*
X77437Y375053D01*
X78037Y374986D01*
X78570Y375053D01*
X79103Y375386D01*
X79437Y375786D01*
X79503Y376186D01*
X79370Y376653D01*
X78903Y376986D01*
X78437Y377119D01*
X77837D01*
G01X78437D02*
X78837Y377319D01*
X79170Y377653D01*
X79303Y378053D01*
X79170Y378453D01*
X78837Y378786D01*
X78237Y378986D01*
X77637Y378919D01*
X77037Y378653D01*
G01X81303Y376653D02*
X81770Y377119D01*
X82170Y377386D01*
X82703Y377519D01*
X83170Y377386D01*
X83503Y377119D01*
X83770Y376719D01*
X83837Y376253D01*
X83770Y375853D01*
X83503Y375453D01*
X83103Y375119D01*
X82637Y374986D01*
X82103Y375119D01*
X81637Y375519D01*
X81370Y376119D01*
X81303Y376786D01*
X81437Y377653D01*
X81637Y378119D01*
X81970Y378586D01*
X82437Y378919D01*
X82903Y378986D01*
X83370Y378853D01*
X83703Y378519D01*
G01X87170Y374853D02*
X87037Y374919D01*
Y375053D01*
X87170Y375119D01*
X87303Y375053D01*
Y374919D01*
X87170Y374853D01*
G01X90503Y378319D02*
X90903Y378719D01*
X91370Y378919D01*
X91903Y378986D01*
X92570Y378853D01*
X93037Y378519D01*
X93170Y378119D01*
X93103Y377719D01*
X92837Y377386D01*
X91503Y376719D01*
X90903Y376253D01*
X90503Y375586D01*
X90370Y374986D01*
X93170D01*
G01X95103Y378319D02*
X95503Y378719D01*
X95970Y378919D01*
X96503Y378986D01*
X97170Y378853D01*
X97637Y378519D01*
X97770Y378119D01*
X97703Y377719D01*
X97437Y377386D01*
X96103Y376719D01*
X95503Y376253D01*
X95103Y375586D01*
X94970Y374986D01*
X97770D01*
G01X36107Y483059D02*
Y487059D01*
X35307Y486259D01*
G01Y483059D02*
X36907D01*
G01X39440Y484726D02*
X39907Y485192D01*
X40307Y485459D01*
X40840Y485592D01*
X41307Y485459D01*
X41640Y485192D01*
X41907Y484792D01*
X41974Y484326D01*
X41907Y483926D01*
X41640Y483526D01*
X41240Y483192D01*
X40774Y483059D01*
X40240Y483192D01*
X39774Y483592D01*
X39507Y484192D01*
X39440Y484859D01*
X39574Y485726D01*
X39774Y486192D01*
X40107Y486659D01*
X40574Y486992D01*
X41040Y487059D01*
X41507Y486926D01*
X41840Y486592D01*
G01X44040Y484726D02*
X44507Y485192D01*
X44907Y485459D01*
X45440Y485592D01*
X45907Y485459D01*
X46240Y485192D01*
X46507Y484792D01*
X46574Y484326D01*
X46507Y483926D01*
X46240Y483526D01*
X45840Y483192D01*
X45374Y483059D01*
X44840Y483192D01*
X44374Y483592D01*
X44107Y484192D01*
X44040Y484859D01*
X44174Y485726D01*
X44374Y486192D01*
X44707Y486659D01*
X45174Y486992D01*
X45640Y487059D01*
X46107Y486926D01*
X46440Y486592D01*
G01X48507Y483059D02*
X51307Y487059D01*
G01X48507D02*
X51307Y483059D01*
G01X53240Y486392D02*
X53640Y486792D01*
X54107Y486992D01*
X54640Y487059D01*
X55307Y486926D01*
X55774Y486592D01*
X55907Y486192D01*
X55840Y485792D01*
X55574Y485459D01*
X54240Y484792D01*
X53640Y484326D01*
X53240Y483659D01*
X53107Y483059D01*
X55907D01*
G01X59907D02*
Y487059D01*
X57440Y484192D01*
X60774D01*
G01X62240Y483659D02*
X62640Y483326D01*
X63107Y483126D01*
X63707Y483059D01*
X64307Y483192D01*
X64774Y483459D01*
X65107Y483926D01*
X65174Y484459D01*
X65040Y484992D01*
X64707Y485326D01*
X64240Y485592D01*
X63774Y485659D01*
X63307Y485592D01*
X62707Y485326D01*
X62907Y487059D01*
X64707D01*
G01X54763Y820529D02*
X55163Y820196D01*
X55630Y819996D01*
X56230Y819929D01*
X56830Y820062D01*
X57297Y820329D01*
X57630Y820796D01*
X57697Y821329D01*
X57563Y821862D01*
X57230Y822196D01*
X56763Y822462D01*
X56297Y822529D01*
X55830Y822462D01*
X55230Y822196D01*
X55430Y823929D01*
X57230D01*
G01X59363Y820529D02*
X59763Y820196D01*
X60230Y819996D01*
X60830Y819929D01*
X61430Y820062D01*
X61897Y820329D01*
X62230Y820796D01*
X62297Y821329D01*
X62163Y821862D01*
X61830Y822196D01*
X61363Y822462D01*
X60897Y822529D01*
X60430Y822462D01*
X59830Y822196D01*
X60030Y823929D01*
X61830D01*
G01X65297Y819929D02*
X65430Y820796D01*
X65630Y821529D01*
X65897Y822196D01*
X66230Y822929D01*
X66763Y823929D01*
X64097D01*
G01X70030Y819796D02*
X69897Y819862D01*
Y819996D01*
X70030Y820062D01*
X70163Y819996D01*
Y819862D01*
X70030Y819796D01*
G01X74630Y823929D02*
X74097Y823796D01*
X73697Y823462D01*
X73430Y823062D01*
X73230Y822529D01*
X73163Y821929D01*
X73230Y821329D01*
X73430Y820796D01*
X73697Y820396D01*
X74097Y820062D01*
X74630Y819929D01*
X75163Y820062D01*
X75563Y820396D01*
X75830Y820796D01*
X76030Y821329D01*
X76097Y821929D01*
X76030Y822529D01*
X75830Y823062D01*
X75563Y823462D01*
X75163Y823796D01*
X74630Y823929D01*
G01X78097Y820396D02*
X78563Y820062D01*
X79097Y819929D01*
X79630Y820062D01*
X80097Y820462D01*
X80430Y821062D01*
X80563Y821662D01*
Y822396D01*
X80430Y822996D01*
X80097Y823529D01*
X79697Y823796D01*
X79230Y823929D01*
X78697Y823796D01*
X78297Y823529D01*
X78030Y823129D01*
X77897Y822596D01*
X78030Y822129D01*
X78363Y821662D01*
X78763Y821396D01*
X79230Y821329D01*
X79763Y821462D01*
X80163Y821796D01*
X80563Y822396D01*
G01X72102Y831075D02*
X72502Y831475D01*
X72969Y831675D01*
X73502Y831742D01*
X74169Y831609D01*
X74636Y831275D01*
X74769Y830875D01*
X74702Y830475D01*
X74436Y830142D01*
X73102Y829475D01*
X72502Y829009D01*
X72102Y828342D01*
X71969Y827742D01*
X74769D01*
G01X76502Y828542D02*
X76902Y828075D01*
X77436Y827809D01*
X78036Y827742D01*
X78569Y827809D01*
X79102Y828142D01*
X79436Y828542D01*
X79502Y828942D01*
X79369Y829409D01*
X78902Y829742D01*
X78436Y829875D01*
X77836D01*
G01X78436D02*
X78836Y830075D01*
X79169Y830409D01*
X79302Y830809D01*
X79169Y831209D01*
X78836Y831542D01*
X78236Y831742D01*
X77636Y831675D01*
X77036Y831409D01*
G01X81302Y829409D02*
X81769Y829875D01*
X82169Y830142D01*
X82702Y830275D01*
X83169Y830142D01*
X83502Y829875D01*
X83769Y829475D01*
X83836Y829009D01*
X83769Y828609D01*
X83502Y828209D01*
X83102Y827875D01*
X82636Y827742D01*
X82102Y827875D01*
X81636Y828275D01*
X81369Y828875D01*
X81302Y829542D01*
X81436Y830409D01*
X81636Y830875D01*
X81969Y831342D01*
X82436Y831675D01*
X82902Y831742D01*
X83369Y831609D01*
X83702Y831275D01*
G01X87169Y827609D02*
X87036Y827675D01*
Y827809D01*
X87169Y827875D01*
X87302Y827809D01*
Y827675D01*
X87169Y827609D01*
G01X90502Y831075D02*
X90902Y831475D01*
X91369Y831675D01*
X91902Y831742D01*
X92569Y831609D01*
X93036Y831275D01*
X93169Y830875D01*
X93102Y830475D01*
X92836Y830142D01*
X91502Y829475D01*
X90902Y829009D01*
X90502Y828342D01*
X90369Y827742D01*
X93169D01*
G01X95102Y831075D02*
X95502Y831475D01*
X95969Y831675D01*
X96502Y831742D01*
X97169Y831609D01*
X97636Y831275D01*
X97769Y830875D01*
X97702Y830475D01*
X97436Y830142D01*
X96102Y829475D01*
X95502Y829009D01*
X95102Y828342D01*
X94969Y827742D01*
X97769D01*
G01X54764Y1273285D02*
X55164Y1272952D01*
X55631Y1272752D01*
X56231Y1272685D01*
X56831Y1272818D01*
X57298Y1273085D01*
X57631Y1273552D01*
X57698Y1274085D01*
X57564Y1274618D01*
X57231Y1274952D01*
X56764Y1275218D01*
X56298Y1275285D01*
X55831Y1275218D01*
X55231Y1274952D01*
X55431Y1276685D01*
X57231D01*
G01X59364Y1273285D02*
X59764Y1272952D01*
X60231Y1272752D01*
X60831Y1272685D01*
X61431Y1272818D01*
X61898Y1273085D01*
X62231Y1273552D01*
X62298Y1274085D01*
X62164Y1274618D01*
X61831Y1274952D01*
X61364Y1275218D01*
X60898Y1275285D01*
X60431Y1275218D01*
X59831Y1274952D01*
X60031Y1276685D01*
X61831D01*
G01X65298Y1272685D02*
X65431Y1273552D01*
X65631Y1274285D01*
X65898Y1274952D01*
X66231Y1275685D01*
X66764Y1276685D01*
X64098D01*
G01X70031Y1272552D02*
X69898Y1272618D01*
Y1272752D01*
X70031Y1272818D01*
X70164Y1272752D01*
Y1272618D01*
X70031Y1272552D01*
G01X74631Y1276685D02*
X74098Y1276552D01*
X73698Y1276218D01*
X73431Y1275818D01*
X73231Y1275285D01*
X73164Y1274685D01*
X73231Y1274085D01*
X73431Y1273552D01*
X73698Y1273152D01*
X74098Y1272818D01*
X74631Y1272685D01*
X75164Y1272818D01*
X75564Y1273152D01*
X75831Y1273552D01*
X76031Y1274085D01*
X76098Y1274685D01*
X76031Y1275285D01*
X75831Y1275818D01*
X75564Y1276218D01*
X75164Y1276552D01*
X74631Y1276685D01*
G01X78098Y1273152D02*
X78564Y1272818D01*
X79098Y1272685D01*
X79631Y1272818D01*
X80098Y1273218D01*
X80431Y1273818D01*
X80564Y1274418D01*
Y1275152D01*
X80431Y1275752D01*
X80098Y1276285D01*
X79698Y1276552D01*
X79231Y1276685D01*
X78698Y1276552D01*
X78298Y1276285D01*
X78031Y1275885D01*
X77898Y1275352D01*
X78031Y1274885D01*
X78364Y1274418D01*
X78764Y1274152D01*
X79231Y1274085D01*
X79764Y1274218D01*
X80164Y1274552D01*
X80564Y1275152D01*
G01X72103Y1283831D02*
X72503Y1284231D01*
X72970Y1284431D01*
X73503Y1284498D01*
X74170Y1284365D01*
X74637Y1284031D01*
X74770Y1283631D01*
X74703Y1283231D01*
X74437Y1282898D01*
X73103Y1282231D01*
X72503Y1281765D01*
X72103Y1281098D01*
X71970Y1280498D01*
X74770D01*
G01X76503Y1281298D02*
X76903Y1280831D01*
X77437Y1280565D01*
X78037Y1280498D01*
X78570Y1280565D01*
X79103Y1280898D01*
X79437Y1281298D01*
X79503Y1281698D01*
X79370Y1282165D01*
X78903Y1282498D01*
X78437Y1282631D01*
X77837D01*
G01X78437D02*
X78837Y1282831D01*
X79170Y1283165D01*
X79303Y1283565D01*
X79170Y1283965D01*
X78837Y1284298D01*
X78237Y1284498D01*
X77637Y1284431D01*
X77037Y1284165D01*
G01X81303Y1282165D02*
X81770Y1282631D01*
X82170Y1282898D01*
X82703Y1283031D01*
X83170Y1282898D01*
X83503Y1282631D01*
X83770Y1282231D01*
X83837Y1281765D01*
X83770Y1281365D01*
X83503Y1280965D01*
X83103Y1280631D01*
X82637Y1280498D01*
X82103Y1280631D01*
X81637Y1281031D01*
X81370Y1281631D01*
X81303Y1282298D01*
X81437Y1283165D01*
X81637Y1283631D01*
X81970Y1284098D01*
X82437Y1284431D01*
X82903Y1284498D01*
X83370Y1284365D01*
X83703Y1284031D01*
G01X87170Y1280365D02*
X87037Y1280431D01*
Y1280565D01*
X87170Y1280631D01*
X87303Y1280565D01*
Y1280431D01*
X87170Y1280365D01*
G01X90503Y1283831D02*
X90903Y1284231D01*
X91370Y1284431D01*
X91903Y1284498D01*
X92570Y1284365D01*
X93037Y1284031D01*
X93170Y1283631D01*
X93103Y1283231D01*
X92837Y1282898D01*
X91503Y1282231D01*
X90903Y1281765D01*
X90503Y1281098D01*
X90370Y1280498D01*
X93170D01*
G01X95103Y1283831D02*
X95503Y1284231D01*
X95970Y1284431D01*
X96503Y1284498D01*
X97170Y1284365D01*
X97637Y1284031D01*
X97770Y1283631D01*
X97703Y1283231D01*
X97437Y1282898D01*
X96103Y1282231D01*
X95503Y1281765D01*
X95103Y1281098D01*
X94970Y1280498D01*
X97770D01*
G01X54331Y1382677D02*
G03Y1374803I0J-3937D01*
G01Y1382677D02*
G03Y1374803I0J-3937D01*
G01Y1382677D02*
X353740D01*
G01X54331D02*
X353740D01*
G01X114295Y378885D02*
G03X148106I16905J-13531D01*
G01X114295D02*
G03X148106I16905J-13531D01*
G01X114295D02*
G03X121220Y392016I-30737J24602D01*
G01X114295Y378885D02*
G03X121220Y392016I-30737J24602D01*
G01X114295Y831641D02*
G03X121220Y844772I-30737J24601D01*
G01X114295Y831641D02*
G03X121220Y844772I-30737J24602D01*
G01X114295Y831641D02*
G03X148106I16905J-13531D01*
G01X114295D02*
G03X148106I16905J-13531D01*
G01X114295Y1284397D02*
G03X148106I16905J-13531D01*
G01X114295D02*
G03X148106I16905J-13531D01*
G01X114295D02*
G03X121220Y1297528I-30737J24601D01*
G01X114295Y1284397D02*
G03X121220Y1297528I-30737J24602D01*
G01X166335Y376882D02*
Y380882D01*
X167669D01*
X168202Y380682D01*
X168602Y380415D01*
X168935Y380015D01*
X169202Y379549D01*
X169269Y378882D01*
X169202Y378215D01*
X168935Y377749D01*
X168602Y377349D01*
X168202Y377082D01*
X167669Y376882D01*
X166335D01*
G01X171469D02*
Y379549D01*
G01Y379015D02*
X171802Y379282D01*
X172135Y379482D01*
X172602Y379549D01*
X172935Y379482D01*
X173335Y379282D01*
G01X177002Y379549D02*
Y376882D01*
G01Y380615D02*
X176869Y380682D01*
Y380815D01*
X177002Y380882D01*
X177135Y380815D01*
Y380682D01*
X177002Y380615D01*
G01X181602Y376882D02*
Y380882D01*
G01X186202Y376882D02*
Y380882D01*
G01X195002Y376882D02*
Y380282D01*
X195135Y380615D01*
X195402Y380815D01*
X195802Y380882D01*
X196202Y380749D01*
X196402Y380415D01*
G01X195602Y379282D02*
X194269D01*
G01X199002Y378682D02*
X201135D01*
X200935Y379149D01*
X200602Y379415D01*
X200135Y379549D01*
X199669Y379482D01*
X199269Y379282D01*
X199002Y378815D01*
X198869Y378415D01*
Y378015D01*
X199002Y377615D01*
X199335Y377215D01*
X199735Y376949D01*
X200202Y376882D01*
X200669Y377015D01*
X201135Y377415D01*
G01X205802Y376882D02*
Y379549D01*
G01Y379082D02*
X205535Y379349D01*
X205135Y379482D01*
X204669Y379549D01*
X204202Y379415D01*
X203802Y379149D01*
X203535Y378749D01*
X203402Y378215D01*
X203535Y377682D01*
X203802Y377282D01*
X204202Y377015D01*
X204669Y376882D01*
X205135Y376949D01*
X205535Y377149D01*
X205802Y377415D01*
G01X209202Y380882D02*
Y376882D01*
G01X208269Y379549D02*
X210135D01*
G01X212669D02*
Y377682D01*
X212935Y377215D01*
X213335Y376949D01*
X213802Y376882D01*
X214269Y376949D01*
X214669Y377215D01*
X214935Y377682D01*
G01Y376882D02*
Y379549D01*
G01X217469Y376882D02*
Y379549D01*
G01Y379015D02*
X217802Y379282D01*
X218135Y379482D01*
X218602Y379549D01*
X218935Y379482D01*
X219335Y379282D01*
G01X222002Y378682D02*
X224135D01*
X223935Y379149D01*
X223602Y379415D01*
X223135Y379549D01*
X222669Y379482D01*
X222269Y379282D01*
X222002Y378815D01*
X221869Y378415D01*
Y378015D01*
X222002Y377615D01*
X222335Y377215D01*
X222735Y376949D01*
X223202Y376882D01*
X223669Y377015D01*
X224135Y377415D01*
G01X141181Y392016D02*
G03X121220I-9980J-3039D01*
G01X141181D02*
G03X148106Y378885I37662J11471D01*
G01X141181Y392016D02*
G03X121220I-9980J-3039D01*
G01X141181D02*
G03X148106Y378885I37662J11471D01*
G01X166334Y829638D02*
Y833638D01*
X167668D01*
X168201Y833438D01*
X168601Y833171D01*
X168934Y832771D01*
X169201Y832305D01*
X169268Y831638D01*
X169201Y830971D01*
X168934Y830505D01*
X168601Y830105D01*
X168201Y829838D01*
X167668Y829638D01*
X166334D01*
G01X171468D02*
Y832305D01*
G01Y831771D02*
X171801Y832038D01*
X172134Y832238D01*
X172601Y832305D01*
X172934Y832238D01*
X173334Y832038D01*
G01X177001Y832305D02*
Y829638D01*
G01Y833371D02*
X176868Y833438D01*
Y833571D01*
X177001Y833638D01*
X177134Y833571D01*
Y833438D01*
X177001Y833371D01*
G01X181601Y829638D02*
Y833638D01*
G01X186201Y829638D02*
Y833638D01*
G01X195001Y829638D02*
Y833038D01*
X195134Y833371D01*
X195401Y833571D01*
X195801Y833638D01*
X196201Y833505D01*
X196401Y833171D01*
G01X195601Y832038D02*
X194268D01*
G01X199001Y831438D02*
X201134D01*
X200934Y831905D01*
X200601Y832171D01*
X200134Y832305D01*
X199668Y832238D01*
X199268Y832038D01*
X199001Y831571D01*
X198868Y831171D01*
Y830771D01*
X199001Y830371D01*
X199334Y829971D01*
X199734Y829705D01*
X200201Y829638D01*
X200668Y829771D01*
X201134Y830171D01*
G01X205801Y829638D02*
Y832305D01*
G01Y831838D02*
X205534Y832105D01*
X205134Y832238D01*
X204668Y832305D01*
X204201Y832171D01*
X203801Y831905D01*
X203534Y831505D01*
X203401Y830971D01*
X203534Y830438D01*
X203801Y830038D01*
X204201Y829771D01*
X204668Y829638D01*
X205134Y829705D01*
X205534Y829905D01*
X205801Y830171D01*
G01X209201Y833638D02*
Y829638D01*
G01X208268Y832305D02*
X210134D01*
G01X212668D02*
Y830438D01*
X212934Y829971D01*
X213334Y829705D01*
X213801Y829638D01*
X214268Y829705D01*
X214668Y829971D01*
X214934Y830438D01*
G01Y829638D02*
Y832305D01*
G01X217468Y829638D02*
Y832305D01*
G01Y831771D02*
X217801Y832038D01*
X218134Y832238D01*
X218601Y832305D01*
X218934Y832238D01*
X219334Y832038D01*
G01X222001Y831438D02*
X224134D01*
X223934Y831905D01*
X223601Y832171D01*
X223134Y832305D01*
X222668Y832238D01*
X222268Y832038D01*
X222001Y831571D01*
X221868Y831171D01*
Y830771D01*
X222001Y830371D01*
X222334Y829971D01*
X222734Y829705D01*
X223201Y829638D01*
X223668Y829771D01*
X224134Y830171D01*
G01X141181Y844772D02*
G03X148106Y831641I37662J11471D01*
G01X141181Y844772D02*
G03X148106Y831641I37662J11471D01*
G01X141181Y844772D02*
G03X121220I-9980J-3040D01*
G01X141181D02*
G03X121220I-9980J-3039D01*
G01X166335Y1282394D02*
Y1286394D01*
X167669D01*
X168202Y1286194D01*
X168602Y1285927D01*
X168935Y1285527D01*
X169202Y1285061D01*
X169269Y1284394D01*
X169202Y1283727D01*
X168935Y1283261D01*
X168602Y1282861D01*
X168202Y1282594D01*
X167669Y1282394D01*
X166335D01*
G01X171469D02*
Y1285061D01*
G01Y1284527D02*
X171802Y1284794D01*
X172135Y1284994D01*
X172602Y1285061D01*
X172935Y1284994D01*
X173335Y1284794D01*
G01X177002Y1285061D02*
Y1282394D01*
G01Y1286127D02*
X176869Y1286194D01*
Y1286327D01*
X177002Y1286394D01*
X177135Y1286327D01*
Y1286194D01*
X177002Y1286127D01*
G01X181602Y1282394D02*
Y1286394D01*
G01X186202Y1282394D02*
Y1286394D01*
G01X195002Y1282394D02*
Y1285794D01*
X195135Y1286127D01*
X195402Y1286327D01*
X195802Y1286394D01*
X196202Y1286261D01*
X196402Y1285927D01*
G01X195602Y1284794D02*
X194269D01*
G01X199002Y1284194D02*
X201135D01*
X200935Y1284661D01*
X200602Y1284927D01*
X200135Y1285061D01*
X199669Y1284994D01*
X199269Y1284794D01*
X199002Y1284327D01*
X198869Y1283927D01*
Y1283527D01*
X199002Y1283127D01*
X199335Y1282727D01*
X199735Y1282461D01*
X200202Y1282394D01*
X200669Y1282527D01*
X201135Y1282927D01*
G01X205802Y1282394D02*
Y1285061D01*
G01Y1284594D02*
X205535Y1284861D01*
X205135Y1284994D01*
X204669Y1285061D01*
X204202Y1284927D01*
X203802Y1284661D01*
X203535Y1284261D01*
X203402Y1283727D01*
X203535Y1283194D01*
X203802Y1282794D01*
X204202Y1282527D01*
X204669Y1282394D01*
X205135Y1282461D01*
X205535Y1282661D01*
X205802Y1282927D01*
G01X209202Y1286394D02*
Y1282394D01*
G01X208269Y1285061D02*
X210135D01*
G01X212669D02*
Y1283194D01*
X212935Y1282727D01*
X213335Y1282461D01*
X213802Y1282394D01*
X214269Y1282461D01*
X214669Y1282727D01*
X214935Y1283194D01*
G01Y1282394D02*
Y1285061D01*
G01X217469Y1282394D02*
Y1285061D01*
G01Y1284527D02*
X217802Y1284794D01*
X218135Y1284994D01*
X218602Y1285061D01*
X218935Y1284994D01*
X219335Y1284794D01*
G01X222002Y1284194D02*
X224135D01*
X223935Y1284661D01*
X223602Y1284927D01*
X223135Y1285061D01*
X222669Y1284994D01*
X222269Y1284794D01*
X222002Y1284327D01*
X221869Y1283927D01*
Y1283527D01*
X222002Y1283127D01*
X222335Y1282727D01*
X222735Y1282461D01*
X223202Y1282394D01*
X223669Y1282527D01*
X224135Y1282927D01*
G01X141181Y1297528D02*
G03X121220I-9980J-3040D01*
G01X141181D02*
G03X148106Y1284397I37662J11471D01*
G01X141181Y1297528D02*
G03X121220I-9980J-3040D01*
G01X141181D02*
G03X148106Y1284397I37662J11471D01*
G01X172798Y334725D02*
Y338725D01*
X170331Y335858D01*
X173665D01*
G01X175131Y335525D02*
X175531Y335058D01*
X176065Y334792D01*
X176665Y334725D01*
X177198Y334792D01*
X177731Y335125D01*
X178065Y335525D01*
X178131Y335925D01*
X177998Y336392D01*
X177531Y336725D01*
X177065Y336858D01*
X176465D01*
G01X177065D02*
X177465Y337058D01*
X177798Y337392D01*
X177931Y337792D01*
X177798Y338192D01*
X177465Y338525D01*
X176865Y338725D01*
X176265Y338658D01*
X175665Y338392D01*
G01X179731Y335525D02*
X180131Y335058D01*
X180665Y334792D01*
X181265Y334725D01*
X181798Y334792D01*
X182331Y335125D01*
X182665Y335525D01*
X182731Y335925D01*
X182598Y336392D01*
X182131Y336725D01*
X181665Y336858D01*
X181065D01*
G01X181665D02*
X182065Y337058D01*
X182398Y337392D01*
X182531Y337792D01*
X182398Y338192D01*
X182065Y338525D01*
X181465Y338725D01*
X180865Y338658D01*
X180265Y338392D01*
G01X185798Y334592D02*
X185665Y334658D01*
Y334792D01*
X185798Y334858D01*
X185931Y334792D01*
Y334658D01*
X185798Y334592D01*
G01X190398Y338725D02*
X189865Y338592D01*
X189465Y338258D01*
X189198Y337858D01*
X188998Y337325D01*
X188931Y336725D01*
X188998Y336125D01*
X189198Y335592D01*
X189465Y335192D01*
X189865Y334858D01*
X190398Y334725D01*
X190931Y334858D01*
X191331Y335192D01*
X191598Y335592D01*
X191798Y336125D01*
X191865Y336725D01*
X191798Y337325D01*
X191598Y337858D01*
X191331Y338258D01*
X190931Y338592D01*
X190398Y338725D01*
G01X194998Y334725D02*
X195465Y334792D01*
X195998Y334992D01*
X196331Y335325D01*
X196465Y335792D01*
X196331Y336258D01*
X195931Y336658D01*
X195331Y336858D01*
X194665D01*
X194265Y336992D01*
X193931Y337325D01*
X193798Y337792D01*
X193998Y338258D01*
X194465Y338592D01*
X194998Y338725D01*
X195531Y338592D01*
X195998Y338258D01*
X196198Y337792D01*
X196065Y337325D01*
X195731Y336992D01*
X195331Y336858D01*
X194665D01*
X194065Y336658D01*
X193665Y336258D01*
X193531Y335792D01*
X193665Y335325D01*
X193998Y334992D01*
X194531Y334792D01*
X194998Y334725D01*
G01X172890Y419049D02*
X173290Y419449D01*
X173757Y419649D01*
X174290Y419716D01*
X174957Y419583D01*
X175424Y419249D01*
X175557Y418849D01*
X175490Y418449D01*
X175224Y418116D01*
X173890Y417449D01*
X173290Y416983D01*
X172890Y416316D01*
X172757Y415716D01*
X175557D01*
G01X178757Y419716D02*
X178224Y419583D01*
X177824Y419249D01*
X177557Y418849D01*
X177357Y418316D01*
X177290Y417716D01*
X177357Y417116D01*
X177557Y416583D01*
X177824Y416183D01*
X178224Y415849D01*
X178757Y415716D01*
X179290Y415849D01*
X179690Y416183D01*
X179957Y416583D01*
X180157Y417116D01*
X180224Y417716D01*
X180157Y418316D01*
X179957Y418849D01*
X179690Y419249D01*
X179290Y419583D01*
X178757Y419716D01*
G01X183357Y415716D02*
X183824Y415783D01*
X184357Y415983D01*
X184690Y416316D01*
X184824Y416783D01*
X184690Y417249D01*
X184290Y417649D01*
X183690Y417849D01*
X183024D01*
X182624Y417983D01*
X182290Y418316D01*
X182157Y418783D01*
X182357Y419249D01*
X182824Y419583D01*
X183357Y419716D01*
X183890Y419583D01*
X184357Y419249D01*
X184557Y418783D01*
X184424Y418316D01*
X184090Y417983D01*
X183690Y417849D01*
X183024D01*
X182424Y417649D01*
X182024Y417249D01*
X181890Y416783D01*
X182024Y416316D01*
X182357Y415983D01*
X182890Y415783D01*
X183357Y415716D01*
G01X187957Y415583D02*
X187824Y415649D01*
Y415783D01*
X187957Y415849D01*
X188090Y415783D01*
Y415649D01*
X187957Y415583D01*
G01X191290Y417383D02*
X191757Y417849D01*
X192157Y418116D01*
X192690Y418249D01*
X193157Y418116D01*
X193490Y417849D01*
X193757Y417449D01*
X193824Y416983D01*
X193757Y416583D01*
X193490Y416183D01*
X193090Y415849D01*
X192624Y415716D01*
X192090Y415849D01*
X191624Y416249D01*
X191357Y416849D01*
X191290Y417516D01*
X191424Y418383D01*
X191624Y418849D01*
X191957Y419316D01*
X192424Y419649D01*
X192890Y419716D01*
X193357Y419583D01*
X193690Y419249D01*
G01X195890Y417383D02*
X196357Y417849D01*
X196757Y418116D01*
X197290Y418249D01*
X197757Y418116D01*
X198090Y417849D01*
X198357Y417449D01*
X198424Y416983D01*
X198357Y416583D01*
X198090Y416183D01*
X197690Y415849D01*
X197224Y415716D01*
X196690Y415849D01*
X196224Y416249D01*
X195957Y416849D01*
X195890Y417516D01*
X196024Y418383D01*
X196224Y418849D01*
X196557Y419316D01*
X197024Y419649D01*
X197490Y419716D01*
X197957Y419583D01*
X198290Y419249D01*
G01X172797Y787481D02*
Y791481D01*
X170330Y788614D01*
X173664D01*
G01X175130Y788281D02*
X175530Y787814D01*
X176064Y787548D01*
X176664Y787481D01*
X177197Y787548D01*
X177730Y787881D01*
X178064Y788281D01*
X178130Y788681D01*
X177997Y789148D01*
X177530Y789481D01*
X177064Y789614D01*
X176464D01*
G01X177064D02*
X177464Y789814D01*
X177797Y790148D01*
X177930Y790548D01*
X177797Y790948D01*
X177464Y791281D01*
X176864Y791481D01*
X176264Y791414D01*
X175664Y791148D01*
G01X179730Y788281D02*
X180130Y787814D01*
X180664Y787548D01*
X181264Y787481D01*
X181797Y787548D01*
X182330Y787881D01*
X182664Y788281D01*
X182730Y788681D01*
X182597Y789148D01*
X182130Y789481D01*
X181664Y789614D01*
X181064D01*
G01X181664D02*
X182064Y789814D01*
X182397Y790148D01*
X182530Y790548D01*
X182397Y790948D01*
X182064Y791281D01*
X181464Y791481D01*
X180864Y791414D01*
X180264Y791148D01*
G01X185797Y787348D02*
X185664Y787414D01*
Y787548D01*
X185797Y787614D01*
X185930Y787548D01*
Y787414D01*
X185797Y787348D01*
G01X190397Y791481D02*
X189864Y791348D01*
X189464Y791014D01*
X189197Y790614D01*
X188997Y790081D01*
X188930Y789481D01*
X188997Y788881D01*
X189197Y788348D01*
X189464Y787948D01*
X189864Y787614D01*
X190397Y787481D01*
X190930Y787614D01*
X191330Y787948D01*
X191597Y788348D01*
X191797Y788881D01*
X191864Y789481D01*
X191797Y790081D01*
X191597Y790614D01*
X191330Y791014D01*
X190930Y791348D01*
X190397Y791481D01*
G01X194997Y787481D02*
X195464Y787548D01*
X195997Y787748D01*
X196330Y788081D01*
X196464Y788548D01*
X196330Y789014D01*
X195930Y789414D01*
X195330Y789614D01*
X194664D01*
X194264Y789748D01*
X193930Y790081D01*
X193797Y790548D01*
X193997Y791014D01*
X194464Y791348D01*
X194997Y791481D01*
X195530Y791348D01*
X195997Y791014D01*
X196197Y790548D01*
X196064Y790081D01*
X195730Y789748D01*
X195330Y789614D01*
X194664D01*
X194064Y789414D01*
X193664Y789014D01*
X193530Y788548D01*
X193664Y788081D01*
X193997Y787748D01*
X194530Y787548D01*
X194997Y787481D01*
G01X172889Y871805D02*
X173289Y872205D01*
X173756Y872405D01*
X174289Y872472D01*
X174956Y872339D01*
X175423Y872005D01*
X175556Y871605D01*
X175489Y871205D01*
X175223Y870872D01*
X173889Y870205D01*
X173289Y869739D01*
X172889Y869072D01*
X172756Y868472D01*
X175556D01*
G01X178756Y872472D02*
X178223Y872339D01*
X177823Y872005D01*
X177556Y871605D01*
X177356Y871072D01*
X177289Y870472D01*
X177356Y869872D01*
X177556Y869339D01*
X177823Y868939D01*
X178223Y868605D01*
X178756Y868472D01*
X179289Y868605D01*
X179689Y868939D01*
X179956Y869339D01*
X180156Y869872D01*
X180223Y870472D01*
X180156Y871072D01*
X179956Y871605D01*
X179689Y872005D01*
X179289Y872339D01*
X178756Y872472D01*
G01X183356Y868472D02*
X183823Y868539D01*
X184356Y868739D01*
X184689Y869072D01*
X184823Y869539D01*
X184689Y870005D01*
X184289Y870405D01*
X183689Y870605D01*
X183023D01*
X182623Y870739D01*
X182289Y871072D01*
X182156Y871539D01*
X182356Y872005D01*
X182823Y872339D01*
X183356Y872472D01*
X183889Y872339D01*
X184356Y872005D01*
X184556Y871539D01*
X184423Y871072D01*
X184089Y870739D01*
X183689Y870605D01*
X183023D01*
X182423Y870405D01*
X182023Y870005D01*
X181889Y869539D01*
X182023Y869072D01*
X182356Y868739D01*
X182889Y868539D01*
X183356Y868472D01*
G01X187956Y868339D02*
X187823Y868405D01*
Y868539D01*
X187956Y868605D01*
X188089Y868539D01*
Y868405D01*
X187956Y868339D01*
G01X191289Y870139D02*
X191756Y870605D01*
X192156Y870872D01*
X192689Y871005D01*
X193156Y870872D01*
X193489Y870605D01*
X193756Y870205D01*
X193823Y869739D01*
X193756Y869339D01*
X193489Y868939D01*
X193089Y868605D01*
X192623Y868472D01*
X192089Y868605D01*
X191623Y869005D01*
X191356Y869605D01*
X191289Y870272D01*
X191423Y871139D01*
X191623Y871605D01*
X191956Y872072D01*
X192423Y872405D01*
X192889Y872472D01*
X193356Y872339D01*
X193689Y872005D01*
G01X195889Y870139D02*
X196356Y870605D01*
X196756Y870872D01*
X197289Y871005D01*
X197756Y870872D01*
X198089Y870605D01*
X198356Y870205D01*
X198423Y869739D01*
X198356Y869339D01*
X198089Y868939D01*
X197689Y868605D01*
X197223Y868472D01*
X196689Y868605D01*
X196223Y869005D01*
X195956Y869605D01*
X195889Y870272D01*
X196023Y871139D01*
X196223Y871605D01*
X196556Y872072D01*
X197023Y872405D01*
X197489Y872472D01*
X197956Y872339D01*
X198289Y872005D01*
G01X172798Y1240237D02*
Y1244237D01*
X170331Y1241370D01*
X173665D01*
G01X175131Y1241037D02*
X175531Y1240570D01*
X176065Y1240304D01*
X176665Y1240237D01*
X177198Y1240304D01*
X177731Y1240637D01*
X178065Y1241037D01*
X178131Y1241437D01*
X177998Y1241904D01*
X177531Y1242237D01*
X177065Y1242370D01*
X176465D01*
G01X177065D02*
X177465Y1242570D01*
X177798Y1242904D01*
X177931Y1243304D01*
X177798Y1243704D01*
X177465Y1244037D01*
X176865Y1244237D01*
X176265Y1244170D01*
X175665Y1243904D01*
G01X179731Y1241037D02*
X180131Y1240570D01*
X180665Y1240304D01*
X181265Y1240237D01*
X181798Y1240304D01*
X182331Y1240637D01*
X182665Y1241037D01*
X182731Y1241437D01*
X182598Y1241904D01*
X182131Y1242237D01*
X181665Y1242370D01*
X181065D01*
G01X181665D02*
X182065Y1242570D01*
X182398Y1242904D01*
X182531Y1243304D01*
X182398Y1243704D01*
X182065Y1244037D01*
X181465Y1244237D01*
X180865Y1244170D01*
X180265Y1243904D01*
G01X185798Y1240104D02*
X185665Y1240170D01*
Y1240304D01*
X185798Y1240370D01*
X185931Y1240304D01*
Y1240170D01*
X185798Y1240104D01*
G01X190398Y1244237D02*
X189865Y1244104D01*
X189465Y1243770D01*
X189198Y1243370D01*
X188998Y1242837D01*
X188931Y1242237D01*
X188998Y1241637D01*
X189198Y1241104D01*
X189465Y1240704D01*
X189865Y1240370D01*
X190398Y1240237D01*
X190931Y1240370D01*
X191331Y1240704D01*
X191598Y1241104D01*
X191798Y1241637D01*
X191865Y1242237D01*
X191798Y1242837D01*
X191598Y1243370D01*
X191331Y1243770D01*
X190931Y1244104D01*
X190398Y1244237D01*
G01X194998Y1240237D02*
X195465Y1240304D01*
X195998Y1240504D01*
X196331Y1240837D01*
X196465Y1241304D01*
X196331Y1241770D01*
X195931Y1242170D01*
X195331Y1242370D01*
X194665D01*
X194265Y1242504D01*
X193931Y1242837D01*
X193798Y1243304D01*
X193998Y1243770D01*
X194465Y1244104D01*
X194998Y1244237D01*
X195531Y1244104D01*
X195998Y1243770D01*
X196198Y1243304D01*
X196065Y1242837D01*
X195731Y1242504D01*
X195331Y1242370D01*
X194665D01*
X194065Y1242170D01*
X193665Y1241770D01*
X193531Y1241304D01*
X193665Y1240837D01*
X193998Y1240504D01*
X194531Y1240304D01*
X194998Y1240237D01*
G01X172890Y1324561D02*
X173290Y1324961D01*
X173757Y1325161D01*
X174290Y1325228D01*
X174957Y1325095D01*
X175424Y1324761D01*
X175557Y1324361D01*
X175490Y1323961D01*
X175224Y1323628D01*
X173890Y1322961D01*
X173290Y1322495D01*
X172890Y1321828D01*
X172757Y1321228D01*
X175557D01*
G01X178757Y1325228D02*
X178224Y1325095D01*
X177824Y1324761D01*
X177557Y1324361D01*
X177357Y1323828D01*
X177290Y1323228D01*
X177357Y1322628D01*
X177557Y1322095D01*
X177824Y1321695D01*
X178224Y1321361D01*
X178757Y1321228D01*
X179290Y1321361D01*
X179690Y1321695D01*
X179957Y1322095D01*
X180157Y1322628D01*
X180224Y1323228D01*
X180157Y1323828D01*
X179957Y1324361D01*
X179690Y1324761D01*
X179290Y1325095D01*
X178757Y1325228D01*
G01X183357Y1321228D02*
X183824Y1321295D01*
X184357Y1321495D01*
X184690Y1321828D01*
X184824Y1322295D01*
X184690Y1322761D01*
X184290Y1323161D01*
X183690Y1323361D01*
X183024D01*
X182624Y1323495D01*
X182290Y1323828D01*
X182157Y1324295D01*
X182357Y1324761D01*
X182824Y1325095D01*
X183357Y1325228D01*
X183890Y1325095D01*
X184357Y1324761D01*
X184557Y1324295D01*
X184424Y1323828D01*
X184090Y1323495D01*
X183690Y1323361D01*
X183024D01*
X182424Y1323161D01*
X182024Y1322761D01*
X181890Y1322295D01*
X182024Y1321828D01*
X182357Y1321495D01*
X182890Y1321295D01*
X183357Y1321228D01*
G01X187957Y1321095D02*
X187824Y1321161D01*
Y1321295D01*
X187957Y1321361D01*
X188090Y1321295D01*
Y1321161D01*
X187957Y1321095D01*
G01X191290Y1322895D02*
X191757Y1323361D01*
X192157Y1323628D01*
X192690Y1323761D01*
X193157Y1323628D01*
X193490Y1323361D01*
X193757Y1322961D01*
X193824Y1322495D01*
X193757Y1322095D01*
X193490Y1321695D01*
X193090Y1321361D01*
X192624Y1321228D01*
X192090Y1321361D01*
X191624Y1321761D01*
X191357Y1322361D01*
X191290Y1323028D01*
X191424Y1323895D01*
X191624Y1324361D01*
X191957Y1324828D01*
X192424Y1325161D01*
X192890Y1325228D01*
X193357Y1325095D01*
X193690Y1324761D01*
G01X195890Y1322895D02*
X196357Y1323361D01*
X196757Y1323628D01*
X197290Y1323761D01*
X197757Y1323628D01*
X198090Y1323361D01*
X198357Y1322961D01*
X198424Y1322495D01*
X198357Y1322095D01*
X198090Y1321695D01*
X197690Y1321361D01*
X197224Y1321228D01*
X196690Y1321361D01*
X196224Y1321761D01*
X195957Y1322361D01*
X195890Y1323028D01*
X196024Y1323895D01*
X196224Y1324361D01*
X196557Y1324828D01*
X197024Y1325161D01*
X197490Y1325228D01*
X197957Y1325095D01*
X198290Y1324761D01*
G01X302795Y367773D02*
X303195Y367440D01*
X303662Y367240D01*
X304262Y367173D01*
X304862Y367306D01*
X305329Y367573D01*
X305662Y368040D01*
X305729Y368573D01*
X305595Y369106D01*
X305262Y369440D01*
X304795Y369706D01*
X304329Y369773D01*
X303862Y369706D01*
X303262Y369440D01*
X303462Y371173D01*
X305262D01*
G01X307395Y367773D02*
X307795Y367440D01*
X308262Y367240D01*
X308862Y367173D01*
X309462Y367306D01*
X309929Y367573D01*
X310262Y368040D01*
X310329Y368573D01*
X310195Y369106D01*
X309862Y369440D01*
X309395Y369706D01*
X308929Y369773D01*
X308462Y369706D01*
X307862Y369440D01*
X308062Y371173D01*
X309862D01*
G01X313329Y367173D02*
X313462Y368040D01*
X313662Y368773D01*
X313929Y369440D01*
X314262Y370173D01*
X314795Y371173D01*
X312129D01*
G01X318062Y367040D02*
X317929Y367106D01*
Y367240D01*
X318062Y367306D01*
X318195Y367240D01*
Y367106D01*
X318062Y367040D01*
G01X322662Y371173D02*
X322129Y371040D01*
X321729Y370706D01*
X321462Y370306D01*
X321262Y369773D01*
X321195Y369173D01*
X321262Y368573D01*
X321462Y368040D01*
X321729Y367640D01*
X322129Y367306D01*
X322662Y367173D01*
X323195Y367306D01*
X323595Y367640D01*
X323862Y368040D01*
X324062Y368573D01*
X324129Y369173D01*
X324062Y369773D01*
X323862Y370306D01*
X323595Y370706D01*
X323195Y371040D01*
X322662Y371173D01*
G01X326129Y367640D02*
X326595Y367306D01*
X327129Y367173D01*
X327662Y367306D01*
X328129Y367706D01*
X328462Y368306D01*
X328595Y368906D01*
Y369640D01*
X328462Y370240D01*
X328129Y370773D01*
X327729Y371040D01*
X327262Y371173D01*
X326729Y371040D01*
X326329Y370773D01*
X326062Y370373D01*
X325929Y369840D01*
X326062Y369373D01*
X326395Y368906D01*
X326795Y368640D01*
X327262Y368573D01*
X327795Y368706D01*
X328195Y369040D01*
X328595Y369640D01*
G01X302795Y820529D02*
X303195Y820196D01*
X303662Y819996D01*
X304262Y819929D01*
X304862Y820062D01*
X305329Y820329D01*
X305662Y820796D01*
X305729Y821329D01*
X305595Y821862D01*
X305262Y822196D01*
X304795Y822462D01*
X304329Y822529D01*
X303862Y822462D01*
X303262Y822196D01*
X303462Y823929D01*
X305262D01*
G01X307395Y820529D02*
X307795Y820196D01*
X308262Y819996D01*
X308862Y819929D01*
X309462Y820062D01*
X309929Y820329D01*
X310262Y820796D01*
X310329Y821329D01*
X310195Y821862D01*
X309862Y822196D01*
X309395Y822462D01*
X308929Y822529D01*
X308462Y822462D01*
X307862Y822196D01*
X308062Y823929D01*
X309862D01*
G01X313329Y819929D02*
X313462Y820796D01*
X313662Y821529D01*
X313929Y822196D01*
X314262Y822929D01*
X314795Y823929D01*
X312129D01*
G01X318062Y819796D02*
X317929Y819862D01*
Y819996D01*
X318062Y820062D01*
X318195Y819996D01*
Y819862D01*
X318062Y819796D01*
G01X322662Y823929D02*
X322129Y823796D01*
X321729Y823462D01*
X321462Y823062D01*
X321262Y822529D01*
X321195Y821929D01*
X321262Y821329D01*
X321462Y820796D01*
X321729Y820396D01*
X322129Y820062D01*
X322662Y819929D01*
X323195Y820062D01*
X323595Y820396D01*
X323862Y820796D01*
X324062Y821329D01*
X324129Y821929D01*
X324062Y822529D01*
X323862Y823062D01*
X323595Y823462D01*
X323195Y823796D01*
X322662Y823929D01*
G01X326129Y820396D02*
X326595Y820062D01*
X327129Y819929D01*
X327662Y820062D01*
X328129Y820462D01*
X328462Y821062D01*
X328595Y821662D01*
Y822396D01*
X328462Y822996D01*
X328129Y823529D01*
X327729Y823796D01*
X327262Y823929D01*
X326729Y823796D01*
X326329Y823529D01*
X326062Y823129D01*
X325929Y822596D01*
X326062Y822129D01*
X326395Y821662D01*
X326795Y821396D01*
X327262Y821329D01*
X327795Y821462D01*
X328195Y821796D01*
X328595Y822396D01*
G01X302795Y1273285D02*
X303195Y1272952D01*
X303662Y1272752D01*
X304262Y1272685D01*
X304862Y1272818D01*
X305329Y1273085D01*
X305662Y1273552D01*
X305729Y1274085D01*
X305595Y1274618D01*
X305262Y1274952D01*
X304795Y1275218D01*
X304329Y1275285D01*
X303862Y1275218D01*
X303262Y1274952D01*
X303462Y1276685D01*
X305262D01*
G01X307395Y1273285D02*
X307795Y1272952D01*
X308262Y1272752D01*
X308862Y1272685D01*
X309462Y1272818D01*
X309929Y1273085D01*
X310262Y1273552D01*
X310329Y1274085D01*
X310195Y1274618D01*
X309862Y1274952D01*
X309395Y1275218D01*
X308929Y1275285D01*
X308462Y1275218D01*
X307862Y1274952D01*
X308062Y1276685D01*
X309862D01*
G01X313329Y1272685D02*
X313462Y1273552D01*
X313662Y1274285D01*
X313929Y1274952D01*
X314262Y1275685D01*
X314795Y1276685D01*
X312129D01*
G01X318062Y1272552D02*
X317929Y1272618D01*
Y1272752D01*
X318062Y1272818D01*
X318195Y1272752D01*
Y1272618D01*
X318062Y1272552D01*
G01X322662Y1276685D02*
X322129Y1276552D01*
X321729Y1276218D01*
X321462Y1275818D01*
X321262Y1275285D01*
X321195Y1274685D01*
X321262Y1274085D01*
X321462Y1273552D01*
X321729Y1273152D01*
X322129Y1272818D01*
X322662Y1272685D01*
X323195Y1272818D01*
X323595Y1273152D01*
X323862Y1273552D01*
X324062Y1274085D01*
X324129Y1274685D01*
X324062Y1275285D01*
X323862Y1275818D01*
X323595Y1276218D01*
X323195Y1276552D01*
X322662Y1276685D01*
G01X326129Y1273152D02*
X326595Y1272818D01*
X327129Y1272685D01*
X327662Y1272818D01*
X328129Y1273218D01*
X328462Y1273818D01*
X328595Y1274418D01*
Y1275152D01*
X328462Y1275752D01*
X328129Y1276285D01*
X327729Y1276552D01*
X327262Y1276685D01*
X326729Y1276552D01*
X326329Y1276285D01*
X326062Y1275885D01*
X325929Y1275352D01*
X326062Y1274885D01*
X326395Y1274418D01*
X326795Y1274152D01*
X327262Y1274085D01*
X327795Y1274218D01*
X328195Y1274552D01*
X328595Y1275152D01*
G01X323228Y-7874D02*
G03Y0I0J3937D01*
G01Y-7874D02*
G03Y0I0J3937D01*
G01X362598D02*
G03Y-7874I0J-3937D01*
G01Y0D02*
G03Y-7874I0J-3937D01*
G01X362327Y378885D02*
G03X396138I16905J-13531D01*
G01X362327D02*
G03X396138I16905J-13531D01*
G01X320134Y378319D02*
X320534Y378719D01*
X321001Y378919D01*
X321534Y378986D01*
X322201Y378853D01*
X322668Y378519D01*
X322801Y378119D01*
X322734Y377719D01*
X322468Y377386D01*
X321134Y376719D01*
X320534Y376253D01*
X320134Y375586D01*
X320001Y374986D01*
X322801D01*
G01X324534Y375786D02*
X324934Y375319D01*
X325468Y375053D01*
X326068Y374986D01*
X326601Y375053D01*
X327134Y375386D01*
X327468Y375786D01*
X327534Y376186D01*
X327401Y376653D01*
X326934Y376986D01*
X326468Y377119D01*
X325868D01*
G01X326468D02*
X326868Y377319D01*
X327201Y377653D01*
X327334Y378053D01*
X327201Y378453D01*
X326868Y378786D01*
X326268Y378986D01*
X325668Y378919D01*
X325068Y378653D01*
G01X329334Y376653D02*
X329801Y377119D01*
X330201Y377386D01*
X330734Y377519D01*
X331201Y377386D01*
X331534Y377119D01*
X331801Y376719D01*
X331868Y376253D01*
X331801Y375853D01*
X331534Y375453D01*
X331134Y375119D01*
X330668Y374986D01*
X330134Y375119D01*
X329668Y375519D01*
X329401Y376119D01*
X329334Y376786D01*
X329468Y377653D01*
X329668Y378119D01*
X330001Y378586D01*
X330468Y378919D01*
X330934Y378986D01*
X331401Y378853D01*
X331734Y378519D01*
G01X335201Y374853D02*
X335068Y374919D01*
Y375053D01*
X335201Y375119D01*
X335334Y375053D01*
Y374919D01*
X335201Y374853D01*
G01X338534Y378319D02*
X338934Y378719D01*
X339401Y378919D01*
X339934Y378986D01*
X340601Y378853D01*
X341068Y378519D01*
X341201Y378119D01*
X341134Y377719D01*
X340868Y377386D01*
X339534Y376719D01*
X338934Y376253D01*
X338534Y375586D01*
X338401Y374986D01*
X341201D01*
G01X343134Y378319D02*
X343534Y378719D01*
X344001Y378919D01*
X344534Y378986D01*
X345201Y378853D01*
X345668Y378519D01*
X345801Y378119D01*
X345734Y377719D01*
X345468Y377386D01*
X344134Y376719D01*
X343534Y376253D01*
X343134Y375586D01*
X343001Y374986D01*
X345801D01*
G01X362327Y378885D02*
G03X369252Y392016I-30737J24602D01*
G01X362327Y378885D02*
G03X369252Y392016I-30737J24602D01*
G01X320134Y831075D02*
X320534Y831475D01*
X321001Y831675D01*
X321534Y831742D01*
X322201Y831609D01*
X322668Y831275D01*
X322801Y830875D01*
X322734Y830475D01*
X322468Y830142D01*
X321134Y829475D01*
X320534Y829009D01*
X320134Y828342D01*
X320001Y827742D01*
X322801D01*
G01X324534Y828542D02*
X324934Y828075D01*
X325468Y827809D01*
X326068Y827742D01*
X326601Y827809D01*
X327134Y828142D01*
X327468Y828542D01*
X327534Y828942D01*
X327401Y829409D01*
X326934Y829742D01*
X326468Y829875D01*
X325868D01*
G01X326468D02*
X326868Y830075D01*
X327201Y830409D01*
X327334Y830809D01*
X327201Y831209D01*
X326868Y831542D01*
X326268Y831742D01*
X325668Y831675D01*
X325068Y831409D01*
G01X329334Y829409D02*
X329801Y829875D01*
X330201Y830142D01*
X330734Y830275D01*
X331201Y830142D01*
X331534Y829875D01*
X331801Y829475D01*
X331868Y829009D01*
X331801Y828609D01*
X331534Y828209D01*
X331134Y827875D01*
X330668Y827742D01*
X330134Y827875D01*
X329668Y828275D01*
X329401Y828875D01*
X329334Y829542D01*
X329468Y830409D01*
X329668Y830875D01*
X330001Y831342D01*
X330468Y831675D01*
X330934Y831742D01*
X331401Y831609D01*
X331734Y831275D01*
G01X335201Y827609D02*
X335068Y827675D01*
Y827809D01*
X335201Y827875D01*
X335334Y827809D01*
Y827675D01*
X335201Y827609D01*
G01X338534Y831075D02*
X338934Y831475D01*
X339401Y831675D01*
X339934Y831742D01*
X340601Y831609D01*
X341068Y831275D01*
X341201Y830875D01*
X341134Y830475D01*
X340868Y830142D01*
X339534Y829475D01*
X338934Y829009D01*
X338534Y828342D01*
X338401Y827742D01*
X341201D01*
G01X343134Y831075D02*
X343534Y831475D01*
X344001Y831675D01*
X344534Y831742D01*
X345201Y831609D01*
X345668Y831275D01*
X345801Y830875D01*
X345734Y830475D01*
X345468Y830142D01*
X344134Y829475D01*
X343534Y829009D01*
X343134Y828342D01*
X343001Y827742D01*
X345801D01*
G01X362327Y831641D02*
G03X369252Y844772I-30737J24602D01*
G01X362327Y831641D02*
G03X369252Y844772I-30737J24602D01*
G01X362327Y831641D02*
G03X396138I16905J-13531D01*
G01X362327D02*
G03X396138I16905J-13531D01*
G01X362327Y1284397D02*
G03X396138I16905J-13531D01*
G01X362327D02*
G03X396138I16905J-13531D01*
G01X320134Y1283831D02*
X320534Y1284231D01*
X321001Y1284431D01*
X321534Y1284498D01*
X322201Y1284365D01*
X322668Y1284031D01*
X322801Y1283631D01*
X322734Y1283231D01*
X322468Y1282898D01*
X321134Y1282231D01*
X320534Y1281765D01*
X320134Y1281098D01*
X320001Y1280498D01*
X322801D01*
G01X324534Y1281298D02*
X324934Y1280831D01*
X325468Y1280565D01*
X326068Y1280498D01*
X326601Y1280565D01*
X327134Y1280898D01*
X327468Y1281298D01*
X327534Y1281698D01*
X327401Y1282165D01*
X326934Y1282498D01*
X326468Y1282631D01*
X325868D01*
G01X326468D02*
X326868Y1282831D01*
X327201Y1283165D01*
X327334Y1283565D01*
X327201Y1283965D01*
X326868Y1284298D01*
X326268Y1284498D01*
X325668Y1284431D01*
X325068Y1284165D01*
G01X329334Y1282165D02*
X329801Y1282631D01*
X330201Y1282898D01*
X330734Y1283031D01*
X331201Y1282898D01*
X331534Y1282631D01*
X331801Y1282231D01*
X331868Y1281765D01*
X331801Y1281365D01*
X331534Y1280965D01*
X331134Y1280631D01*
X330668Y1280498D01*
X330134Y1280631D01*
X329668Y1281031D01*
X329401Y1281631D01*
X329334Y1282298D01*
X329468Y1283165D01*
X329668Y1283631D01*
X330001Y1284098D01*
X330468Y1284431D01*
X330934Y1284498D01*
X331401Y1284365D01*
X331734Y1284031D01*
G01X335201Y1280365D02*
X335068Y1280431D01*
Y1280565D01*
X335201Y1280631D01*
X335334Y1280565D01*
Y1280431D01*
X335201Y1280365D01*
G01X338534Y1283831D02*
X338934Y1284231D01*
X339401Y1284431D01*
X339934Y1284498D01*
X340601Y1284365D01*
X341068Y1284031D01*
X341201Y1283631D01*
X341134Y1283231D01*
X340868Y1282898D01*
X339534Y1282231D01*
X338934Y1281765D01*
X338534Y1281098D01*
X338401Y1280498D01*
X341201D01*
G01X343134Y1283831D02*
X343534Y1284231D01*
X344001Y1284431D01*
X344534Y1284498D01*
X345201Y1284365D01*
X345668Y1284031D01*
X345801Y1283631D01*
X345734Y1283231D01*
X345468Y1282898D01*
X344134Y1282231D01*
X343534Y1281765D01*
X343134Y1281098D01*
X343001Y1280498D01*
X345801D01*
G01X362327Y1284397D02*
G03X369252Y1297528I-30737J24602D01*
G01X362327Y1284397D02*
G03X369252Y1297528I-30737J24602D01*
G01X353740Y1374803D02*
G03Y1382677I0J3937D01*
G01Y1374803D02*
G03Y1382677I0J3937D01*
G01X401575Y3937D02*
Y55118D01*
G01X397638Y0D02*
G03X401575Y3937I0J3937D01*
G01X409449D02*
Y51181D01*
G01X397638Y-7874D02*
G03X409449Y3937I0J11811D01*
G01X397638Y0D02*
G03X401575Y3937I0J3937D01*
G01D02*
Y55118D01*
G01X409449Y3937D02*
Y51181D01*
G01X397638Y-7874D02*
G03X409449Y3937I0J11811D01*
G01X362598Y-7874D02*
X397638D01*
G01X362598D02*
X397638D01*
G01X392737Y43276D02*
Y39276D01*
X394337D01*
X394870Y39476D01*
X395270Y39943D01*
X395403Y40476D01*
X395270Y41009D01*
X394937Y41409D01*
X394337Y41609D01*
X392737D01*
G01X397737Y43276D02*
Y40609D01*
G01Y41143D02*
X398070Y40876D01*
X398403Y40676D01*
X398870Y40609D01*
X399203Y40676D01*
X399603Y40876D01*
G01X402270Y41476D02*
X404403D01*
X404203Y41009D01*
X403870Y40743D01*
X403403Y40609D01*
X402937Y40676D01*
X402537Y40876D01*
X402270Y41343D01*
X402137Y41743D01*
Y42143D01*
X402270Y42543D01*
X402603Y42943D01*
X403003Y43209D01*
X403470Y43276D01*
X403937Y43143D01*
X404403Y42743D01*
G01X406870Y42809D02*
X407203Y43076D01*
X407670Y43276D01*
X408070D01*
X408470Y43143D01*
X408737Y42943D01*
X408870Y42676D01*
X408803Y42276D01*
X408537Y42076D01*
X407337Y41676D01*
X407070Y41209D01*
X407203Y40876D01*
X407470Y40676D01*
X407870Y40609D01*
X408270Y40676D01*
X408670Y40876D01*
G01X411470Y42809D02*
X411803Y43076D01*
X412270Y43276D01*
X412670D01*
X413070Y43143D01*
X413337Y42943D01*
X413470Y42676D01*
X413403Y42276D01*
X413137Y42076D01*
X411937Y41676D01*
X411670Y41209D01*
X411803Y40876D01*
X412070Y40676D01*
X412470Y40609D01*
X412870Y40676D01*
X413270Y40876D01*
G01X416203Y41943D02*
X417937D01*
G01X421270Y43276D02*
Y39876D01*
X421403Y39543D01*
X421670Y39343D01*
X422070Y39276D01*
X422470Y39409D01*
X422670Y39743D01*
G01X421870Y40876D02*
X420537D01*
G01X426270Y40609D02*
Y43276D01*
G01Y39543D02*
X426137Y39476D01*
Y39343D01*
X426270Y39276D01*
X426403Y39343D01*
Y39476D01*
X426270Y39543D01*
G01X430870Y39276D02*
Y43276D01*
G01X429937Y40609D02*
X431803D01*
G01X438737Y43276D02*
Y39276D01*
X440337D01*
X440870Y39476D01*
X441270Y39943D01*
X441403Y40476D01*
X441270Y41009D01*
X440937Y41409D01*
X440337Y41609D01*
X438737D01*
G01X444670Y39276D02*
Y43276D01*
G01X443137Y39276D02*
X446203D01*
G01X447870Y43276D02*
Y39276D01*
G01X450670D02*
Y43276D01*
G01Y41276D02*
X447870D01*
G01X457337Y43276D02*
Y39276D01*
G01X459470Y40609D02*
X457337Y42143D01*
G01X458203Y41543D02*
X459603Y43276D01*
G01X462070Y41476D02*
X464203D01*
X464003Y41009D01*
X463670Y40743D01*
X463203Y40609D01*
X462737Y40676D01*
X462337Y40876D01*
X462070Y41343D01*
X461937Y41743D01*
Y42143D01*
X462070Y42543D01*
X462403Y42943D01*
X462803Y43209D01*
X463270Y43276D01*
X463737Y43143D01*
X464203Y42743D01*
G01X466670Y41476D02*
X468803D01*
X468603Y41009D01*
X468270Y40743D01*
X467803Y40609D01*
X467337Y40676D01*
X466937Y40876D01*
X466670Y41343D01*
X466537Y41743D01*
Y42143D01*
X466670Y42543D01*
X467003Y42943D01*
X467403Y43209D01*
X467870Y43276D01*
X468337Y43143D01*
X468803Y42743D01*
G01X471070Y44609D02*
Y40609D01*
G01Y41209D02*
X471403Y40876D01*
X471737Y40676D01*
X472270Y40609D01*
X472737Y40676D01*
X473203Y41009D01*
X473403Y41476D01*
X473470Y41943D01*
X473403Y42409D01*
X473203Y42876D01*
X472803Y43143D01*
X472270Y43276D01*
X471803Y43209D01*
X471337Y43009D01*
X471070Y42743D01*
G01X480337Y43276D02*
Y39276D01*
G01Y41209D02*
X480670Y40876D01*
X481003Y40676D01*
X481537Y40609D01*
X481937Y40676D01*
X482403Y40943D01*
X482603Y41343D01*
Y43276D01*
G01X486070D02*
X485670Y43209D01*
X485270Y42943D01*
X485003Y42476D01*
X484870Y41943D01*
X485003Y41409D01*
X485270Y40943D01*
X485670Y40676D01*
X486070Y40609D01*
X486470Y40676D01*
X486870Y40943D01*
X487137Y41409D01*
X487203Y41943D01*
X487137Y42476D01*
X486870Y42943D01*
X486470Y43209D01*
X486070Y43276D01*
G01X490670D02*
Y39276D01*
G01X494270Y41476D02*
X496403D01*
X496203Y41009D01*
X495870Y40743D01*
X495403Y40609D01*
X494937Y40676D01*
X494537Y40876D01*
X494270Y41343D01*
X494137Y41743D01*
Y42143D01*
X494270Y42543D01*
X494603Y42943D01*
X495003Y43209D01*
X495470Y43276D01*
X495937Y43143D01*
X496403Y42743D01*
G01X503470Y42809D02*
X503803Y43076D01*
X504270Y43276D01*
X504670D01*
X505070Y43143D01*
X505337Y42943D01*
X505470Y42676D01*
X505403Y42276D01*
X505137Y42076D01*
X503937Y41676D01*
X503670Y41209D01*
X503803Y40876D01*
X504070Y40676D01*
X504470Y40609D01*
X504870Y40676D01*
X505270Y40876D01*
G01X509070Y40609D02*
Y43276D01*
G01Y39543D02*
X508937Y39476D01*
Y39343D01*
X509070Y39276D01*
X509203Y39343D01*
Y39476D01*
X509070Y39543D01*
G01X512670Y40609D02*
X514670D01*
X512670Y43276D01*
X514670D01*
G01X517270Y41476D02*
X519403D01*
X519203Y41009D01*
X518870Y40743D01*
X518403Y40609D01*
X517937Y40676D01*
X517537Y40876D01*
X517270Y41343D01*
X517137Y41743D01*
Y42143D01*
X517270Y42543D01*
X517603Y42943D01*
X518003Y43209D01*
X518470Y43276D01*
X518937Y43143D01*
X519403Y42743D01*
G01X527470Y39276D02*
Y43276D01*
G01X526537Y40609D02*
X528403D01*
G01X532070Y43276D02*
X531670Y43209D01*
X531270Y42943D01*
X531003Y42476D01*
X530870Y41943D01*
X531003Y41409D01*
X531270Y40943D01*
X531670Y40676D01*
X532070Y40609D01*
X532470Y40676D01*
X532870Y40943D01*
X533137Y41409D01*
X533203Y41943D01*
X533137Y42476D01*
X532870Y42943D01*
X532470Y43209D01*
X532070Y43276D01*
G01X536670D02*
Y39276D01*
G01X540270Y41476D02*
X542403D01*
X542203Y41009D01*
X541870Y40743D01*
X541403Y40609D01*
X540937Y40676D01*
X540537Y40876D01*
X540270Y41343D01*
X540137Y41743D01*
Y42143D01*
X540270Y42543D01*
X540603Y42943D01*
X541003Y43209D01*
X541470Y43276D01*
X541937Y43143D01*
X542403Y42743D01*
G01X544937Y43276D02*
Y40609D01*
G01Y41143D02*
X545270Y40876D01*
X545603Y40676D01*
X546070Y40609D01*
X546403Y40676D01*
X546803Y40876D01*
G01X551670Y43276D02*
Y40609D01*
G01Y41076D02*
X551403Y40809D01*
X551003Y40676D01*
X550537Y40609D01*
X550070Y40743D01*
X549670Y41009D01*
X549403Y41409D01*
X549270Y41943D01*
X549403Y42476D01*
X549670Y42876D01*
X550070Y43143D01*
X550537Y43276D01*
X551003Y43209D01*
X551403Y43009D01*
X551670Y42743D01*
G01X553937Y43276D02*
Y40609D01*
G01Y41276D02*
X554203Y40943D01*
X554603Y40676D01*
X555137Y40609D01*
X555603Y40676D01*
X556003Y40943D01*
X556203Y41409D01*
Y43276D01*
G01X560737Y40943D02*
X560270Y40676D01*
X559870Y40609D01*
X559337Y40743D01*
X558937Y41009D01*
X558670Y41476D01*
X558603Y41943D01*
X558670Y42409D01*
X558937Y42809D01*
X559337Y43143D01*
X559870Y43276D01*
X560337Y43143D01*
X560737Y42876D01*
G01X563270Y41476D02*
X565403D01*
X565203Y41009D01*
X564870Y40743D01*
X564403Y40609D01*
X563937Y40676D01*
X563537Y40876D01*
X563270Y41343D01*
X563137Y41743D01*
Y42143D01*
X563270Y42543D01*
X563603Y42943D01*
X564003Y43209D01*
X564470Y43276D01*
X564937Y43143D01*
X565403Y42743D01*
G01X572737Y41943D02*
X574337D01*
G01X573470Y41076D02*
Y42809D01*
G01X576870Y43409D02*
X579270Y39276D01*
G01X581803Y41943D02*
X583537D01*
G01X586003Y39943D02*
X586403Y39543D01*
X586870Y39343D01*
X587403Y39276D01*
X588070Y39409D01*
X588537Y39743D01*
X588670Y40143D01*
X588603Y40543D01*
X588337Y40876D01*
X587003Y41543D01*
X586403Y42009D01*
X586003Y42676D01*
X585870Y43276D01*
X588670D01*
G01X589870D02*
Y40609D01*
G01Y41343D02*
X590070Y41009D01*
X590403Y40743D01*
X590870Y40609D01*
X591337Y40743D01*
X591670Y41009D01*
X591870Y41343D01*
Y43276D01*
G01Y41343D02*
X592070Y41009D01*
X592403Y40743D01*
X592870Y40609D01*
X593337Y40743D01*
X593670Y41009D01*
X593870Y41409D01*
Y43276D01*
G01X596470Y40609D02*
Y43276D01*
G01Y39543D02*
X596337Y39476D01*
Y39343D01*
X596470Y39276D01*
X596603Y39343D01*
Y39476D01*
X596470Y39543D01*
G01X601070Y43276D02*
Y39276D01*
G01X604670Y42809D02*
X605003Y43076D01*
X605470Y43276D01*
X605870D01*
X606270Y43143D01*
X606537Y42943D01*
X606670Y42676D01*
X606603Y42276D01*
X606337Y42076D01*
X605137Y41676D01*
X604870Y41209D01*
X605003Y40876D01*
X605270Y40676D01*
X605670Y40609D01*
X606070Y40676D01*
X606470Y40876D01*
G01X398370Y59056D02*
X594370D01*
G01X405512Y59055D02*
G03X401575Y55118I0J-3937D01*
G01X405512Y59055D02*
G03X401575Y55118I0J-3937D01*
G01X405512Y59055D02*
X586614D01*
G01X409449Y51181D02*
X582677D01*
G01X405512Y59055D02*
X586614D01*
G01X409449Y51181D02*
X582677D01*
G01X389213Y392016D02*
G03X396138Y378885I37662J11471D01*
G01X389213Y392016D02*
G03X396138Y378885I37662J11471D01*
G01X389213Y392016D02*
G03X369252I-9981J-3039D01*
G01X389213D02*
G03X369252I-9981J-3039D01*
G01X389213Y844772D02*
G03X396138Y831641I37662J11471D01*
G01X389213Y844772D02*
G03X396138Y831641I37662J11471D01*
G01X389213Y844772D02*
G03X369252I-9981J-3040D01*
G01X389213D02*
G03X369252I-9981J-3039D01*
G01X389213Y1297528D02*
G03X396138Y1284397I37662J11471D01*
G01X389213Y1297528D02*
G03X396138Y1284397I37662J11471D01*
G01X389213Y1297528D02*
G03X369252I-9981J-3040D01*
G01X389213D02*
G03X369252I-9981J-3040D01*
G01X393110Y1382677D02*
G03Y1374803I0J-3937D01*
G01Y1382677D02*
X692520D01*
G01X393110D02*
X692520D01*
G01X393110D02*
G03Y1374803I0J-3937D01*
G01X427424Y61677D02*
Y122970D01*
X566670D01*
Y61677D01*
X427424D01*
G01X420829Y334725D02*
Y338725D01*
X418362Y335858D01*
X421696D01*
G01X423162Y335525D02*
X423562Y335058D01*
X424096Y334792D01*
X424696Y334725D01*
X425229Y334792D01*
X425762Y335125D01*
X426096Y335525D01*
X426162Y335925D01*
X426029Y336392D01*
X425562Y336725D01*
X425096Y336858D01*
X424496D01*
G01X425096D02*
X425496Y337058D01*
X425829Y337392D01*
X425962Y337792D01*
X425829Y338192D01*
X425496Y338525D01*
X424896Y338725D01*
X424296Y338658D01*
X423696Y338392D01*
G01X427762Y335525D02*
X428162Y335058D01*
X428696Y334792D01*
X429296Y334725D01*
X429829Y334792D01*
X430362Y335125D01*
X430696Y335525D01*
X430762Y335925D01*
X430629Y336392D01*
X430162Y336725D01*
X429696Y336858D01*
X429096D01*
G01X429696D02*
X430096Y337058D01*
X430429Y337392D01*
X430562Y337792D01*
X430429Y338192D01*
X430096Y338525D01*
X429496Y338725D01*
X428896Y338658D01*
X428296Y338392D01*
G01X433829Y334592D02*
X433696Y334658D01*
Y334792D01*
X433829Y334858D01*
X433962Y334792D01*
Y334658D01*
X433829Y334592D01*
G01X438429Y338725D02*
X437896Y338592D01*
X437496Y338258D01*
X437229Y337858D01*
X437029Y337325D01*
X436962Y336725D01*
X437029Y336125D01*
X437229Y335592D01*
X437496Y335192D01*
X437896Y334858D01*
X438429Y334725D01*
X438962Y334858D01*
X439362Y335192D01*
X439629Y335592D01*
X439829Y336125D01*
X439896Y336725D01*
X439829Y337325D01*
X439629Y337858D01*
X439362Y338258D01*
X438962Y338592D01*
X438429Y338725D01*
G01X443029Y334725D02*
X443496Y334792D01*
X444029Y334992D01*
X444362Y335325D01*
X444496Y335792D01*
X444362Y336258D01*
X443962Y336658D01*
X443362Y336858D01*
X442696D01*
X442296Y336992D01*
X441962Y337325D01*
X441829Y337792D01*
X442029Y338258D01*
X442496Y338592D01*
X443029Y338725D01*
X443562Y338592D01*
X444029Y338258D01*
X444229Y337792D01*
X444096Y337325D01*
X443762Y336992D01*
X443362Y336858D01*
X442696D01*
X442096Y336658D01*
X441696Y336258D01*
X441562Y335792D01*
X441696Y335325D01*
X442029Y334992D01*
X442562Y334792D01*
X443029Y334725D01*
G01X414366Y376882D02*
Y380882D01*
X415700D01*
X416233Y380682D01*
X416633Y380415D01*
X416966Y380015D01*
X417233Y379549D01*
X417300Y378882D01*
X417233Y378215D01*
X416966Y377749D01*
X416633Y377349D01*
X416233Y377082D01*
X415700Y376882D01*
X414366D01*
G01X419500D02*
Y379549D01*
G01Y379015D02*
X419833Y379282D01*
X420166Y379482D01*
X420633Y379549D01*
X420966Y379482D01*
X421366Y379282D01*
G01X425033Y379549D02*
Y376882D01*
G01Y380615D02*
X424900Y380682D01*
Y380815D01*
X425033Y380882D01*
X425166Y380815D01*
Y380682D01*
X425033Y380615D01*
G01X429633Y376882D02*
Y380882D01*
G01X434233Y376882D02*
Y380882D01*
G01X443033Y376882D02*
Y380282D01*
X443166Y380615D01*
X443433Y380815D01*
X443833Y380882D01*
X444233Y380749D01*
X444433Y380415D01*
G01X443633Y379282D02*
X442300D01*
G01X447033Y378682D02*
X449166D01*
X448966Y379149D01*
X448633Y379415D01*
X448166Y379549D01*
X447700Y379482D01*
X447300Y379282D01*
X447033Y378815D01*
X446900Y378415D01*
Y378015D01*
X447033Y377615D01*
X447366Y377215D01*
X447766Y376949D01*
X448233Y376882D01*
X448700Y377015D01*
X449166Y377415D01*
G01X453833Y376882D02*
Y379549D01*
G01Y379082D02*
X453566Y379349D01*
X453166Y379482D01*
X452700Y379549D01*
X452233Y379415D01*
X451833Y379149D01*
X451566Y378749D01*
X451433Y378215D01*
X451566Y377682D01*
X451833Y377282D01*
X452233Y377015D01*
X452700Y376882D01*
X453166Y376949D01*
X453566Y377149D01*
X453833Y377415D01*
G01X457233Y380882D02*
Y376882D01*
G01X456300Y379549D02*
X458166D01*
G01X460700D02*
Y377682D01*
X460966Y377215D01*
X461366Y376949D01*
X461833Y376882D01*
X462300Y376949D01*
X462700Y377215D01*
X462966Y377682D01*
G01Y376882D02*
Y379549D01*
G01X465500Y376882D02*
Y379549D01*
G01Y379015D02*
X465833Y379282D01*
X466166Y379482D01*
X466633Y379549D01*
X466966Y379482D01*
X467366Y379282D01*
G01X470033Y378682D02*
X472166D01*
X471966Y379149D01*
X471633Y379415D01*
X471166Y379549D01*
X470700Y379482D01*
X470300Y379282D01*
X470033Y378815D01*
X469900Y378415D01*
Y378015D01*
X470033Y377615D01*
X470366Y377215D01*
X470766Y376949D01*
X471233Y376882D01*
X471700Y377015D01*
X472166Y377415D01*
G01X420921Y419049D02*
X421321Y419449D01*
X421788Y419649D01*
X422321Y419716D01*
X422988Y419583D01*
X423455Y419249D01*
X423588Y418849D01*
X423521Y418449D01*
X423255Y418116D01*
X421921Y417449D01*
X421321Y416983D01*
X420921Y416316D01*
X420788Y415716D01*
X423588D01*
G01X426788Y419716D02*
X426255Y419583D01*
X425855Y419249D01*
X425588Y418849D01*
X425388Y418316D01*
X425321Y417716D01*
X425388Y417116D01*
X425588Y416583D01*
X425855Y416183D01*
X426255Y415849D01*
X426788Y415716D01*
X427321Y415849D01*
X427721Y416183D01*
X427988Y416583D01*
X428188Y417116D01*
X428255Y417716D01*
X428188Y418316D01*
X427988Y418849D01*
X427721Y419249D01*
X427321Y419583D01*
X426788Y419716D01*
G01X431388Y415716D02*
X431855Y415783D01*
X432388Y415983D01*
X432721Y416316D01*
X432855Y416783D01*
X432721Y417249D01*
X432321Y417649D01*
X431721Y417849D01*
X431055D01*
X430655Y417983D01*
X430321Y418316D01*
X430188Y418783D01*
X430388Y419249D01*
X430855Y419583D01*
X431388Y419716D01*
X431921Y419583D01*
X432388Y419249D01*
X432588Y418783D01*
X432455Y418316D01*
X432121Y417983D01*
X431721Y417849D01*
X431055D01*
X430455Y417649D01*
X430055Y417249D01*
X429921Y416783D01*
X430055Y416316D01*
X430388Y415983D01*
X430921Y415783D01*
X431388Y415716D01*
G01X435988Y415583D02*
X435855Y415649D01*
Y415783D01*
X435988Y415849D01*
X436121Y415783D01*
Y415649D01*
X435988Y415583D01*
G01X439321Y417383D02*
X439788Y417849D01*
X440188Y418116D01*
X440721Y418249D01*
X441188Y418116D01*
X441521Y417849D01*
X441788Y417449D01*
X441855Y416983D01*
X441788Y416583D01*
X441521Y416183D01*
X441121Y415849D01*
X440655Y415716D01*
X440121Y415849D01*
X439655Y416249D01*
X439388Y416849D01*
X439321Y417516D01*
X439455Y418383D01*
X439655Y418849D01*
X439988Y419316D01*
X440455Y419649D01*
X440921Y419716D01*
X441388Y419583D01*
X441721Y419249D01*
G01X443921Y417383D02*
X444388Y417849D01*
X444788Y418116D01*
X445321Y418249D01*
X445788Y418116D01*
X446121Y417849D01*
X446388Y417449D01*
X446455Y416983D01*
X446388Y416583D01*
X446121Y416183D01*
X445721Y415849D01*
X445255Y415716D01*
X444721Y415849D01*
X444255Y416249D01*
X443988Y416849D01*
X443921Y417516D01*
X444055Y418383D01*
X444255Y418849D01*
X444588Y419316D01*
X445055Y419649D01*
X445521Y419716D01*
X445988Y419583D01*
X446321Y419249D01*
G01X420829Y787481D02*
Y791481D01*
X418362Y788614D01*
X421696D01*
G01X423162Y788281D02*
X423562Y787814D01*
X424096Y787548D01*
X424696Y787481D01*
X425229Y787548D01*
X425762Y787881D01*
X426096Y788281D01*
X426162Y788681D01*
X426029Y789148D01*
X425562Y789481D01*
X425096Y789614D01*
X424496D01*
G01X425096D02*
X425496Y789814D01*
X425829Y790148D01*
X425962Y790548D01*
X425829Y790948D01*
X425496Y791281D01*
X424896Y791481D01*
X424296Y791414D01*
X423696Y791148D01*
G01X427762Y788281D02*
X428162Y787814D01*
X428696Y787548D01*
X429296Y787481D01*
X429829Y787548D01*
X430362Y787881D01*
X430696Y788281D01*
X430762Y788681D01*
X430629Y789148D01*
X430162Y789481D01*
X429696Y789614D01*
X429096D01*
G01X429696D02*
X430096Y789814D01*
X430429Y790148D01*
X430562Y790548D01*
X430429Y790948D01*
X430096Y791281D01*
X429496Y791481D01*
X428896Y791414D01*
X428296Y791148D01*
G01X433829Y787348D02*
X433696Y787414D01*
Y787548D01*
X433829Y787614D01*
X433962Y787548D01*
Y787414D01*
X433829Y787348D01*
G01X438429Y791481D02*
X437896Y791348D01*
X437496Y791014D01*
X437229Y790614D01*
X437029Y790081D01*
X436962Y789481D01*
X437029Y788881D01*
X437229Y788348D01*
X437496Y787948D01*
X437896Y787614D01*
X438429Y787481D01*
X438962Y787614D01*
X439362Y787948D01*
X439629Y788348D01*
X439829Y788881D01*
X439896Y789481D01*
X439829Y790081D01*
X439629Y790614D01*
X439362Y791014D01*
X438962Y791348D01*
X438429Y791481D01*
G01X443029Y787481D02*
X443496Y787548D01*
X444029Y787748D01*
X444362Y788081D01*
X444496Y788548D01*
X444362Y789014D01*
X443962Y789414D01*
X443362Y789614D01*
X442696D01*
X442296Y789748D01*
X441962Y790081D01*
X441829Y790548D01*
X442029Y791014D01*
X442496Y791348D01*
X443029Y791481D01*
X443562Y791348D01*
X444029Y791014D01*
X444229Y790548D01*
X444096Y790081D01*
X443762Y789748D01*
X443362Y789614D01*
X442696D01*
X442096Y789414D01*
X441696Y789014D01*
X441562Y788548D01*
X441696Y788081D01*
X442029Y787748D01*
X442562Y787548D01*
X443029Y787481D01*
G01X414366Y829638D02*
Y833638D01*
X415700D01*
X416233Y833438D01*
X416633Y833171D01*
X416966Y832771D01*
X417233Y832305D01*
X417300Y831638D01*
X417233Y830971D01*
X416966Y830505D01*
X416633Y830105D01*
X416233Y829838D01*
X415700Y829638D01*
X414366D01*
G01X419500D02*
Y832305D01*
G01Y831771D02*
X419833Y832038D01*
X420166Y832238D01*
X420633Y832305D01*
X420966Y832238D01*
X421366Y832038D01*
G01X425033Y832305D02*
Y829638D01*
G01Y833371D02*
X424900Y833438D01*
Y833571D01*
X425033Y833638D01*
X425166Y833571D01*
Y833438D01*
X425033Y833371D01*
G01X429633Y829638D02*
Y833638D01*
G01X434233Y829638D02*
Y833638D01*
G01X443033Y829638D02*
Y833038D01*
X443166Y833371D01*
X443433Y833571D01*
X443833Y833638D01*
X444233Y833505D01*
X444433Y833171D01*
G01X443633Y832038D02*
X442300D01*
G01X447033Y831438D02*
X449166D01*
X448966Y831905D01*
X448633Y832171D01*
X448166Y832305D01*
X447700Y832238D01*
X447300Y832038D01*
X447033Y831571D01*
X446900Y831171D01*
Y830771D01*
X447033Y830371D01*
X447366Y829971D01*
X447766Y829705D01*
X448233Y829638D01*
X448700Y829771D01*
X449166Y830171D01*
G01X453833Y829638D02*
Y832305D01*
G01Y831838D02*
X453566Y832105D01*
X453166Y832238D01*
X452700Y832305D01*
X452233Y832171D01*
X451833Y831905D01*
X451566Y831505D01*
X451433Y830971D01*
X451566Y830438D01*
X451833Y830038D01*
X452233Y829771D01*
X452700Y829638D01*
X453166Y829705D01*
X453566Y829905D01*
X453833Y830171D01*
G01X457233Y833638D02*
Y829638D01*
G01X456300Y832305D02*
X458166D01*
G01X460700D02*
Y830438D01*
X460966Y829971D01*
X461366Y829705D01*
X461833Y829638D01*
X462300Y829705D01*
X462700Y829971D01*
X462966Y830438D01*
G01Y829638D02*
Y832305D01*
G01X465500Y829638D02*
Y832305D01*
G01Y831771D02*
X465833Y832038D01*
X466166Y832238D01*
X466633Y832305D01*
X466966Y832238D01*
X467366Y832038D01*
G01X470033Y831438D02*
X472166D01*
X471966Y831905D01*
X471633Y832171D01*
X471166Y832305D01*
X470700Y832238D01*
X470300Y832038D01*
X470033Y831571D01*
X469900Y831171D01*
Y830771D01*
X470033Y830371D01*
X470366Y829971D01*
X470766Y829705D01*
X471233Y829638D01*
X471700Y829771D01*
X472166Y830171D01*
G01X420921Y871805D02*
X421321Y872205D01*
X421788Y872405D01*
X422321Y872472D01*
X422988Y872339D01*
X423455Y872005D01*
X423588Y871605D01*
X423521Y871205D01*
X423255Y870872D01*
X421921Y870205D01*
X421321Y869739D01*
X420921Y869072D01*
X420788Y868472D01*
X423588D01*
G01X426788Y872472D02*
X426255Y872339D01*
X425855Y872005D01*
X425588Y871605D01*
X425388Y871072D01*
X425321Y870472D01*
X425388Y869872D01*
X425588Y869339D01*
X425855Y868939D01*
X426255Y868605D01*
X426788Y868472D01*
X427321Y868605D01*
X427721Y868939D01*
X427988Y869339D01*
X428188Y869872D01*
X428255Y870472D01*
X428188Y871072D01*
X427988Y871605D01*
X427721Y872005D01*
X427321Y872339D01*
X426788Y872472D01*
G01X431388Y868472D02*
X431855Y868539D01*
X432388Y868739D01*
X432721Y869072D01*
X432855Y869539D01*
X432721Y870005D01*
X432321Y870405D01*
X431721Y870605D01*
X431055D01*
X430655Y870739D01*
X430321Y871072D01*
X430188Y871539D01*
X430388Y872005D01*
X430855Y872339D01*
X431388Y872472D01*
X431921Y872339D01*
X432388Y872005D01*
X432588Y871539D01*
X432455Y871072D01*
X432121Y870739D01*
X431721Y870605D01*
X431055D01*
X430455Y870405D01*
X430055Y870005D01*
X429921Y869539D01*
X430055Y869072D01*
X430388Y868739D01*
X430921Y868539D01*
X431388Y868472D01*
G01X435988Y868339D02*
X435855Y868405D01*
Y868539D01*
X435988Y868605D01*
X436121Y868539D01*
Y868405D01*
X435988Y868339D01*
G01X439321Y870139D02*
X439788Y870605D01*
X440188Y870872D01*
X440721Y871005D01*
X441188Y870872D01*
X441521Y870605D01*
X441788Y870205D01*
X441855Y869739D01*
X441788Y869339D01*
X441521Y868939D01*
X441121Y868605D01*
X440655Y868472D01*
X440121Y868605D01*
X439655Y869005D01*
X439388Y869605D01*
X439321Y870272D01*
X439455Y871139D01*
X439655Y871605D01*
X439988Y872072D01*
X440455Y872405D01*
X440921Y872472D01*
X441388Y872339D01*
X441721Y872005D01*
G01X443921Y870139D02*
X444388Y870605D01*
X444788Y870872D01*
X445321Y871005D01*
X445788Y870872D01*
X446121Y870605D01*
X446388Y870205D01*
X446455Y869739D01*
X446388Y869339D01*
X446121Y868939D01*
X445721Y868605D01*
X445255Y868472D01*
X444721Y868605D01*
X444255Y869005D01*
X443988Y869605D01*
X443921Y870272D01*
X444055Y871139D01*
X444255Y871605D01*
X444588Y872072D01*
X445055Y872405D01*
X445521Y872472D01*
X445988Y872339D01*
X446321Y872005D01*
G01X420829Y1240237D02*
Y1244237D01*
X418362Y1241370D01*
X421696D01*
G01X423162Y1241037D02*
X423562Y1240570D01*
X424096Y1240304D01*
X424696Y1240237D01*
X425229Y1240304D01*
X425762Y1240637D01*
X426096Y1241037D01*
X426162Y1241437D01*
X426029Y1241904D01*
X425562Y1242237D01*
X425096Y1242370D01*
X424496D01*
G01X425096D02*
X425496Y1242570D01*
X425829Y1242904D01*
X425962Y1243304D01*
X425829Y1243704D01*
X425496Y1244037D01*
X424896Y1244237D01*
X424296Y1244170D01*
X423696Y1243904D01*
G01X427762Y1241037D02*
X428162Y1240570D01*
X428696Y1240304D01*
X429296Y1240237D01*
X429829Y1240304D01*
X430362Y1240637D01*
X430696Y1241037D01*
X430762Y1241437D01*
X430629Y1241904D01*
X430162Y1242237D01*
X429696Y1242370D01*
X429096D01*
G01X429696D02*
X430096Y1242570D01*
X430429Y1242904D01*
X430562Y1243304D01*
X430429Y1243704D01*
X430096Y1244037D01*
X429496Y1244237D01*
X428896Y1244170D01*
X428296Y1243904D01*
G01X433829Y1240104D02*
X433696Y1240170D01*
Y1240304D01*
X433829Y1240370D01*
X433962Y1240304D01*
Y1240170D01*
X433829Y1240104D01*
G01X438429Y1244237D02*
X437896Y1244104D01*
X437496Y1243770D01*
X437229Y1243370D01*
X437029Y1242837D01*
X436962Y1242237D01*
X437029Y1241637D01*
X437229Y1241104D01*
X437496Y1240704D01*
X437896Y1240370D01*
X438429Y1240237D01*
X438962Y1240370D01*
X439362Y1240704D01*
X439629Y1241104D01*
X439829Y1241637D01*
X439896Y1242237D01*
X439829Y1242837D01*
X439629Y1243370D01*
X439362Y1243770D01*
X438962Y1244104D01*
X438429Y1244237D01*
G01X443029Y1240237D02*
X443496Y1240304D01*
X444029Y1240504D01*
X444362Y1240837D01*
X444496Y1241304D01*
X444362Y1241770D01*
X443962Y1242170D01*
X443362Y1242370D01*
X442696D01*
X442296Y1242504D01*
X441962Y1242837D01*
X441829Y1243304D01*
X442029Y1243770D01*
X442496Y1244104D01*
X443029Y1244237D01*
X443562Y1244104D01*
X444029Y1243770D01*
X444229Y1243304D01*
X444096Y1242837D01*
X443762Y1242504D01*
X443362Y1242370D01*
X442696D01*
X442096Y1242170D01*
X441696Y1241770D01*
X441562Y1241304D01*
X441696Y1240837D01*
X442029Y1240504D01*
X442562Y1240304D01*
X443029Y1240237D01*
G01X420921Y1324561D02*
X421321Y1324961D01*
X421788Y1325161D01*
X422321Y1325228D01*
X422988Y1325095D01*
X423455Y1324761D01*
X423588Y1324361D01*
X423521Y1323961D01*
X423255Y1323628D01*
X421921Y1322961D01*
X421321Y1322495D01*
X420921Y1321828D01*
X420788Y1321228D01*
X423588D01*
G01X426788Y1325228D02*
X426255Y1325095D01*
X425855Y1324761D01*
X425588Y1324361D01*
X425388Y1323828D01*
X425321Y1323228D01*
X425388Y1322628D01*
X425588Y1322095D01*
X425855Y1321695D01*
X426255Y1321361D01*
X426788Y1321228D01*
X427321Y1321361D01*
X427721Y1321695D01*
X427988Y1322095D01*
X428188Y1322628D01*
X428255Y1323228D01*
X428188Y1323828D01*
X427988Y1324361D01*
X427721Y1324761D01*
X427321Y1325095D01*
X426788Y1325228D01*
G01X431388Y1321228D02*
X431855Y1321295D01*
X432388Y1321495D01*
X432721Y1321828D01*
X432855Y1322295D01*
X432721Y1322761D01*
X432321Y1323161D01*
X431721Y1323361D01*
X431055D01*
X430655Y1323495D01*
X430321Y1323828D01*
X430188Y1324295D01*
X430388Y1324761D01*
X430855Y1325095D01*
X431388Y1325228D01*
X431921Y1325095D01*
X432388Y1324761D01*
X432588Y1324295D01*
X432455Y1323828D01*
X432121Y1323495D01*
X431721Y1323361D01*
X431055D01*
X430455Y1323161D01*
X430055Y1322761D01*
X429921Y1322295D01*
X430055Y1321828D01*
X430388Y1321495D01*
X430921Y1321295D01*
X431388Y1321228D01*
G01X435988Y1321095D02*
X435855Y1321161D01*
Y1321295D01*
X435988Y1321361D01*
X436121Y1321295D01*
Y1321161D01*
X435988Y1321095D01*
G01X439321Y1322895D02*
X439788Y1323361D01*
X440188Y1323628D01*
X440721Y1323761D01*
X441188Y1323628D01*
X441521Y1323361D01*
X441788Y1322961D01*
X441855Y1322495D01*
X441788Y1322095D01*
X441521Y1321695D01*
X441121Y1321361D01*
X440655Y1321228D01*
X440121Y1321361D01*
X439655Y1321761D01*
X439388Y1322361D01*
X439321Y1323028D01*
X439455Y1323895D01*
X439655Y1324361D01*
X439988Y1324828D01*
X440455Y1325161D01*
X440921Y1325228D01*
X441388Y1325095D01*
X441721Y1324761D01*
G01X443921Y1322895D02*
X444388Y1323361D01*
X444788Y1323628D01*
X445321Y1323761D01*
X445788Y1323628D01*
X446121Y1323361D01*
X446388Y1322961D01*
X446455Y1322495D01*
X446388Y1322095D01*
X446121Y1321695D01*
X445721Y1321361D01*
X445255Y1321228D01*
X444721Y1321361D01*
X444255Y1321761D01*
X443988Y1322361D01*
X443921Y1323028D01*
X444055Y1323895D01*
X444255Y1324361D01*
X444588Y1324828D01*
X445055Y1325161D01*
X445521Y1325228D01*
X445988Y1325095D01*
X446321Y1324761D01*
G01X414366Y1282394D02*
Y1286394D01*
X415700D01*
X416233Y1286194D01*
X416633Y1285927D01*
X416966Y1285527D01*
X417233Y1285061D01*
X417300Y1284394D01*
X417233Y1283727D01*
X416966Y1283261D01*
X416633Y1282861D01*
X416233Y1282594D01*
X415700Y1282394D01*
X414366D01*
G01X419500D02*
Y1285061D01*
G01Y1284527D02*
X419833Y1284794D01*
X420166Y1284994D01*
X420633Y1285061D01*
X420966Y1284994D01*
X421366Y1284794D01*
G01X425033Y1285061D02*
Y1282394D01*
G01Y1286127D02*
X424900Y1286194D01*
Y1286327D01*
X425033Y1286394D01*
X425166Y1286327D01*
Y1286194D01*
X425033Y1286127D01*
G01X429633Y1282394D02*
Y1286394D01*
G01X434233Y1282394D02*
Y1286394D01*
G01X443033Y1282394D02*
Y1285794D01*
X443166Y1286127D01*
X443433Y1286327D01*
X443833Y1286394D01*
X444233Y1286261D01*
X444433Y1285927D01*
G01X443633Y1284794D02*
X442300D01*
G01X447033Y1284194D02*
X449166D01*
X448966Y1284661D01*
X448633Y1284927D01*
X448166Y1285061D01*
X447700Y1284994D01*
X447300Y1284794D01*
X447033Y1284327D01*
X446900Y1283927D01*
Y1283527D01*
X447033Y1283127D01*
X447366Y1282727D01*
X447766Y1282461D01*
X448233Y1282394D01*
X448700Y1282527D01*
X449166Y1282927D01*
G01X453833Y1282394D02*
Y1285061D01*
G01Y1284594D02*
X453566Y1284861D01*
X453166Y1284994D01*
X452700Y1285061D01*
X452233Y1284927D01*
X451833Y1284661D01*
X451566Y1284261D01*
X451433Y1283727D01*
X451566Y1283194D01*
X451833Y1282794D01*
X452233Y1282527D01*
X452700Y1282394D01*
X453166Y1282461D01*
X453566Y1282661D01*
X453833Y1282927D01*
G01X457233Y1286394D02*
Y1282394D01*
G01X456300Y1285061D02*
X458166D01*
G01X460700D02*
Y1283194D01*
X460966Y1282727D01*
X461366Y1282461D01*
X461833Y1282394D01*
X462300Y1282461D01*
X462700Y1282727D01*
X462966Y1283194D01*
G01Y1282394D02*
Y1285061D01*
G01X465500Y1282394D02*
Y1285061D01*
G01Y1284527D02*
X465833Y1284794D01*
X466166Y1284994D01*
X466633Y1285061D01*
X466966Y1284994D01*
X467366Y1284794D01*
G01X470033Y1284194D02*
X472166D01*
X471966Y1284661D01*
X471633Y1284927D01*
X471166Y1285061D01*
X470700Y1284994D01*
X470300Y1284794D01*
X470033Y1284327D01*
X469900Y1283927D01*
Y1283527D01*
X470033Y1283127D01*
X470366Y1282727D01*
X470766Y1282461D01*
X471233Y1282394D01*
X471700Y1282527D01*
X472166Y1282927D01*
G01X489265Y50394D02*
X489798Y50727D01*
X490398Y50927D01*
X490932D01*
X491465Y50727D01*
X491865Y50394D01*
X492065Y49927D01*
X491932Y49460D01*
X491598Y49060D01*
X490998Y48794D01*
X490198Y48660D01*
X489732Y48394D01*
X489532Y47927D01*
X489665Y47460D01*
X489998Y47127D01*
X490465Y46927D01*
X490932D01*
X491398Y47060D01*
X491798Y47394D01*
G01X495265Y50927D02*
Y46927D01*
G01X499865Y48260D02*
Y50927D01*
G01Y47194D02*
X499732Y47127D01*
Y46994D01*
X499865Y46927D01*
X499998Y46994D01*
Y47127D01*
X499865Y47194D01*
G01X504465Y46927D02*
Y50927D01*
G01X503532Y48260D02*
X505398D01*
G01X497751Y58567D02*
X499751Y56567D01*
X495751D01*
X497751Y58567D01*
Y52567D01*
G01X523327Y829921D02*
G03X483169I-20079J0D01*
G01X523327D02*
G03I-20079J0D01*
G01X483169D02*
G03X523327I20079J0D01*
G01X522270Y58476D02*
X518270Y54476D01*
X526270D01*
X522270Y58476D01*
Y44476D01*
G01X550826Y367773D02*
X551226Y367440D01*
X551693Y367240D01*
X552293Y367173D01*
X552893Y367306D01*
X553360Y367573D01*
X553693Y368040D01*
X553760Y368573D01*
X553626Y369106D01*
X553293Y369440D01*
X552826Y369706D01*
X552360Y369773D01*
X551893Y369706D01*
X551293Y369440D01*
X551493Y371173D01*
X553293D01*
G01X555426Y367773D02*
X555826Y367440D01*
X556293Y367240D01*
X556893Y367173D01*
X557493Y367306D01*
X557960Y367573D01*
X558293Y368040D01*
X558360Y368573D01*
X558226Y369106D01*
X557893Y369440D01*
X557426Y369706D01*
X556960Y369773D01*
X556493Y369706D01*
X555893Y369440D01*
X556093Y371173D01*
X557893D01*
G01X561360Y367173D02*
X561493Y368040D01*
X561693Y368773D01*
X561960Y369440D01*
X562293Y370173D01*
X562826Y371173D01*
X560160D01*
G01X566093Y367040D02*
X565960Y367106D01*
Y367240D01*
X566093Y367306D01*
X566226Y367240D01*
Y367106D01*
X566093Y367040D01*
G01X570693Y371173D02*
X570160Y371040D01*
X569760Y370706D01*
X569493Y370306D01*
X569293Y369773D01*
X569226Y369173D01*
X569293Y368573D01*
X569493Y368040D01*
X569760Y367640D01*
X570160Y367306D01*
X570693Y367173D01*
X571226Y367306D01*
X571626Y367640D01*
X571893Y368040D01*
X572093Y368573D01*
X572160Y369173D01*
X572093Y369773D01*
X571893Y370306D01*
X571626Y370706D01*
X571226Y371040D01*
X570693Y371173D01*
G01X574160Y367640D02*
X574626Y367306D01*
X575160Y367173D01*
X575693Y367306D01*
X576160Y367706D01*
X576493Y368306D01*
X576626Y368906D01*
Y369640D01*
X576493Y370240D01*
X576160Y370773D01*
X575760Y371040D01*
X575293Y371173D01*
X574760Y371040D01*
X574360Y370773D01*
X574093Y370373D01*
X573960Y369840D01*
X574093Y369373D01*
X574426Y368906D01*
X574826Y368640D01*
X575293Y368573D01*
X575826Y368706D01*
X576226Y369040D01*
X576626Y369640D01*
G01X550826Y820529D02*
X551226Y820196D01*
X551693Y819996D01*
X552293Y819929D01*
X552893Y820062D01*
X553360Y820329D01*
X553693Y820796D01*
X553760Y821329D01*
X553626Y821862D01*
X553293Y822196D01*
X552826Y822462D01*
X552360Y822529D01*
X551893Y822462D01*
X551293Y822196D01*
X551493Y823929D01*
X553293D01*
G01X555426Y820529D02*
X555826Y820196D01*
X556293Y819996D01*
X556893Y819929D01*
X557493Y820062D01*
X557960Y820329D01*
X558293Y820796D01*
X558360Y821329D01*
X558226Y821862D01*
X557893Y822196D01*
X557426Y822462D01*
X556960Y822529D01*
X556493Y822462D01*
X555893Y822196D01*
X556093Y823929D01*
X557893D01*
G01X561360Y819929D02*
X561493Y820796D01*
X561693Y821529D01*
X561960Y822196D01*
X562293Y822929D01*
X562826Y823929D01*
X560160D01*
G01X566093Y819796D02*
X565960Y819862D01*
Y819996D01*
X566093Y820062D01*
X566226Y819996D01*
Y819862D01*
X566093Y819796D01*
G01X570693Y823929D02*
X570160Y823796D01*
X569760Y823462D01*
X569493Y823062D01*
X569293Y822529D01*
X569226Y821929D01*
X569293Y821329D01*
X569493Y820796D01*
X569760Y820396D01*
X570160Y820062D01*
X570693Y819929D01*
X571226Y820062D01*
X571626Y820396D01*
X571893Y820796D01*
X572093Y821329D01*
X572160Y821929D01*
X572093Y822529D01*
X571893Y823062D01*
X571626Y823462D01*
X571226Y823796D01*
X570693Y823929D01*
G01X574160Y820396D02*
X574626Y820062D01*
X575160Y819929D01*
X575693Y820062D01*
X576160Y820462D01*
X576493Y821062D01*
X576626Y821662D01*
Y822396D01*
X576493Y822996D01*
X576160Y823529D01*
X575760Y823796D01*
X575293Y823929D01*
X574760Y823796D01*
X574360Y823529D01*
X574093Y823129D01*
X573960Y822596D01*
X574093Y822129D01*
X574426Y821662D01*
X574826Y821396D01*
X575293Y821329D01*
X575826Y821462D01*
X576226Y821796D01*
X576626Y822396D01*
G01X550826Y1273285D02*
X551226Y1272952D01*
X551693Y1272752D01*
X552293Y1272685D01*
X552893Y1272818D01*
X553360Y1273085D01*
X553693Y1273552D01*
X553760Y1274085D01*
X553626Y1274618D01*
X553293Y1274952D01*
X552826Y1275218D01*
X552360Y1275285D01*
X551893Y1275218D01*
X551293Y1274952D01*
X551493Y1276685D01*
X553293D01*
G01X555426Y1273285D02*
X555826Y1272952D01*
X556293Y1272752D01*
X556893Y1272685D01*
X557493Y1272818D01*
X557960Y1273085D01*
X558293Y1273552D01*
X558360Y1274085D01*
X558226Y1274618D01*
X557893Y1274952D01*
X557426Y1275218D01*
X556960Y1275285D01*
X556493Y1275218D01*
X555893Y1274952D01*
X556093Y1276685D01*
X557893D01*
G01X561360Y1272685D02*
X561493Y1273552D01*
X561693Y1274285D01*
X561960Y1274952D01*
X562293Y1275685D01*
X562826Y1276685D01*
X560160D01*
G01X566093Y1272552D02*
X565960Y1272618D01*
Y1272752D01*
X566093Y1272818D01*
X566226Y1272752D01*
Y1272618D01*
X566093Y1272552D01*
G01X570693Y1276685D02*
X570160Y1276552D01*
X569760Y1276218D01*
X569493Y1275818D01*
X569293Y1275285D01*
X569226Y1274685D01*
X569293Y1274085D01*
X569493Y1273552D01*
X569760Y1273152D01*
X570160Y1272818D01*
X570693Y1272685D01*
X571226Y1272818D01*
X571626Y1273152D01*
X571893Y1273552D01*
X572093Y1274085D01*
X572160Y1274685D01*
X572093Y1275285D01*
X571893Y1275818D01*
X571626Y1276218D01*
X571226Y1276552D01*
X570693Y1276685D01*
G01X574160Y1273152D02*
X574626Y1272818D01*
X575160Y1272685D01*
X575693Y1272818D01*
X576160Y1273218D01*
X576493Y1273818D01*
X576626Y1274418D01*
Y1275152D01*
X576493Y1275752D01*
X576160Y1276285D01*
X575760Y1276552D01*
X575293Y1276685D01*
X574760Y1276552D01*
X574360Y1276285D01*
X574093Y1275885D01*
X573960Y1275352D01*
X574093Y1274885D01*
X574426Y1274418D01*
X574826Y1274152D01*
X575293Y1274085D01*
X575826Y1274218D01*
X576226Y1274552D01*
X576626Y1275152D01*
G01X594488Y-7874D02*
X628765D01*
G01X594488D02*
X628765D01*
G01X590551Y55118D02*
Y3937D01*
G01D02*
G03X594488Y0I3937J0D01*
G01X582677Y51181D02*
Y3937D01*
G01D02*
G03X594488Y-7874I11811J0D01*
G01X590551Y55118D02*
Y3937D01*
G01D02*
G03X594488Y0I3937J0D01*
G01X582677Y51181D02*
Y3937D01*
G01D02*
G03X594488Y-7874I11811J0D01*
G01Y0D02*
X783465D01*
G01X594488D02*
X783465D01*
G01X590551Y55118D02*
G03X586614Y59055I-3937J0D01*
G01X590551Y55118D02*
G03X586614Y59055I-3937J0D01*
G01X568165Y378319D02*
X568565Y378719D01*
X569032Y378919D01*
X569565Y378986D01*
X570232Y378853D01*
X570699Y378519D01*
X570832Y378119D01*
X570765Y377719D01*
X570499Y377386D01*
X569165Y376719D01*
X568565Y376253D01*
X568165Y375586D01*
X568032Y374986D01*
X570832D01*
G01X572565Y375786D02*
X572965Y375319D01*
X573499Y375053D01*
X574099Y374986D01*
X574632Y375053D01*
X575165Y375386D01*
X575499Y375786D01*
X575565Y376186D01*
X575432Y376653D01*
X574965Y376986D01*
X574499Y377119D01*
X573899D01*
G01X574499D02*
X574899Y377319D01*
X575232Y377653D01*
X575365Y378053D01*
X575232Y378453D01*
X574899Y378786D01*
X574299Y378986D01*
X573699Y378919D01*
X573099Y378653D01*
G01X577365Y376653D02*
X577832Y377119D01*
X578232Y377386D01*
X578765Y377519D01*
X579232Y377386D01*
X579565Y377119D01*
X579832Y376719D01*
X579899Y376253D01*
X579832Y375853D01*
X579565Y375453D01*
X579165Y375119D01*
X578699Y374986D01*
X578165Y375119D01*
X577699Y375519D01*
X577432Y376119D01*
X577365Y376786D01*
X577499Y377653D01*
X577699Y378119D01*
X578032Y378586D01*
X578499Y378919D01*
X578965Y378986D01*
X579432Y378853D01*
X579765Y378519D01*
G01X583232Y374853D02*
X583099Y374919D01*
Y375053D01*
X583232Y375119D01*
X583365Y375053D01*
Y374919D01*
X583232Y374853D01*
G01X586565Y378319D02*
X586965Y378719D01*
X587432Y378919D01*
X587965Y378986D01*
X588632Y378853D01*
X589099Y378519D01*
X589232Y378119D01*
X589165Y377719D01*
X588899Y377386D01*
X587565Y376719D01*
X586965Y376253D01*
X586565Y375586D01*
X586432Y374986D01*
X589232D01*
G01X591165Y378319D02*
X591565Y378719D01*
X592032Y378919D01*
X592565Y378986D01*
X593232Y378853D01*
X593699Y378519D01*
X593832Y378119D01*
X593765Y377719D01*
X593499Y377386D01*
X592165Y376719D01*
X591565Y376253D01*
X591165Y375586D01*
X591032Y374986D01*
X593832D01*
G01X568165Y831075D02*
X568565Y831475D01*
X569032Y831675D01*
X569565Y831742D01*
X570232Y831609D01*
X570699Y831275D01*
X570832Y830875D01*
X570765Y830475D01*
X570499Y830142D01*
X569165Y829475D01*
X568565Y829009D01*
X568165Y828342D01*
X568032Y827742D01*
X570832D01*
G01X572565Y828542D02*
X572965Y828075D01*
X573499Y827809D01*
X574099Y827742D01*
X574632Y827809D01*
X575165Y828142D01*
X575499Y828542D01*
X575565Y828942D01*
X575432Y829409D01*
X574965Y829742D01*
X574499Y829875D01*
X573899D01*
G01X574499D02*
X574899Y830075D01*
X575232Y830409D01*
X575365Y830809D01*
X575232Y831209D01*
X574899Y831542D01*
X574299Y831742D01*
X573699Y831675D01*
X573099Y831409D01*
G01X577365Y829409D02*
X577832Y829875D01*
X578232Y830142D01*
X578765Y830275D01*
X579232Y830142D01*
X579565Y829875D01*
X579832Y829475D01*
X579899Y829009D01*
X579832Y828609D01*
X579565Y828209D01*
X579165Y827875D01*
X578699Y827742D01*
X578165Y827875D01*
X577699Y828275D01*
X577432Y828875D01*
X577365Y829542D01*
X577499Y830409D01*
X577699Y830875D01*
X578032Y831342D01*
X578499Y831675D01*
X578965Y831742D01*
X579432Y831609D01*
X579765Y831275D01*
G01X583232Y827609D02*
X583099Y827675D01*
Y827809D01*
X583232Y827875D01*
X583365Y827809D01*
Y827675D01*
X583232Y827609D01*
G01X586565Y831075D02*
X586965Y831475D01*
X587432Y831675D01*
X587965Y831742D01*
X588632Y831609D01*
X589099Y831275D01*
X589232Y830875D01*
X589165Y830475D01*
X588899Y830142D01*
X587565Y829475D01*
X586965Y829009D01*
X586565Y828342D01*
X586432Y827742D01*
X589232D01*
G01X591165Y831075D02*
X591565Y831475D01*
X592032Y831675D01*
X592565Y831742D01*
X593232Y831609D01*
X593699Y831275D01*
X593832Y830875D01*
X593765Y830475D01*
X593499Y830142D01*
X592165Y829475D01*
X591565Y829009D01*
X591165Y828342D01*
X591032Y827742D01*
X593832D01*
G01X568165Y1283831D02*
X568565Y1284231D01*
X569032Y1284431D01*
X569565Y1284498D01*
X570232Y1284365D01*
X570699Y1284031D01*
X570832Y1283631D01*
X570765Y1283231D01*
X570499Y1282898D01*
X569165Y1282231D01*
X568565Y1281765D01*
X568165Y1281098D01*
X568032Y1280498D01*
X570832D01*
G01X572565Y1281298D02*
X572965Y1280831D01*
X573499Y1280565D01*
X574099Y1280498D01*
X574632Y1280565D01*
X575165Y1280898D01*
X575499Y1281298D01*
X575565Y1281698D01*
X575432Y1282165D01*
X574965Y1282498D01*
X574499Y1282631D01*
X573899D01*
G01X574499D02*
X574899Y1282831D01*
X575232Y1283165D01*
X575365Y1283565D01*
X575232Y1283965D01*
X574899Y1284298D01*
X574299Y1284498D01*
X573699Y1284431D01*
X573099Y1284165D01*
G01X577365Y1282165D02*
X577832Y1282631D01*
X578232Y1282898D01*
X578765Y1283031D01*
X579232Y1282898D01*
X579565Y1282631D01*
X579832Y1282231D01*
X579899Y1281765D01*
X579832Y1281365D01*
X579565Y1280965D01*
X579165Y1280631D01*
X578699Y1280498D01*
X578165Y1280631D01*
X577699Y1281031D01*
X577432Y1281631D01*
X577365Y1282298D01*
X577499Y1283165D01*
X577699Y1283631D01*
X578032Y1284098D01*
X578499Y1284431D01*
X578965Y1284498D01*
X579432Y1284365D01*
X579765Y1284031D01*
G01X583232Y1280365D02*
X583099Y1280431D01*
Y1280565D01*
X583232Y1280631D01*
X583365Y1280565D01*
Y1280431D01*
X583232Y1280365D01*
G01X586565Y1283831D02*
X586965Y1284231D01*
X587432Y1284431D01*
X587965Y1284498D01*
X588632Y1284365D01*
X589099Y1284031D01*
X589232Y1283631D01*
X589165Y1283231D01*
X588899Y1282898D01*
X587565Y1282231D01*
X586965Y1281765D01*
X586565Y1281098D01*
X586432Y1280498D01*
X589232D01*
G01X591165Y1283831D02*
X591565Y1284231D01*
X592032Y1284431D01*
X592565Y1284498D01*
X593232Y1284365D01*
X593699Y1284031D01*
X593832Y1283631D01*
X593765Y1283231D01*
X593499Y1282898D01*
X592165Y1282231D01*
X591565Y1281765D01*
X591165Y1281098D01*
X591032Y1280498D01*
X593832D01*
G01X628765Y-7874D02*
G03Y0I0J3937D01*
G01Y-7874D02*
G03Y0I0J3937D01*
G01X610358Y378885D02*
G03X644169I16906J-13531D01*
G01X610358D02*
G03X644169I16906J-13531D01*
G01X637244Y392016D02*
G03X644169Y378885I37662J11471D01*
G01X637244Y392016D02*
G03X644169Y378885I37662J11471D01*
G01X637244Y392016D02*
G03X617283I-9980J-3039D01*
G01X637244D02*
G03X617283I-9980J-3039D01*
G01X610358Y378885D02*
G03X617283Y392016I-30737J24602D01*
G01X610358Y378885D02*
G03X617283Y392016I-30737J24602D01*
G01X637244Y844772D02*
G03X644169Y831641I37662J11471D01*
G01X637244Y844772D02*
G03X644169Y831641I37662J11471D01*
G01X610358D02*
G03X617283Y844772I-30737J24601D01*
G01X610358Y831641D02*
G03X617283Y844772I-30737J24602D01*
G01X610358Y831641D02*
G03X644169I16906J-13531D01*
G01X610358D02*
G03X644169I16906J-13531D01*
G01X637244Y844772D02*
G03X617283I-9980J-3040D01*
G01X637244D02*
G03X617283I-9980J-3039D01*
G01X610358Y1284397D02*
G03X644169I16906J-13531D01*
G01X610358D02*
G03X644169I16906J-13531D01*
G01X637244Y1297528D02*
G03X644169Y1284397I37662J11471D01*
G01X637244Y1297528D02*
G03X644169Y1284397I37662J11471D01*
G01X610358D02*
G03X617283Y1297528I-30737J24601D01*
G01X637244D02*
G03X617283I-9980J-3040D01*
G01X610358Y1284397D02*
G03X617283Y1297528I-30737J24602D01*
G01X637244D02*
G03X617283I-9980J-3040D01*
G01X659474Y0D02*
G03Y-7874I0J-3937D01*
G01Y0D02*
G03Y-7874I0J-3937D01*
G01D02*
X780203D01*
G01X659474D02*
X780203D01*
G01X668860Y334725D02*
Y338725D01*
X666393Y335858D01*
X669727D01*
G01X671193Y335525D02*
X671593Y335058D01*
X672127Y334792D01*
X672727Y334725D01*
X673260Y334792D01*
X673793Y335125D01*
X674127Y335525D01*
X674193Y335925D01*
X674060Y336392D01*
X673593Y336725D01*
X673127Y336858D01*
X672527D01*
G01X673127D02*
X673527Y337058D01*
X673860Y337392D01*
X673993Y337792D01*
X673860Y338192D01*
X673527Y338525D01*
X672927Y338725D01*
X672327Y338658D01*
X671727Y338392D01*
G01X675793Y335525D02*
X676193Y335058D01*
X676727Y334792D01*
X677327Y334725D01*
X677860Y334792D01*
X678393Y335125D01*
X678727Y335525D01*
X678793Y335925D01*
X678660Y336392D01*
X678193Y336725D01*
X677727Y336858D01*
X677127D01*
G01X677727D02*
X678127Y337058D01*
X678460Y337392D01*
X678593Y337792D01*
X678460Y338192D01*
X678127Y338525D01*
X677527Y338725D01*
X676927Y338658D01*
X676327Y338392D01*
G01X681860Y334592D02*
X681727Y334658D01*
Y334792D01*
X681860Y334858D01*
X681993Y334792D01*
Y334658D01*
X681860Y334592D01*
G01X686460Y338725D02*
X685927Y338592D01*
X685527Y338258D01*
X685260Y337858D01*
X685060Y337325D01*
X684993Y336725D01*
X685060Y336125D01*
X685260Y335592D01*
X685527Y335192D01*
X685927Y334858D01*
X686460Y334725D01*
X686993Y334858D01*
X687393Y335192D01*
X687660Y335592D01*
X687860Y336125D01*
X687927Y336725D01*
X687860Y337325D01*
X687660Y337858D01*
X687393Y338258D01*
X686993Y338592D01*
X686460Y338725D01*
G01X691060Y334725D02*
X691527Y334792D01*
X692060Y334992D01*
X692393Y335325D01*
X692527Y335792D01*
X692393Y336258D01*
X691993Y336658D01*
X691393Y336858D01*
X690727D01*
X690327Y336992D01*
X689993Y337325D01*
X689860Y337792D01*
X690060Y338258D01*
X690527Y338592D01*
X691060Y338725D01*
X691593Y338592D01*
X692060Y338258D01*
X692260Y337792D01*
X692127Y337325D01*
X691793Y336992D01*
X691393Y336858D01*
X690727D01*
X690127Y336658D01*
X689727Y336258D01*
X689593Y335792D01*
X689727Y335325D01*
X690060Y334992D01*
X690593Y334792D01*
X691060Y334725D01*
G01X662397Y376882D02*
Y380882D01*
X663731D01*
X664264Y380682D01*
X664664Y380415D01*
X664997Y380015D01*
X665264Y379549D01*
X665331Y378882D01*
X665264Y378215D01*
X664997Y377749D01*
X664664Y377349D01*
X664264Y377082D01*
X663731Y376882D01*
X662397D01*
G01X667531D02*
Y379549D01*
G01Y379015D02*
X667864Y379282D01*
X668197Y379482D01*
X668664Y379549D01*
X668997Y379482D01*
X669397Y379282D01*
G01X673064Y379549D02*
Y376882D01*
G01Y380615D02*
X672931Y380682D01*
Y380815D01*
X673064Y380882D01*
X673197Y380815D01*
Y380682D01*
X673064Y380615D01*
G01X677664Y376882D02*
Y380882D01*
G01X682264Y376882D02*
Y380882D01*
G01X691064Y376882D02*
Y380282D01*
X691197Y380615D01*
X691464Y380815D01*
X691864Y380882D01*
X692264Y380749D01*
X692464Y380415D01*
G01X691664Y379282D02*
X690331D01*
G01X695064Y378682D02*
X697197D01*
X696997Y379149D01*
X696664Y379415D01*
X696197Y379549D01*
X695731Y379482D01*
X695331Y379282D01*
X695064Y378815D01*
X694931Y378415D01*
Y378015D01*
X695064Y377615D01*
X695397Y377215D01*
X695797Y376949D01*
X696264Y376882D01*
X696731Y377015D01*
X697197Y377415D01*
G01X701864Y376882D02*
Y379549D01*
G01Y379082D02*
X701597Y379349D01*
X701197Y379482D01*
X700731Y379549D01*
X700264Y379415D01*
X699864Y379149D01*
X699597Y378749D01*
X699464Y378215D01*
X699597Y377682D01*
X699864Y377282D01*
X700264Y377015D01*
X700731Y376882D01*
X701197Y376949D01*
X701597Y377149D01*
X701864Y377415D01*
G01X705264Y380882D02*
Y376882D01*
G01X704331Y379549D02*
X706197D01*
G01X708731D02*
Y377682D01*
X708997Y377215D01*
X709397Y376949D01*
X709864Y376882D01*
X710331Y376949D01*
X710731Y377215D01*
X710997Y377682D01*
G01Y376882D02*
Y379549D01*
G01X713531Y376882D02*
Y379549D01*
G01Y379015D02*
X713864Y379282D01*
X714197Y379482D01*
X714664Y379549D01*
X714997Y379482D01*
X715397Y379282D01*
G01X718064Y378682D02*
X720197D01*
X719997Y379149D01*
X719664Y379415D01*
X719197Y379549D01*
X718731Y379482D01*
X718331Y379282D01*
X718064Y378815D01*
X717931Y378415D01*
Y378015D01*
X718064Y377615D01*
X718397Y377215D01*
X718797Y376949D01*
X719264Y376882D01*
X719731Y377015D01*
X720197Y377415D01*
G01X668952Y419049D02*
X669352Y419449D01*
X669819Y419649D01*
X670352Y419716D01*
X671019Y419583D01*
X671486Y419249D01*
X671619Y418849D01*
X671552Y418449D01*
X671286Y418116D01*
X669952Y417449D01*
X669352Y416983D01*
X668952Y416316D01*
X668819Y415716D01*
X671619D01*
G01X674819Y419716D02*
X674286Y419583D01*
X673886Y419249D01*
X673619Y418849D01*
X673419Y418316D01*
X673352Y417716D01*
X673419Y417116D01*
X673619Y416583D01*
X673886Y416183D01*
X674286Y415849D01*
X674819Y415716D01*
X675352Y415849D01*
X675752Y416183D01*
X676019Y416583D01*
X676219Y417116D01*
X676286Y417716D01*
X676219Y418316D01*
X676019Y418849D01*
X675752Y419249D01*
X675352Y419583D01*
X674819Y419716D01*
G01X679419Y415716D02*
X679886Y415783D01*
X680419Y415983D01*
X680752Y416316D01*
X680886Y416783D01*
X680752Y417249D01*
X680352Y417649D01*
X679752Y417849D01*
X679086D01*
X678686Y417983D01*
X678352Y418316D01*
X678219Y418783D01*
X678419Y419249D01*
X678886Y419583D01*
X679419Y419716D01*
X679952Y419583D01*
X680419Y419249D01*
X680619Y418783D01*
X680486Y418316D01*
X680152Y417983D01*
X679752Y417849D01*
X679086D01*
X678486Y417649D01*
X678086Y417249D01*
X677952Y416783D01*
X678086Y416316D01*
X678419Y415983D01*
X678952Y415783D01*
X679419Y415716D01*
G01X684019Y415583D02*
X683886Y415649D01*
Y415783D01*
X684019Y415849D01*
X684152Y415783D01*
Y415649D01*
X684019Y415583D01*
G01X687352Y417383D02*
X687819Y417849D01*
X688219Y418116D01*
X688752Y418249D01*
X689219Y418116D01*
X689552Y417849D01*
X689819Y417449D01*
X689886Y416983D01*
X689819Y416583D01*
X689552Y416183D01*
X689152Y415849D01*
X688686Y415716D01*
X688152Y415849D01*
X687686Y416249D01*
X687419Y416849D01*
X687352Y417516D01*
X687486Y418383D01*
X687686Y418849D01*
X688019Y419316D01*
X688486Y419649D01*
X688952Y419716D01*
X689419Y419583D01*
X689752Y419249D01*
G01X691952Y417383D02*
X692419Y417849D01*
X692819Y418116D01*
X693352Y418249D01*
X693819Y418116D01*
X694152Y417849D01*
X694419Y417449D01*
X694486Y416983D01*
X694419Y416583D01*
X694152Y416183D01*
X693752Y415849D01*
X693286Y415716D01*
X692752Y415849D01*
X692286Y416249D01*
X692019Y416849D01*
X691952Y417516D01*
X692086Y418383D01*
X692286Y418849D01*
X692619Y419316D01*
X693086Y419649D01*
X693552Y419716D01*
X694019Y419583D01*
X694352Y419249D01*
G01X668860Y787481D02*
Y791481D01*
X666393Y788614D01*
X669727D01*
G01X671193Y788281D02*
X671593Y787814D01*
X672127Y787548D01*
X672727Y787481D01*
X673260Y787548D01*
X673793Y787881D01*
X674127Y788281D01*
X674193Y788681D01*
X674060Y789148D01*
X673593Y789481D01*
X673127Y789614D01*
X672527D01*
G01X673127D02*
X673527Y789814D01*
X673860Y790148D01*
X673993Y790548D01*
X673860Y790948D01*
X673527Y791281D01*
X672927Y791481D01*
X672327Y791414D01*
X671727Y791148D01*
G01X675793Y788281D02*
X676193Y787814D01*
X676727Y787548D01*
X677327Y787481D01*
X677860Y787548D01*
X678393Y787881D01*
X678727Y788281D01*
X678793Y788681D01*
X678660Y789148D01*
X678193Y789481D01*
X677727Y789614D01*
X677127D01*
G01X677727D02*
X678127Y789814D01*
X678460Y790148D01*
X678593Y790548D01*
X678460Y790948D01*
X678127Y791281D01*
X677527Y791481D01*
X676927Y791414D01*
X676327Y791148D01*
G01X681860Y787348D02*
X681727Y787414D01*
Y787548D01*
X681860Y787614D01*
X681993Y787548D01*
Y787414D01*
X681860Y787348D01*
G01X686460Y791481D02*
X685927Y791348D01*
X685527Y791014D01*
X685260Y790614D01*
X685060Y790081D01*
X684993Y789481D01*
X685060Y788881D01*
X685260Y788348D01*
X685527Y787948D01*
X685927Y787614D01*
X686460Y787481D01*
X686993Y787614D01*
X687393Y787948D01*
X687660Y788348D01*
X687860Y788881D01*
X687927Y789481D01*
X687860Y790081D01*
X687660Y790614D01*
X687393Y791014D01*
X686993Y791348D01*
X686460Y791481D01*
G01X691060Y787481D02*
X691527Y787548D01*
X692060Y787748D01*
X692393Y788081D01*
X692527Y788548D01*
X692393Y789014D01*
X691993Y789414D01*
X691393Y789614D01*
X690727D01*
X690327Y789748D01*
X689993Y790081D01*
X689860Y790548D01*
X690060Y791014D01*
X690527Y791348D01*
X691060Y791481D01*
X691593Y791348D01*
X692060Y791014D01*
X692260Y790548D01*
X692127Y790081D01*
X691793Y789748D01*
X691393Y789614D01*
X690727D01*
X690127Y789414D01*
X689727Y789014D01*
X689593Y788548D01*
X689727Y788081D01*
X690060Y787748D01*
X690593Y787548D01*
X691060Y787481D01*
G01X662397Y829638D02*
Y833638D01*
X663731D01*
X664264Y833438D01*
X664664Y833171D01*
X664997Y832771D01*
X665264Y832305D01*
X665331Y831638D01*
X665264Y830971D01*
X664997Y830505D01*
X664664Y830105D01*
X664264Y829838D01*
X663731Y829638D01*
X662397D01*
G01X667531D02*
Y832305D01*
G01Y831771D02*
X667864Y832038D01*
X668197Y832238D01*
X668664Y832305D01*
X668997Y832238D01*
X669397Y832038D01*
G01X673064Y832305D02*
Y829638D01*
G01Y833371D02*
X672931Y833438D01*
Y833571D01*
X673064Y833638D01*
X673197Y833571D01*
Y833438D01*
X673064Y833371D01*
G01X677664Y829638D02*
Y833638D01*
G01X682264Y829638D02*
Y833638D01*
G01X691064Y829638D02*
Y833038D01*
X691197Y833371D01*
X691464Y833571D01*
X691864Y833638D01*
X692264Y833505D01*
X692464Y833171D01*
G01X691664Y832038D02*
X690331D01*
G01X695064Y831438D02*
X697197D01*
X696997Y831905D01*
X696664Y832171D01*
X696197Y832305D01*
X695731Y832238D01*
X695331Y832038D01*
X695064Y831571D01*
X694931Y831171D01*
Y830771D01*
X695064Y830371D01*
X695397Y829971D01*
X695797Y829705D01*
X696264Y829638D01*
X696731Y829771D01*
X697197Y830171D01*
G01X701864Y829638D02*
Y832305D01*
G01Y831838D02*
X701597Y832105D01*
X701197Y832238D01*
X700731Y832305D01*
X700264Y832171D01*
X699864Y831905D01*
X699597Y831505D01*
X699464Y830971D01*
X699597Y830438D01*
X699864Y830038D01*
X700264Y829771D01*
X700731Y829638D01*
X701197Y829705D01*
X701597Y829905D01*
X701864Y830171D01*
G01X705264Y833638D02*
Y829638D01*
G01X704331Y832305D02*
X706197D01*
G01X708731D02*
Y830438D01*
X708997Y829971D01*
X709397Y829705D01*
X709864Y829638D01*
X710331Y829705D01*
X710731Y829971D01*
X710997Y830438D01*
G01Y829638D02*
Y832305D01*
G01X713531Y829638D02*
Y832305D01*
G01Y831771D02*
X713864Y832038D01*
X714197Y832238D01*
X714664Y832305D01*
X714997Y832238D01*
X715397Y832038D01*
G01X718064Y831438D02*
X720197D01*
X719997Y831905D01*
X719664Y832171D01*
X719197Y832305D01*
X718731Y832238D01*
X718331Y832038D01*
X718064Y831571D01*
X717931Y831171D01*
Y830771D01*
X718064Y830371D01*
X718397Y829971D01*
X718797Y829705D01*
X719264Y829638D01*
X719731Y829771D01*
X720197Y830171D01*
G01X668952Y871805D02*
X669352Y872205D01*
X669819Y872405D01*
X670352Y872472D01*
X671019Y872339D01*
X671486Y872005D01*
X671619Y871605D01*
X671552Y871205D01*
X671286Y870872D01*
X669952Y870205D01*
X669352Y869739D01*
X668952Y869072D01*
X668819Y868472D01*
X671619D01*
G01X674819Y872472D02*
X674286Y872339D01*
X673886Y872005D01*
X673619Y871605D01*
X673419Y871072D01*
X673352Y870472D01*
X673419Y869872D01*
X673619Y869339D01*
X673886Y868939D01*
X674286Y868605D01*
X674819Y868472D01*
X675352Y868605D01*
X675752Y868939D01*
X676019Y869339D01*
X676219Y869872D01*
X676286Y870472D01*
X676219Y871072D01*
X676019Y871605D01*
X675752Y872005D01*
X675352Y872339D01*
X674819Y872472D01*
G01X679419Y868472D02*
X679886Y868539D01*
X680419Y868739D01*
X680752Y869072D01*
X680886Y869539D01*
X680752Y870005D01*
X680352Y870405D01*
X679752Y870605D01*
X679086D01*
X678686Y870739D01*
X678352Y871072D01*
X678219Y871539D01*
X678419Y872005D01*
X678886Y872339D01*
X679419Y872472D01*
X679952Y872339D01*
X680419Y872005D01*
X680619Y871539D01*
X680486Y871072D01*
X680152Y870739D01*
X679752Y870605D01*
X679086D01*
X678486Y870405D01*
X678086Y870005D01*
X677952Y869539D01*
X678086Y869072D01*
X678419Y868739D01*
X678952Y868539D01*
X679419Y868472D01*
G01X684019Y868339D02*
X683886Y868405D01*
Y868539D01*
X684019Y868605D01*
X684152Y868539D01*
Y868405D01*
X684019Y868339D01*
G01X687352Y870139D02*
X687819Y870605D01*
X688219Y870872D01*
X688752Y871005D01*
X689219Y870872D01*
X689552Y870605D01*
X689819Y870205D01*
X689886Y869739D01*
X689819Y869339D01*
X689552Y868939D01*
X689152Y868605D01*
X688686Y868472D01*
X688152Y868605D01*
X687686Y869005D01*
X687419Y869605D01*
X687352Y870272D01*
X687486Y871139D01*
X687686Y871605D01*
X688019Y872072D01*
X688486Y872405D01*
X688952Y872472D01*
X689419Y872339D01*
X689752Y872005D01*
G01X691952Y870139D02*
X692419Y870605D01*
X692819Y870872D01*
X693352Y871005D01*
X693819Y870872D01*
X694152Y870605D01*
X694419Y870205D01*
X694486Y869739D01*
X694419Y869339D01*
X694152Y868939D01*
X693752Y868605D01*
X693286Y868472D01*
X692752Y868605D01*
X692286Y869005D01*
X692019Y869605D01*
X691952Y870272D01*
X692086Y871139D01*
X692286Y871605D01*
X692619Y872072D01*
X693086Y872405D01*
X693552Y872472D01*
X694019Y872339D01*
X694352Y872005D01*
G01X668860Y1240237D02*
Y1244237D01*
X666393Y1241370D01*
X669727D01*
G01X671193Y1241037D02*
X671593Y1240570D01*
X672127Y1240304D01*
X672727Y1240237D01*
X673260Y1240304D01*
X673793Y1240637D01*
X674127Y1241037D01*
X674193Y1241437D01*
X674060Y1241904D01*
X673593Y1242237D01*
X673127Y1242370D01*
X672527D01*
G01X673127D02*
X673527Y1242570D01*
X673860Y1242904D01*
X673993Y1243304D01*
X673860Y1243704D01*
X673527Y1244037D01*
X672927Y1244237D01*
X672327Y1244170D01*
X671727Y1243904D01*
G01X675793Y1241037D02*
X676193Y1240570D01*
X676727Y1240304D01*
X677327Y1240237D01*
X677860Y1240304D01*
X678393Y1240637D01*
X678727Y1241037D01*
X678793Y1241437D01*
X678660Y1241904D01*
X678193Y1242237D01*
X677727Y1242370D01*
X677127D01*
G01X677727D02*
X678127Y1242570D01*
X678460Y1242904D01*
X678593Y1243304D01*
X678460Y1243704D01*
X678127Y1244037D01*
X677527Y1244237D01*
X676927Y1244170D01*
X676327Y1243904D01*
G01X681860Y1240104D02*
X681727Y1240170D01*
Y1240304D01*
X681860Y1240370D01*
X681993Y1240304D01*
Y1240170D01*
X681860Y1240104D01*
G01X686460Y1244237D02*
X685927Y1244104D01*
X685527Y1243770D01*
X685260Y1243370D01*
X685060Y1242837D01*
X684993Y1242237D01*
X685060Y1241637D01*
X685260Y1241104D01*
X685527Y1240704D01*
X685927Y1240370D01*
X686460Y1240237D01*
X686993Y1240370D01*
X687393Y1240704D01*
X687660Y1241104D01*
X687860Y1241637D01*
X687927Y1242237D01*
X687860Y1242837D01*
X687660Y1243370D01*
X687393Y1243770D01*
X686993Y1244104D01*
X686460Y1244237D01*
G01X691060Y1240237D02*
X691527Y1240304D01*
X692060Y1240504D01*
X692393Y1240837D01*
X692527Y1241304D01*
X692393Y1241770D01*
X691993Y1242170D01*
X691393Y1242370D01*
X690727D01*
X690327Y1242504D01*
X689993Y1242837D01*
X689860Y1243304D01*
X690060Y1243770D01*
X690527Y1244104D01*
X691060Y1244237D01*
X691593Y1244104D01*
X692060Y1243770D01*
X692260Y1243304D01*
X692127Y1242837D01*
X691793Y1242504D01*
X691393Y1242370D01*
X690727D01*
X690127Y1242170D01*
X689727Y1241770D01*
X689593Y1241304D01*
X689727Y1240837D01*
X690060Y1240504D01*
X690593Y1240304D01*
X691060Y1240237D01*
G01X668952Y1324561D02*
X669352Y1324961D01*
X669819Y1325161D01*
X670352Y1325228D01*
X671019Y1325095D01*
X671486Y1324761D01*
X671619Y1324361D01*
X671552Y1323961D01*
X671286Y1323628D01*
X669952Y1322961D01*
X669352Y1322495D01*
X668952Y1321828D01*
X668819Y1321228D01*
X671619D01*
G01X674819Y1325228D02*
X674286Y1325095D01*
X673886Y1324761D01*
X673619Y1324361D01*
X673419Y1323828D01*
X673352Y1323228D01*
X673419Y1322628D01*
X673619Y1322095D01*
X673886Y1321695D01*
X674286Y1321361D01*
X674819Y1321228D01*
X675352Y1321361D01*
X675752Y1321695D01*
X676019Y1322095D01*
X676219Y1322628D01*
X676286Y1323228D01*
X676219Y1323828D01*
X676019Y1324361D01*
X675752Y1324761D01*
X675352Y1325095D01*
X674819Y1325228D01*
G01X679419Y1321228D02*
X679886Y1321295D01*
X680419Y1321495D01*
X680752Y1321828D01*
X680886Y1322295D01*
X680752Y1322761D01*
X680352Y1323161D01*
X679752Y1323361D01*
X679086D01*
X678686Y1323495D01*
X678352Y1323828D01*
X678219Y1324295D01*
X678419Y1324761D01*
X678886Y1325095D01*
X679419Y1325228D01*
X679952Y1325095D01*
X680419Y1324761D01*
X680619Y1324295D01*
X680486Y1323828D01*
X680152Y1323495D01*
X679752Y1323361D01*
X679086D01*
X678486Y1323161D01*
X678086Y1322761D01*
X677952Y1322295D01*
X678086Y1321828D01*
X678419Y1321495D01*
X678952Y1321295D01*
X679419Y1321228D01*
G01X684019Y1321095D02*
X683886Y1321161D01*
Y1321295D01*
X684019Y1321361D01*
X684152Y1321295D01*
Y1321161D01*
X684019Y1321095D01*
G01X687352Y1322895D02*
X687819Y1323361D01*
X688219Y1323628D01*
X688752Y1323761D01*
X689219Y1323628D01*
X689552Y1323361D01*
X689819Y1322961D01*
X689886Y1322495D01*
X689819Y1322095D01*
X689552Y1321695D01*
X689152Y1321361D01*
X688686Y1321228D01*
X688152Y1321361D01*
X687686Y1321761D01*
X687419Y1322361D01*
X687352Y1323028D01*
X687486Y1323895D01*
X687686Y1324361D01*
X688019Y1324828D01*
X688486Y1325161D01*
X688952Y1325228D01*
X689419Y1325095D01*
X689752Y1324761D01*
G01X691952Y1322895D02*
X692419Y1323361D01*
X692819Y1323628D01*
X693352Y1323761D01*
X693819Y1323628D01*
X694152Y1323361D01*
X694419Y1322961D01*
X694486Y1322495D01*
X694419Y1322095D01*
X694152Y1321695D01*
X693752Y1321361D01*
X693286Y1321228D01*
X692752Y1321361D01*
X692286Y1321761D01*
X692019Y1322361D01*
X691952Y1323028D01*
X692086Y1323895D01*
X692286Y1324361D01*
X692619Y1324828D01*
X693086Y1325161D01*
X693552Y1325228D01*
X694019Y1325095D01*
X694352Y1324761D01*
G01X662397Y1282394D02*
Y1286394D01*
X663731D01*
X664264Y1286194D01*
X664664Y1285927D01*
X664997Y1285527D01*
X665264Y1285061D01*
X665331Y1284394D01*
X665264Y1283727D01*
X664997Y1283261D01*
X664664Y1282861D01*
X664264Y1282594D01*
X663731Y1282394D01*
X662397D01*
G01X667531D02*
Y1285061D01*
G01Y1284527D02*
X667864Y1284794D01*
X668197Y1284994D01*
X668664Y1285061D01*
X668997Y1284994D01*
X669397Y1284794D01*
G01X673064Y1285061D02*
Y1282394D01*
G01Y1286127D02*
X672931Y1286194D01*
Y1286327D01*
X673064Y1286394D01*
X673197Y1286327D01*
Y1286194D01*
X673064Y1286127D01*
G01X677664Y1282394D02*
Y1286394D01*
G01X682264Y1282394D02*
Y1286394D01*
G01X691064Y1282394D02*
Y1285794D01*
X691197Y1286127D01*
X691464Y1286327D01*
X691864Y1286394D01*
X692264Y1286261D01*
X692464Y1285927D01*
G01X691664Y1284794D02*
X690331D01*
G01X695064Y1284194D02*
X697197D01*
X696997Y1284661D01*
X696664Y1284927D01*
X696197Y1285061D01*
X695731Y1284994D01*
X695331Y1284794D01*
X695064Y1284327D01*
X694931Y1283927D01*
Y1283527D01*
X695064Y1283127D01*
X695397Y1282727D01*
X695797Y1282461D01*
X696264Y1282394D01*
X696731Y1282527D01*
X697197Y1282927D01*
G01X701864Y1282394D02*
Y1285061D01*
G01Y1284594D02*
X701597Y1284861D01*
X701197Y1284994D01*
X700731Y1285061D01*
X700264Y1284927D01*
X699864Y1284661D01*
X699597Y1284261D01*
X699464Y1283727D01*
X699597Y1283194D01*
X699864Y1282794D01*
X700264Y1282527D01*
X700731Y1282394D01*
X701197Y1282461D01*
X701597Y1282661D01*
X701864Y1282927D01*
G01X705264Y1286394D02*
Y1282394D01*
G01X704331Y1285061D02*
X706197D01*
G01X708731D02*
Y1283194D01*
X708997Y1282727D01*
X709397Y1282461D01*
X709864Y1282394D01*
X710331Y1282461D01*
X710731Y1282727D01*
X710997Y1283194D01*
G01Y1282394D02*
Y1285061D01*
G01X713531Y1282394D02*
Y1285061D01*
G01Y1284527D02*
X713864Y1284794D01*
X714197Y1284994D01*
X714664Y1285061D01*
X714997Y1284994D01*
X715397Y1284794D01*
G01X718064Y1284194D02*
X720197D01*
X719997Y1284661D01*
X719664Y1284927D01*
X719197Y1285061D01*
X718731Y1284994D01*
X718331Y1284794D01*
X718064Y1284327D01*
X717931Y1283927D01*
Y1283527D01*
X718064Y1283127D01*
X718397Y1282727D01*
X718797Y1282461D01*
X719264Y1282394D01*
X719731Y1282527D01*
X720197Y1282927D01*
G01X692520Y1374803D02*
G03Y1382677I0J3937D01*
G01Y1374803D02*
G03Y1382677I0J3937D01*
G01X720020Y253622D02*
X720420Y253289D01*
X720887Y253089D01*
X721487Y253022D01*
X722087Y253155D01*
X722554Y253422D01*
X722887Y253889D01*
X722954Y254422D01*
X722820Y254955D01*
X722487Y255289D01*
X722020Y255555D01*
X721554Y255622D01*
X721087Y255555D01*
X720487Y255289D01*
X720687Y257022D01*
X722487D01*
G01X724620Y253622D02*
X725020Y253289D01*
X725487Y253089D01*
X726087Y253022D01*
X726687Y253155D01*
X727154Y253422D01*
X727487Y253889D01*
X727554Y254422D01*
X727420Y254955D01*
X727087Y255289D01*
X726620Y255555D01*
X726154Y255622D01*
X725687Y255555D01*
X725087Y255289D01*
X725287Y257022D01*
X727087D01*
G01X730554Y253022D02*
X730687Y253889D01*
X730887Y254622D01*
X731154Y255289D01*
X731487Y256022D01*
X732020Y257022D01*
X729354D01*
G01X735287Y252889D02*
X735154Y252955D01*
Y253089D01*
X735287Y253155D01*
X735420Y253089D01*
Y252955D01*
X735287Y252889D01*
G01X739887Y257022D02*
X739354Y256889D01*
X738954Y256555D01*
X738687Y256155D01*
X738487Y255622D01*
X738420Y255022D01*
X738487Y254422D01*
X738687Y253889D01*
X738954Y253489D01*
X739354Y253155D01*
X739887Y253022D01*
X740420Y253155D01*
X740820Y253489D01*
X741087Y253889D01*
X741287Y254422D01*
X741354Y255022D01*
X741287Y255622D01*
X741087Y256155D01*
X740820Y256555D01*
X740420Y256889D01*
X739887Y257022D01*
G01X743354Y253489D02*
X743820Y253155D01*
X744354Y253022D01*
X744887Y253155D01*
X745354Y253555D01*
X745687Y254155D01*
X745820Y254755D01*
Y255489D01*
X745687Y256089D01*
X745354Y256622D01*
X744954Y256889D01*
X744487Y257022D01*
X743954Y256889D01*
X743554Y256622D01*
X743287Y256222D01*
X743154Y255689D01*
X743287Y255222D01*
X743620Y254755D01*
X744020Y254489D01*
X744487Y254422D01*
X745020Y254555D01*
X745420Y254889D01*
X745820Y255489D01*
G01X737359Y264168D02*
X737759Y264568D01*
X738226Y264768D01*
X738759Y264835D01*
X739426Y264702D01*
X739893Y264368D01*
X740026Y263968D01*
X739959Y263568D01*
X739693Y263235D01*
X738359Y262568D01*
X737759Y262102D01*
X737359Y261435D01*
X737226Y260835D01*
X740026D01*
G01X741759Y261635D02*
X742159Y261168D01*
X742693Y260902D01*
X743293Y260835D01*
X743826Y260902D01*
X744359Y261235D01*
X744693Y261635D01*
X744759Y262035D01*
X744626Y262502D01*
X744159Y262835D01*
X743693Y262968D01*
X743093D01*
G01X743693D02*
X744093Y263168D01*
X744426Y263502D01*
X744559Y263902D01*
X744426Y264302D01*
X744093Y264635D01*
X743493Y264835D01*
X742893Y264768D01*
X742293Y264502D01*
G01X746559Y262502D02*
X747026Y262968D01*
X747426Y263235D01*
X747959Y263368D01*
X748426Y263235D01*
X748759Y262968D01*
X749026Y262568D01*
X749093Y262102D01*
X749026Y261702D01*
X748759Y261302D01*
X748359Y260968D01*
X747893Y260835D01*
X747359Y260968D01*
X746893Y261368D01*
X746626Y261968D01*
X746559Y262635D01*
X746693Y263502D01*
X746893Y263968D01*
X747226Y264435D01*
X747693Y264768D01*
X748159Y264835D01*
X748626Y264702D01*
X748959Y264368D01*
G01X752426Y260702D02*
X752293Y260768D01*
Y260902D01*
X752426Y260968D01*
X752559Y260902D01*
Y260768D01*
X752426Y260702D01*
G01X755759Y264168D02*
X756159Y264568D01*
X756626Y264768D01*
X757159Y264835D01*
X757826Y264702D01*
X758293Y264368D01*
X758426Y263968D01*
X758359Y263568D01*
X758093Y263235D01*
X756759Y262568D01*
X756159Y262102D01*
X755759Y261435D01*
X755626Y260835D01*
X758426D01*
G01X760359Y264168D02*
X760759Y264568D01*
X761226Y264768D01*
X761759Y264835D01*
X762426Y264702D01*
X762893Y264368D01*
X763026Y263968D01*
X762959Y263568D01*
X762693Y263235D01*
X761359Y262568D01*
X760759Y262102D01*
X760359Y261435D01*
X760226Y260835D01*
X763026D01*
G01X720020Y726063D02*
X720420Y725730D01*
X720887Y725530D01*
X721487Y725463D01*
X722087Y725596D01*
X722554Y725863D01*
X722887Y726330D01*
X722954Y726863D01*
X722820Y727396D01*
X722487Y727730D01*
X722020Y727996D01*
X721554Y728063D01*
X721087Y727996D01*
X720487Y727730D01*
X720687Y729463D01*
X722487D01*
G01X724620Y726063D02*
X725020Y725730D01*
X725487Y725530D01*
X726087Y725463D01*
X726687Y725596D01*
X727154Y725863D01*
X727487Y726330D01*
X727554Y726863D01*
X727420Y727396D01*
X727087Y727730D01*
X726620Y727996D01*
X726154Y728063D01*
X725687Y727996D01*
X725087Y727730D01*
X725287Y729463D01*
X727087D01*
G01X730554Y725463D02*
X730687Y726330D01*
X730887Y727063D01*
X731154Y727730D01*
X731487Y728463D01*
X732020Y729463D01*
X729354D01*
G01X735287Y725330D02*
X735154Y725396D01*
Y725530D01*
X735287Y725596D01*
X735420Y725530D01*
Y725396D01*
X735287Y725330D01*
G01X739887Y729463D02*
X739354Y729330D01*
X738954Y728996D01*
X738687Y728596D01*
X738487Y728063D01*
X738420Y727463D01*
X738487Y726863D01*
X738687Y726330D01*
X738954Y725930D01*
X739354Y725596D01*
X739887Y725463D01*
X740420Y725596D01*
X740820Y725930D01*
X741087Y726330D01*
X741287Y726863D01*
X741354Y727463D01*
X741287Y728063D01*
X741087Y728596D01*
X740820Y728996D01*
X740420Y729330D01*
X739887Y729463D01*
G01X743354Y725930D02*
X743820Y725596D01*
X744354Y725463D01*
X744887Y725596D01*
X745354Y725996D01*
X745687Y726596D01*
X745820Y727196D01*
Y727930D01*
X745687Y728530D01*
X745354Y729063D01*
X744954Y729330D01*
X744487Y729463D01*
X743954Y729330D01*
X743554Y729063D01*
X743287Y728663D01*
X743154Y728130D01*
X743287Y727663D01*
X743620Y727196D01*
X744020Y726930D01*
X744487Y726863D01*
X745020Y726996D01*
X745420Y727330D01*
X745820Y727930D01*
G01X737359Y736609D02*
X737759Y737009D01*
X738226Y737209D01*
X738759Y737276D01*
X739426Y737143D01*
X739893Y736809D01*
X740026Y736409D01*
X739959Y736009D01*
X739693Y735676D01*
X738359Y735009D01*
X737759Y734543D01*
X737359Y733876D01*
X737226Y733276D01*
X740026D01*
G01X741759Y734076D02*
X742159Y733609D01*
X742693Y733343D01*
X743293Y733276D01*
X743826Y733343D01*
X744359Y733676D01*
X744693Y734076D01*
X744759Y734476D01*
X744626Y734943D01*
X744159Y735276D01*
X743693Y735409D01*
X743093D01*
G01X743693D02*
X744093Y735609D01*
X744426Y735943D01*
X744559Y736343D01*
X744426Y736743D01*
X744093Y737076D01*
X743493Y737276D01*
X742893Y737209D01*
X742293Y736943D01*
G01X746559Y734943D02*
X747026Y735409D01*
X747426Y735676D01*
X747959Y735809D01*
X748426Y735676D01*
X748759Y735409D01*
X749026Y735009D01*
X749093Y734543D01*
X749026Y734143D01*
X748759Y733743D01*
X748359Y733409D01*
X747893Y733276D01*
X747359Y733409D01*
X746893Y733809D01*
X746626Y734409D01*
X746559Y735076D01*
X746693Y735943D01*
X746893Y736409D01*
X747226Y736876D01*
X747693Y737209D01*
X748159Y737276D01*
X748626Y737143D01*
X748959Y736809D01*
G01X752426Y733143D02*
X752293Y733209D01*
Y733343D01*
X752426Y733409D01*
X752559Y733343D01*
Y733209D01*
X752426Y733143D01*
G01X755759Y736609D02*
X756159Y737009D01*
X756626Y737209D01*
X757159Y737276D01*
X757826Y737143D01*
X758293Y736809D01*
X758426Y736409D01*
X758359Y736009D01*
X758093Y735676D01*
X756759Y735009D01*
X756159Y734543D01*
X755759Y733876D01*
X755626Y733276D01*
X758426D01*
G01X760359Y736609D02*
X760759Y737009D01*
X761226Y737209D01*
X761759Y737276D01*
X762426Y737143D01*
X762893Y736809D01*
X763026Y736409D01*
X762959Y736009D01*
X762693Y735676D01*
X761359Y735009D01*
X760759Y734543D01*
X760359Y733876D01*
X760226Y733276D01*
X763026D01*
G01X746850Y1374803D02*
G03X750787Y1378740I0J3937D01*
G01X746850Y1374803D02*
G03X750787Y1378740I0J3937D01*
G01X723228Y1382677D02*
G03Y1374803I0J-3937D01*
G01Y1382677D02*
X742913D01*
G01X723228D02*
X742913D01*
G01X723228D02*
G03Y1374803I0J-3937D01*
G01X742913Y1464567D02*
Y1382677D01*
G01Y1464567D02*
Y1382677D01*
G01X754724Y1476378D02*
G03X742913Y1464567I0J-11811D01*
G01X754724Y1476378D02*
G03X742913Y1464567I0J-11811D01*
G01X862205Y-7874D02*
X791339D01*
G01X787402Y-3937D02*
G03X791339Y-7874I3937J0D01*
G01X787402Y-3937D02*
G03X791339Y-7874I3937J0D01*
G01D02*
X862205D01*
G01X858268Y-15748D02*
X791339D01*
G01X858268D02*
X791339D01*
G01X787402Y-3937D02*
G03X783465Y0I-3937J0D01*
G01X787402Y-3937D02*
G03X783465Y0I-3937J0D01*
G01X780203Y-7874D02*
G03X791339Y-15748I11136J3937D01*
G01X780203Y-7874D02*
G03X791339Y-15748I11136J3937D01*
G01X779551Y264712D02*
G03X813362I16905J-13531D01*
G01X779551D02*
G03X813362I16905J-13531D01*
G01X779551D02*
G03X786476Y277843I-30737J24601D01*
G01X806437D02*
G03X786476I-9981J-3040D01*
G01X779551Y264712D02*
G03X786476Y277843I-30737J24602D01*
G01X806437D02*
G03X786476I-9981J-3040D01*
G01X779551Y737153D02*
G03X786476Y750284I-30737J24601D01*
G01X779551Y737154D02*
G03X786476Y750284I-30736J24602D01*
G01X779551Y737153D02*
G03X813362I16905J-13531D01*
G01X779551D02*
G03X813362I16905J-13531D01*
G01X806437Y750284D02*
G03X786476I-9981J-3040D01*
G01X806437D02*
G03X786476I-9981J-3040D01*
G01X750787Y1464567D02*
Y1378740D01*
G01Y1464567D02*
Y1378740D01*
G01X783465Y1468504D02*
G03X787402Y1472441I0J3937D01*
G01X783465Y1468504D02*
G03X787402Y1472441I0J3937D01*
G01X783465Y1468504D02*
X754724D01*
G01D02*
G03X750787Y1464567I0J-3937D01*
G01X783465Y1468504D02*
X754724D01*
G01D02*
G03X750787Y1464567I0J-3937D01*
G01X779528Y1476378D02*
X754724D01*
G01X779528D02*
X754724D01*
G01X787402Y1654331D02*
Y1472441D01*
G01X779528Y1596063D02*
Y1476378D01*
G01X787402Y1654331D02*
Y1472441D01*
G01X779528Y1596063D02*
Y1476378D01*
G01X762339Y1574994D02*
Y1578994D01*
X763939D01*
X764472Y1578794D01*
X764872Y1578327D01*
X765005Y1577794D01*
X764872Y1577261D01*
X764539Y1576861D01*
X763939Y1576661D01*
X762339D01*
G01X767339Y1574994D02*
Y1577661D01*
G01Y1577127D02*
X767672Y1577394D01*
X768005Y1577594D01*
X768472Y1577661D01*
X768805Y1577594D01*
X769205Y1577394D01*
G01X771872Y1576794D02*
X774005D01*
X773805Y1577261D01*
X773472Y1577527D01*
X773005Y1577661D01*
X772539Y1577594D01*
X772139Y1577394D01*
X771872Y1576927D01*
X771739Y1576527D01*
Y1576127D01*
X771872Y1575727D01*
X772205Y1575327D01*
X772605Y1575061D01*
X773072Y1574994D01*
X773539Y1575127D01*
X774005Y1575527D01*
G01X776472Y1575461D02*
X776805Y1575194D01*
X777272Y1574994D01*
X777672D01*
X778072Y1575127D01*
X778339Y1575327D01*
X778472Y1575594D01*
X778405Y1575994D01*
X778139Y1576194D01*
X776939Y1576594D01*
X776672Y1577061D01*
X776805Y1577394D01*
X777072Y1577594D01*
X777472Y1577661D01*
X777872Y1577594D01*
X778272Y1577394D01*
G01X781072Y1575461D02*
X781405Y1575194D01*
X781872Y1574994D01*
X782272D01*
X782672Y1575127D01*
X782939Y1575327D01*
X783072Y1575594D01*
X783005Y1575994D01*
X782739Y1576194D01*
X781539Y1576594D01*
X781272Y1577061D01*
X781405Y1577394D01*
X781672Y1577594D01*
X782072Y1577661D01*
X782472Y1577594D01*
X782872Y1577394D01*
G01X785805Y1576327D02*
X787539D01*
G01X790872Y1574994D02*
Y1578394D01*
X791005Y1578727D01*
X791272Y1578927D01*
X791672Y1578994D01*
X792072Y1578861D01*
X792272Y1578527D01*
G01X791472Y1577394D02*
X790139D01*
G01X795872Y1577661D02*
Y1574994D01*
G01Y1578727D02*
X795739Y1578794D01*
Y1578927D01*
X795872Y1578994D01*
X796005Y1578927D01*
Y1578794D01*
X795872Y1578727D01*
G01X800472Y1578994D02*
Y1574994D01*
G01X799539Y1577661D02*
X801405D01*
G01X808339Y1574994D02*
Y1578994D01*
X809939D01*
X810472Y1578794D01*
X810872Y1578327D01*
X811005Y1577794D01*
X810872Y1577261D01*
X810539Y1576861D01*
X809939Y1576661D01*
X808339D01*
G01X814272Y1578994D02*
Y1574994D01*
G01X812739Y1578994D02*
X815805D01*
G01X817472Y1574994D02*
Y1578994D01*
G01X820272D02*
Y1574994D01*
G01Y1576994D02*
X817472D01*
G01X826939Y1574994D02*
Y1578994D01*
G01X829072Y1577661D02*
X826939Y1576127D01*
G01X827805Y1576727D02*
X829205Y1574994D01*
G01X831672Y1576794D02*
X833805D01*
X833605Y1577261D01*
X833272Y1577527D01*
X832805Y1577661D01*
X832339Y1577594D01*
X831939Y1577394D01*
X831672Y1576927D01*
X831539Y1576527D01*
Y1576127D01*
X831672Y1575727D01*
X832005Y1575327D01*
X832405Y1575061D01*
X832872Y1574994D01*
X833339Y1575127D01*
X833805Y1575527D01*
G01X836272Y1576794D02*
X838405D01*
X838205Y1577261D01*
X837872Y1577527D01*
X837405Y1577661D01*
X836939Y1577594D01*
X836539Y1577394D01*
X836272Y1576927D01*
X836139Y1576527D01*
Y1576127D01*
X836272Y1575727D01*
X836605Y1575327D01*
X837005Y1575061D01*
X837472Y1574994D01*
X837939Y1575127D01*
X838405Y1575527D01*
G01X840672Y1573661D02*
Y1577661D01*
G01Y1577061D02*
X841005Y1577394D01*
X841339Y1577594D01*
X841872Y1577661D01*
X842339Y1577594D01*
X842805Y1577261D01*
X843005Y1576794D01*
X843072Y1576327D01*
X843005Y1575861D01*
X842805Y1575394D01*
X842405Y1575127D01*
X841872Y1574994D01*
X841405Y1575061D01*
X840939Y1575261D01*
X840672Y1575527D01*
G01X849939Y1574994D02*
Y1578994D01*
G01Y1577061D02*
X850272Y1577394D01*
X850605Y1577594D01*
X851139Y1577661D01*
X851539Y1577594D01*
X852005Y1577327D01*
X852205Y1576927D01*
Y1574994D01*
G01X855672D02*
X855272Y1575061D01*
X854872Y1575327D01*
X854605Y1575794D01*
X854472Y1576327D01*
X854605Y1576861D01*
X854872Y1577327D01*
X855272Y1577594D01*
X855672Y1577661D01*
X856072Y1577594D01*
X856472Y1577327D01*
X856739Y1576861D01*
X856805Y1576327D01*
X856739Y1575794D01*
X856472Y1575327D01*
X856072Y1575061D01*
X855672Y1574994D01*
G01X860272D02*
Y1578994D01*
G01X863872Y1576794D02*
X866005D01*
X865805Y1577261D01*
X865472Y1577527D01*
X865005Y1577661D01*
X864539Y1577594D01*
X864139Y1577394D01*
X863872Y1576927D01*
X863739Y1576527D01*
Y1576127D01*
X863872Y1575727D01*
X864205Y1575327D01*
X864605Y1575061D01*
X865072Y1574994D01*
X865539Y1575127D01*
X866005Y1575527D01*
G01X873072Y1575461D02*
X873405Y1575194D01*
X873872Y1574994D01*
X874272D01*
X874672Y1575127D01*
X874939Y1575327D01*
X875072Y1575594D01*
X875005Y1575994D01*
X874739Y1576194D01*
X873539Y1576594D01*
X873272Y1577061D01*
X873405Y1577394D01*
X873672Y1577594D01*
X874072Y1577661D01*
X874472Y1577594D01*
X874872Y1577394D01*
G01X878672Y1577661D02*
Y1574994D01*
G01Y1578727D02*
X878539Y1578794D01*
Y1578927D01*
X878672Y1578994D01*
X878805Y1578927D01*
Y1578794D01*
X878672Y1578727D01*
G01X882272Y1577661D02*
X884272D01*
X882272Y1574994D01*
X884272D01*
G01X886872Y1576794D02*
X889005D01*
X888805Y1577261D01*
X888472Y1577527D01*
X888005Y1577661D01*
X887539Y1577594D01*
X887139Y1577394D01*
X886872Y1576927D01*
X886739Y1576527D01*
Y1576127D01*
X886872Y1575727D01*
X887205Y1575327D01*
X887605Y1575061D01*
X888072Y1574994D01*
X888539Y1575127D01*
X889005Y1575527D01*
G01X897072Y1578994D02*
Y1574994D01*
G01X896139Y1577661D02*
X898005D01*
G01X901672Y1574994D02*
X901272Y1575061D01*
X900872Y1575327D01*
X900605Y1575794D01*
X900472Y1576327D01*
X900605Y1576861D01*
X900872Y1577327D01*
X901272Y1577594D01*
X901672Y1577661D01*
X902072Y1577594D01*
X902472Y1577327D01*
X902739Y1576861D01*
X902805Y1576327D01*
X902739Y1575794D01*
X902472Y1575327D01*
X902072Y1575061D01*
X901672Y1574994D01*
G01X906272D02*
Y1578994D01*
G01X909872Y1576794D02*
X912005D01*
X911805Y1577261D01*
X911472Y1577527D01*
X911005Y1577661D01*
X910539Y1577594D01*
X910139Y1577394D01*
X909872Y1576927D01*
X909739Y1576527D01*
Y1576127D01*
X909872Y1575727D01*
X910205Y1575327D01*
X910605Y1575061D01*
X911072Y1574994D01*
X911539Y1575127D01*
X912005Y1575527D01*
G01X914539Y1574994D02*
Y1577661D01*
G01Y1577127D02*
X914872Y1577394D01*
X915205Y1577594D01*
X915672Y1577661D01*
X916005Y1577594D01*
X916405Y1577394D01*
G01X921272Y1574994D02*
Y1577661D01*
G01Y1577194D02*
X921005Y1577461D01*
X920605Y1577594D01*
X920139Y1577661D01*
X919672Y1577527D01*
X919272Y1577261D01*
X919005Y1576861D01*
X918872Y1576327D01*
X919005Y1575794D01*
X919272Y1575394D01*
X919672Y1575127D01*
X920139Y1574994D01*
X920605Y1575061D01*
X921005Y1575261D01*
X921272Y1575527D01*
G01X923539Y1574994D02*
Y1577661D01*
G01Y1576994D02*
X923805Y1577327D01*
X924205Y1577594D01*
X924739Y1577661D01*
X925205Y1577594D01*
X925605Y1577327D01*
X925805Y1576861D01*
Y1574994D01*
G01X930339Y1577327D02*
X929872Y1577594D01*
X929472Y1577661D01*
X928939Y1577527D01*
X928539Y1577261D01*
X928272Y1576794D01*
X928205Y1576327D01*
X928272Y1575861D01*
X928539Y1575461D01*
X928939Y1575127D01*
X929472Y1574994D01*
X929939Y1575127D01*
X930339Y1575394D01*
G01X932872Y1576794D02*
X935005D01*
X934805Y1577261D01*
X934472Y1577527D01*
X934005Y1577661D01*
X933539Y1577594D01*
X933139Y1577394D01*
X932872Y1576927D01*
X932739Y1576527D01*
Y1576127D01*
X932872Y1575727D01*
X933205Y1575327D01*
X933605Y1575061D01*
X934072Y1574994D01*
X934539Y1575127D01*
X935005Y1575527D01*
G01X942339Y1576327D02*
X943939D01*
G01X943072Y1577194D02*
Y1575461D01*
G01X946472Y1574861D02*
X948872Y1578994D01*
G01X951405Y1576327D02*
X953139D01*
G01X955605Y1578327D02*
X956005Y1578727D01*
X956472Y1578927D01*
X957005Y1578994D01*
X957672Y1578861D01*
X958139Y1578527D01*
X958272Y1578127D01*
X958205Y1577727D01*
X957939Y1577394D01*
X956605Y1576727D01*
X956005Y1576261D01*
X955605Y1575594D01*
X955472Y1574994D01*
X958272D01*
G01X964072D02*
Y1577661D01*
G01Y1576927D02*
X964272Y1577261D01*
X964605Y1577527D01*
X965072Y1577661D01*
X965539Y1577527D01*
X965872Y1577261D01*
X966072Y1576927D01*
Y1574994D01*
G01Y1576927D02*
X966272Y1577261D01*
X966605Y1577527D01*
X967072Y1577661D01*
X967539Y1577527D01*
X967872Y1577261D01*
X968072Y1576861D01*
Y1574994D01*
G01X970672Y1577661D02*
Y1574994D01*
G01Y1578727D02*
X970539Y1578794D01*
Y1578927D01*
X970672Y1578994D01*
X970805Y1578927D01*
Y1578794D01*
X970672Y1578727D01*
G01X975272Y1574994D02*
Y1578994D01*
G01X978872Y1575461D02*
X979205Y1575194D01*
X979672Y1574994D01*
X980072D01*
X980472Y1575127D01*
X980739Y1575327D01*
X980872Y1575594D01*
X980805Y1575994D01*
X980539Y1576194D01*
X979339Y1576594D01*
X979072Y1577061D01*
X979205Y1577394D01*
X979472Y1577594D01*
X979872Y1577661D01*
X980272Y1577594D01*
X980672Y1577394D01*
G01X787402Y1596063D02*
G03X779528I-3937J0D01*
G01X787402D02*
G03X779528I-3937J0D01*
G01X796772Y1658268D02*
X942772D01*
G01X1216535D02*
X791339D01*
G01D02*
G03X787402Y1654331I0J-3937D01*
G01X779528D02*
G03X775591Y1658268I-3937J0D01*
G01X1216535D02*
X791339D01*
G01D02*
G03X787402Y1654331I0J-3937D01*
G01X779528D02*
G03X775591Y1658268I-3937J0D01*
G01X779528Y1654331D02*
Y1626772D01*
G01D02*
G03X787402I3937J0D01*
G01X779528Y1654331D02*
Y1626772D01*
G01D02*
G03X787402I3937J0D01*
G01X838054Y220574D02*
Y224574D01*
X835587Y221707D01*
X838921D01*
G01X840387Y221374D02*
X840787Y220907D01*
X841321Y220641D01*
X841921Y220574D01*
X842454Y220641D01*
X842987Y220974D01*
X843321Y221374D01*
X843387Y221774D01*
X843254Y222241D01*
X842787Y222574D01*
X842321Y222707D01*
X841721D01*
G01X842321D02*
X842721Y222907D01*
X843054Y223241D01*
X843187Y223641D01*
X843054Y224041D01*
X842721Y224374D01*
X842121Y224574D01*
X841521Y224507D01*
X840921Y224241D01*
G01X844987Y221374D02*
X845387Y220907D01*
X845921Y220641D01*
X846521Y220574D01*
X847054Y220641D01*
X847587Y220974D01*
X847921Y221374D01*
X847987Y221774D01*
X847854Y222241D01*
X847387Y222574D01*
X846921Y222707D01*
X846321D01*
G01X846921D02*
X847321Y222907D01*
X847654Y223241D01*
X847787Y223641D01*
X847654Y224041D01*
X847321Y224374D01*
X846721Y224574D01*
X846121Y224507D01*
X845521Y224241D01*
G01X851054Y220441D02*
X850921Y220507D01*
Y220641D01*
X851054Y220707D01*
X851187Y220641D01*
Y220507D01*
X851054Y220441D01*
G01X855654Y224574D02*
X855121Y224441D01*
X854721Y224107D01*
X854454Y223707D01*
X854254Y223174D01*
X854187Y222574D01*
X854254Y221974D01*
X854454Y221441D01*
X854721Y221041D01*
X855121Y220707D01*
X855654Y220574D01*
X856187Y220707D01*
X856587Y221041D01*
X856854Y221441D01*
X857054Y221974D01*
X857121Y222574D01*
X857054Y223174D01*
X856854Y223707D01*
X856587Y224107D01*
X856187Y224441D01*
X855654Y224574D01*
G01X860254Y220574D02*
X860721Y220641D01*
X861254Y220841D01*
X861587Y221174D01*
X861721Y221641D01*
X861587Y222107D01*
X861187Y222507D01*
X860587Y222707D01*
X859921D01*
X859521Y222841D01*
X859187Y223174D01*
X859054Y223641D01*
X859254Y224107D01*
X859721Y224441D01*
X860254Y224574D01*
X860787Y224441D01*
X861254Y224107D01*
X861454Y223641D01*
X861321Y223174D01*
X860987Y222841D01*
X860587Y222707D01*
X859921D01*
X859321Y222507D01*
X858921Y222107D01*
X858787Y221641D01*
X858921Y221174D01*
X859254Y220841D01*
X859787Y220641D01*
X860254Y220574D01*
G01X838146Y304898D02*
X838546Y305298D01*
X839013Y305498D01*
X839546Y305565D01*
X840213Y305432D01*
X840680Y305098D01*
X840813Y304698D01*
X840746Y304298D01*
X840480Y303965D01*
X839146Y303298D01*
X838546Y302832D01*
X838146Y302165D01*
X838013Y301565D01*
X840813D01*
G01X844013Y305565D02*
X843480Y305432D01*
X843080Y305098D01*
X842813Y304698D01*
X842613Y304165D01*
X842546Y303565D01*
X842613Y302965D01*
X842813Y302432D01*
X843080Y302032D01*
X843480Y301698D01*
X844013Y301565D01*
X844546Y301698D01*
X844946Y302032D01*
X845213Y302432D01*
X845413Y302965D01*
X845480Y303565D01*
X845413Y304165D01*
X845213Y304698D01*
X844946Y305098D01*
X844546Y305432D01*
X844013Y305565D01*
G01X848613Y301565D02*
X849080Y301632D01*
X849613Y301832D01*
X849946Y302165D01*
X850080Y302632D01*
X849946Y303098D01*
X849546Y303498D01*
X848946Y303698D01*
X848280D01*
X847880Y303832D01*
X847546Y304165D01*
X847413Y304632D01*
X847613Y305098D01*
X848080Y305432D01*
X848613Y305565D01*
X849146Y305432D01*
X849613Y305098D01*
X849813Y304632D01*
X849680Y304165D01*
X849346Y303832D01*
X848946Y303698D01*
X848280D01*
X847680Y303498D01*
X847280Y303098D01*
X847146Y302632D01*
X847280Y302165D01*
X847613Y301832D01*
X848146Y301632D01*
X848613Y301565D01*
G01X853213Y301432D02*
X853080Y301498D01*
Y301632D01*
X853213Y301698D01*
X853346Y301632D01*
Y301498D01*
X853213Y301432D01*
G01X856546Y303232D02*
X857013Y303698D01*
X857413Y303965D01*
X857946Y304098D01*
X858413Y303965D01*
X858746Y303698D01*
X859013Y303298D01*
X859080Y302832D01*
X859013Y302432D01*
X858746Y302032D01*
X858346Y301698D01*
X857880Y301565D01*
X857346Y301698D01*
X856880Y302098D01*
X856613Y302698D01*
X856546Y303365D01*
X856680Y304232D01*
X856880Y304698D01*
X857213Y305165D01*
X857680Y305498D01*
X858146Y305565D01*
X858613Y305432D01*
X858946Y305098D01*
G01X861146Y303232D02*
X861613Y303698D01*
X862013Y303965D01*
X862546Y304098D01*
X863013Y303965D01*
X863346Y303698D01*
X863613Y303298D01*
X863680Y302832D01*
X863613Y302432D01*
X863346Y302032D01*
X862946Y301698D01*
X862480Y301565D01*
X861946Y301698D01*
X861480Y302098D01*
X861213Y302698D01*
X861146Y303365D01*
X861280Y304232D01*
X861480Y304698D01*
X861813Y305165D01*
X862280Y305498D01*
X862746Y305565D01*
X863213Y305432D01*
X863546Y305098D01*
G01X831591Y262731D02*
Y266731D01*
X832925D01*
X833458Y266531D01*
X833858Y266264D01*
X834191Y265864D01*
X834458Y265398D01*
X834525Y264731D01*
X834458Y264064D01*
X834191Y263598D01*
X833858Y263198D01*
X833458Y262931D01*
X832925Y262731D01*
X831591D01*
G01X836725D02*
Y265398D01*
G01Y264864D02*
X837058Y265131D01*
X837391Y265331D01*
X837858Y265398D01*
X838191Y265331D01*
X838591Y265131D01*
G01X842258Y265398D02*
Y262731D01*
G01Y266464D02*
X842125Y266531D01*
Y266664D01*
X842258Y266731D01*
X842391Y266664D01*
Y266531D01*
X842258Y266464D01*
G01X846858Y262731D02*
Y266731D01*
G01X851458Y262731D02*
Y266731D01*
G01X860258Y262731D02*
Y266131D01*
X860391Y266464D01*
X860658Y266664D01*
X861058Y266731D01*
X861458Y266598D01*
X861658Y266264D01*
G01X860858Y265131D02*
X859525D01*
G01X864258Y264531D02*
X866391D01*
X866191Y264998D01*
X865858Y265264D01*
X865391Y265398D01*
X864925Y265331D01*
X864525Y265131D01*
X864258Y264664D01*
X864125Y264264D01*
Y263864D01*
X864258Y263464D01*
X864591Y263064D01*
X864991Y262798D01*
X865458Y262731D01*
X865925Y262864D01*
X866391Y263264D01*
G01X871058Y262731D02*
Y265398D01*
G01Y264931D02*
X870791Y265198D01*
X870391Y265331D01*
X869925Y265398D01*
X869458Y265264D01*
X869058Y264998D01*
X868791Y264598D01*
X868658Y264064D01*
X868791Y263531D01*
X869058Y263131D01*
X869458Y262864D01*
X869925Y262731D01*
X870391Y262798D01*
X870791Y262998D01*
X871058Y263264D01*
G01X874458Y266731D02*
Y262731D01*
G01X873525Y265398D02*
X875391D01*
G01X877925D02*
Y263531D01*
X878191Y263064D01*
X878591Y262798D01*
X879058Y262731D01*
X879525Y262798D01*
X879925Y263064D01*
X880191Y263531D01*
G01Y262731D02*
Y265398D01*
G01X882725Y262731D02*
Y265398D01*
G01Y264864D02*
X883058Y265131D01*
X883391Y265331D01*
X883858Y265398D01*
X884191Y265331D01*
X884591Y265131D01*
G01X887258Y264531D02*
X889391D01*
X889191Y264998D01*
X888858Y265264D01*
X888391Y265398D01*
X887925Y265331D01*
X887525Y265131D01*
X887258Y264664D01*
X887125Y264264D01*
Y263864D01*
X887258Y263464D01*
X887591Y263064D01*
X887991Y262798D01*
X888458Y262731D01*
X888925Y262864D01*
X889391Y263264D01*
G01X806437Y277843D02*
G03X813362Y264712I37662J11471D01*
G01X806437Y277843D02*
G03X813362Y264712I37662J11471D01*
G01X838054Y693015D02*
Y697015D01*
X835587Y694148D01*
X838921D01*
G01X840387Y693815D02*
X840787Y693348D01*
X841321Y693082D01*
X841921Y693015D01*
X842454Y693082D01*
X842987Y693415D01*
X843321Y693815D01*
X843387Y694215D01*
X843254Y694682D01*
X842787Y695015D01*
X842321Y695148D01*
X841721D01*
G01X842321D02*
X842721Y695348D01*
X843054Y695682D01*
X843187Y696082D01*
X843054Y696482D01*
X842721Y696815D01*
X842121Y697015D01*
X841521Y696948D01*
X840921Y696682D01*
G01X844987Y693815D02*
X845387Y693348D01*
X845921Y693082D01*
X846521Y693015D01*
X847054Y693082D01*
X847587Y693415D01*
X847921Y693815D01*
X847987Y694215D01*
X847854Y694682D01*
X847387Y695015D01*
X846921Y695148D01*
X846321D01*
G01X846921D02*
X847321Y695348D01*
X847654Y695682D01*
X847787Y696082D01*
X847654Y696482D01*
X847321Y696815D01*
X846721Y697015D01*
X846121Y696948D01*
X845521Y696682D01*
G01X851054Y692882D02*
X850921Y692948D01*
Y693082D01*
X851054Y693148D01*
X851187Y693082D01*
Y692948D01*
X851054Y692882D01*
G01X855654Y697015D02*
X855121Y696882D01*
X854721Y696548D01*
X854454Y696148D01*
X854254Y695615D01*
X854187Y695015D01*
X854254Y694415D01*
X854454Y693882D01*
X854721Y693482D01*
X855121Y693148D01*
X855654Y693015D01*
X856187Y693148D01*
X856587Y693482D01*
X856854Y693882D01*
X857054Y694415D01*
X857121Y695015D01*
X857054Y695615D01*
X856854Y696148D01*
X856587Y696548D01*
X856187Y696882D01*
X855654Y697015D01*
G01X860254Y693015D02*
X860721Y693082D01*
X861254Y693282D01*
X861587Y693615D01*
X861721Y694082D01*
X861587Y694548D01*
X861187Y694948D01*
X860587Y695148D01*
X859921D01*
X859521Y695282D01*
X859187Y695615D01*
X859054Y696082D01*
X859254Y696548D01*
X859721Y696882D01*
X860254Y697015D01*
X860787Y696882D01*
X861254Y696548D01*
X861454Y696082D01*
X861321Y695615D01*
X860987Y695282D01*
X860587Y695148D01*
X859921D01*
X859321Y694948D01*
X858921Y694548D01*
X858787Y694082D01*
X858921Y693615D01*
X859254Y693282D01*
X859787Y693082D01*
X860254Y693015D01*
G01X831591Y735172D02*
Y739172D01*
X832925D01*
X833458Y738972D01*
X833858Y738705D01*
X834191Y738305D01*
X834458Y737839D01*
X834525Y737172D01*
X834458Y736505D01*
X834191Y736039D01*
X833858Y735639D01*
X833458Y735372D01*
X832925Y735172D01*
X831591D01*
G01X836725D02*
Y737839D01*
G01Y737305D02*
X837058Y737572D01*
X837391Y737772D01*
X837858Y737839D01*
X838191Y737772D01*
X838591Y737572D01*
G01X842258Y737839D02*
Y735172D01*
G01Y738905D02*
X842125Y738972D01*
Y739105D01*
X842258Y739172D01*
X842391Y739105D01*
Y738972D01*
X842258Y738905D01*
G01X846858Y735172D02*
Y739172D01*
G01X851458Y735172D02*
Y739172D01*
G01X860258Y735172D02*
Y738572D01*
X860391Y738905D01*
X860658Y739105D01*
X861058Y739172D01*
X861458Y739039D01*
X861658Y738705D01*
G01X860858Y737572D02*
X859525D01*
G01X864258Y736972D02*
X866391D01*
X866191Y737439D01*
X865858Y737705D01*
X865391Y737839D01*
X864925Y737772D01*
X864525Y737572D01*
X864258Y737105D01*
X864125Y736705D01*
Y736305D01*
X864258Y735905D01*
X864591Y735505D01*
X864991Y735239D01*
X865458Y735172D01*
X865925Y735305D01*
X866391Y735705D01*
G01X871058Y735172D02*
Y737839D01*
G01Y737372D02*
X870791Y737639D01*
X870391Y737772D01*
X869925Y737839D01*
X869458Y737705D01*
X869058Y737439D01*
X868791Y737039D01*
X868658Y736505D01*
X868791Y735972D01*
X869058Y735572D01*
X869458Y735305D01*
X869925Y735172D01*
X870391Y735239D01*
X870791Y735439D01*
X871058Y735705D01*
G01X874458Y739172D02*
Y735172D01*
G01X873525Y737839D02*
X875391D01*
G01X877925D02*
Y735972D01*
X878191Y735505D01*
X878591Y735239D01*
X879058Y735172D01*
X879525Y735239D01*
X879925Y735505D01*
X880191Y735972D01*
G01Y735172D02*
Y737839D01*
G01X882725Y735172D02*
Y737839D01*
G01Y737305D02*
X883058Y737572D01*
X883391Y737772D01*
X883858Y737839D01*
X884191Y737772D01*
X884591Y737572D01*
G01X887258Y736972D02*
X889391D01*
X889191Y737439D01*
X888858Y737705D01*
X888391Y737839D01*
X887925Y737772D01*
X887525Y737572D01*
X887258Y737105D01*
X887125Y736705D01*
Y736305D01*
X887258Y735905D01*
X887591Y735505D01*
X887991Y735239D01*
X888458Y735172D01*
X888925Y735305D01*
X889391Y735705D01*
G01X806437Y750284D02*
G03X813362Y737153I37662J11471D01*
G01X806437Y750284D02*
G03X813362Y737154I37661J11472D01*
G01X838146Y777339D02*
X838546Y777739D01*
X839013Y777939D01*
X839546Y778006D01*
X840213Y777873D01*
X840680Y777539D01*
X840813Y777139D01*
X840746Y776739D01*
X840480Y776406D01*
X839146Y775739D01*
X838546Y775273D01*
X838146Y774606D01*
X838013Y774006D01*
X840813D01*
G01X844013Y778006D02*
X843480Y777873D01*
X843080Y777539D01*
X842813Y777139D01*
X842613Y776606D01*
X842546Y776006D01*
X842613Y775406D01*
X842813Y774873D01*
X843080Y774473D01*
X843480Y774139D01*
X844013Y774006D01*
X844546Y774139D01*
X844946Y774473D01*
X845213Y774873D01*
X845413Y775406D01*
X845480Y776006D01*
X845413Y776606D01*
X845213Y777139D01*
X844946Y777539D01*
X844546Y777873D01*
X844013Y778006D01*
G01X848613Y774006D02*
X849080Y774073D01*
X849613Y774273D01*
X849946Y774606D01*
X850080Y775073D01*
X849946Y775539D01*
X849546Y775939D01*
X848946Y776139D01*
X848280D01*
X847880Y776273D01*
X847546Y776606D01*
X847413Y777073D01*
X847613Y777539D01*
X848080Y777873D01*
X848613Y778006D01*
X849146Y777873D01*
X849613Y777539D01*
X849813Y777073D01*
X849680Y776606D01*
X849346Y776273D01*
X848946Y776139D01*
X848280D01*
X847680Y775939D01*
X847280Y775539D01*
X847146Y775073D01*
X847280Y774606D01*
X847613Y774273D01*
X848146Y774073D01*
X848613Y774006D01*
G01X853213Y773873D02*
X853080Y773939D01*
Y774073D01*
X853213Y774139D01*
X853346Y774073D01*
Y773939D01*
X853213Y773873D01*
G01X856546Y775673D02*
X857013Y776139D01*
X857413Y776406D01*
X857946Y776539D01*
X858413Y776406D01*
X858746Y776139D01*
X859013Y775739D01*
X859080Y775273D01*
X859013Y774873D01*
X858746Y774473D01*
X858346Y774139D01*
X857880Y774006D01*
X857346Y774139D01*
X856880Y774539D01*
X856613Y775139D01*
X856546Y775806D01*
X856680Y776673D01*
X856880Y777139D01*
X857213Y777606D01*
X857680Y777939D01*
X858146Y778006D01*
X858613Y777873D01*
X858946Y777539D01*
G01X861146Y775673D02*
X861613Y776139D01*
X862013Y776406D01*
X862546Y776539D01*
X863013Y776406D01*
X863346Y776139D01*
X863613Y775739D01*
X863680Y775273D01*
X863613Y774873D01*
X863346Y774473D01*
X862946Y774139D01*
X862480Y774006D01*
X861946Y774139D01*
X861480Y774539D01*
X861213Y775139D01*
X861146Y775806D01*
X861280Y776673D01*
X861480Y777139D01*
X861813Y777606D01*
X862280Y777939D01*
X862746Y778006D01*
X863213Y777873D01*
X863546Y777539D01*
G01X835026Y1581529D02*
Y1591229D01*
X840026Y1586229D01*
X830026D01*
X835026Y1591229D01*
G01X824272Y1653288D02*
X914311D01*
Y1591595D01*
X824272D01*
Y1653288D01*
G01X866142Y-148819D02*
Y-11811D01*
G01Y-148819D02*
G03X870079Y-152756I3937J0D01*
G01X866142Y-11811D02*
Y-148819D01*
G01D02*
G03X870079Y-152756I3937J0D01*
G01X866142Y-129134D02*
G03X858268I-3937J0D01*
G01X866142D02*
G03X858268I-3937J0D01*
G01Y-148819D02*
Y-129134D01*
G01X854331Y-152756D02*
G03X858268Y-148819I0J3937D01*
G01D02*
Y-129134D01*
G01X854331Y-152756D02*
G03X858268Y-148819I0J3937D01*
G01X1177165Y-152756D02*
X870079D01*
G01D02*
X1177165D01*
G01X858268Y-98425D02*
Y-15748D01*
G01Y-98425D02*
Y-15748D01*
G01Y-98425D02*
G03X866142I3937J0D01*
G01X858268D02*
G03X866142I3937J0D01*
G01X872666Y-67159D02*
X873066Y-67492D01*
X873533Y-67692D01*
X874133Y-67759D01*
X874733Y-67626D01*
X875200Y-67359D01*
X875533Y-66892D01*
X875600Y-66359D01*
X875466Y-65826D01*
X875133Y-65492D01*
X874666Y-65226D01*
X874200Y-65159D01*
X873733Y-65226D01*
X873133Y-65492D01*
X873333Y-63759D01*
X875133D01*
G01X877266Y-67159D02*
X877666Y-67492D01*
X878133Y-67692D01*
X878733Y-67759D01*
X879333Y-67626D01*
X879800Y-67359D01*
X880133Y-66892D01*
X880200Y-66359D01*
X880066Y-65826D01*
X879733Y-65492D01*
X879266Y-65226D01*
X878800Y-65159D01*
X878333Y-65226D01*
X877733Y-65492D01*
X877933Y-63759D01*
X879733D01*
G01X883200Y-67759D02*
X883333Y-66892D01*
X883533Y-66159D01*
X883800Y-65492D01*
X884133Y-64759D01*
X884666Y-63759D01*
X882000D01*
G01X887933Y-67892D02*
X887800Y-67826D01*
Y-67692D01*
X887933Y-67626D01*
X888066Y-67692D01*
Y-67826D01*
X887933Y-67892D01*
G01X892533Y-63759D02*
X892000Y-63892D01*
X891600Y-64226D01*
X891333Y-64626D01*
X891133Y-65159D01*
X891066Y-65759D01*
X891133Y-66359D01*
X891333Y-66892D01*
X891600Y-67292D01*
X892000Y-67626D01*
X892533Y-67759D01*
X893066Y-67626D01*
X893466Y-67292D01*
X893733Y-66892D01*
X893933Y-66359D01*
X894000Y-65759D01*
X893933Y-65159D01*
X893733Y-64626D01*
X893466Y-64226D01*
X893066Y-63892D01*
X892533Y-63759D01*
G01X896000Y-67292D02*
X896466Y-67626D01*
X897000Y-67759D01*
X897533Y-67626D01*
X898000Y-67226D01*
X898333Y-66626D01*
X898466Y-66026D01*
Y-65292D01*
X898333Y-64692D01*
X898000Y-64159D01*
X897600Y-63892D01*
X897133Y-63759D01*
X896600Y-63892D01*
X896200Y-64159D01*
X895933Y-64559D01*
X895800Y-65092D01*
X895933Y-65559D01*
X896266Y-66026D01*
X896666Y-66292D01*
X897133Y-66359D01*
X897666Y-66226D01*
X898066Y-65892D01*
X898466Y-65292D01*
G01X889061Y-56704D02*
X889461Y-56304D01*
X889928Y-56104D01*
X890461Y-56037D01*
X891128Y-56170D01*
X891595Y-56504D01*
X891728Y-56904D01*
X891661Y-57304D01*
X891395Y-57637D01*
X890061Y-58304D01*
X889461Y-58770D01*
X889061Y-59437D01*
X888928Y-60037D01*
X891728D01*
G01X893461Y-59237D02*
X893861Y-59704D01*
X894395Y-59970D01*
X894995Y-60037D01*
X895528Y-59970D01*
X896061Y-59637D01*
X896395Y-59237D01*
X896461Y-58837D01*
X896328Y-58370D01*
X895861Y-58037D01*
X895395Y-57904D01*
X894795D01*
G01X895395D02*
X895795Y-57704D01*
X896128Y-57370D01*
X896261Y-56970D01*
X896128Y-56570D01*
X895795Y-56237D01*
X895195Y-56037D01*
X894595Y-56104D01*
X893995Y-56370D01*
G01X898261Y-58370D02*
X898728Y-57904D01*
X899128Y-57637D01*
X899661Y-57504D01*
X900128Y-57637D01*
X900461Y-57904D01*
X900728Y-58304D01*
X900795Y-58770D01*
X900728Y-59170D01*
X900461Y-59570D01*
X900061Y-59904D01*
X899595Y-60037D01*
X899061Y-59904D01*
X898595Y-59504D01*
X898328Y-58904D01*
X898261Y-58237D01*
X898395Y-57370D01*
X898595Y-56904D01*
X898928Y-56437D01*
X899395Y-56104D01*
X899861Y-56037D01*
X900328Y-56170D01*
X900661Y-56504D01*
G01X904128Y-60170D02*
X903995Y-60104D01*
Y-59970D01*
X904128Y-59904D01*
X904261Y-59970D01*
Y-60104D01*
X904128Y-60170D01*
G01X907461Y-56704D02*
X907861Y-56304D01*
X908328Y-56104D01*
X908861Y-56037D01*
X909528Y-56170D01*
X909995Y-56504D01*
X910128Y-56904D01*
X910061Y-57304D01*
X909795Y-57637D01*
X908461Y-58304D01*
X907861Y-58770D01*
X907461Y-59437D01*
X907328Y-60037D01*
X910128D01*
G01X911861Y-59237D02*
X912261Y-59704D01*
X912795Y-59970D01*
X913395Y-60037D01*
X913928Y-59970D01*
X914461Y-59637D01*
X914795Y-59237D01*
X914861Y-58837D01*
X914728Y-58370D01*
X914261Y-58037D01*
X913795Y-57904D01*
X913195D01*
G01X913795D02*
X914195Y-57704D01*
X914528Y-57370D01*
X914661Y-56970D01*
X914528Y-56570D01*
X914195Y-56237D01*
X913595Y-56037D01*
X912995Y-56104D01*
X912395Y-56370D01*
G01X866142Y-11811D02*
G03X862205Y-7874I-3937J0D01*
G01X866142Y-11811D02*
G03X862205Y-7874I-3937J0D01*
G01X884981Y1078032D02*
X885381Y1077699D01*
X885848Y1077499D01*
X886448Y1077432D01*
X887048Y1077565D01*
X887515Y1077832D01*
X887848Y1078299D01*
X887915Y1078832D01*
X887781Y1079365D01*
X887448Y1079699D01*
X886981Y1079965D01*
X886515Y1080032D01*
X886048Y1079965D01*
X885448Y1079699D01*
X885648Y1081432D01*
X887448D01*
G01X889581Y1078032D02*
X889981Y1077699D01*
X890448Y1077499D01*
X891048Y1077432D01*
X891648Y1077565D01*
X892115Y1077832D01*
X892448Y1078299D01*
X892515Y1078832D01*
X892381Y1079365D01*
X892048Y1079699D01*
X891581Y1079965D01*
X891115Y1080032D01*
X890648Y1079965D01*
X890048Y1079699D01*
X890248Y1081432D01*
X892048D01*
G01X895515Y1077432D02*
X895648Y1078299D01*
X895848Y1079032D01*
X896115Y1079699D01*
X896448Y1080432D01*
X896981Y1081432D01*
X894315D01*
G01X900248Y1077299D02*
X900115Y1077365D01*
Y1077499D01*
X900248Y1077565D01*
X900381Y1077499D01*
Y1077365D01*
X900248Y1077299D01*
G01X904848Y1081432D02*
X904315Y1081299D01*
X903915Y1080965D01*
X903648Y1080565D01*
X903448Y1080032D01*
X903381Y1079432D01*
X903448Y1078832D01*
X903648Y1078299D01*
X903915Y1077899D01*
X904315Y1077565D01*
X904848Y1077432D01*
X905381Y1077565D01*
X905781Y1077899D01*
X906048Y1078299D01*
X906248Y1078832D01*
X906315Y1079432D01*
X906248Y1080032D01*
X906048Y1080565D01*
X905781Y1080965D01*
X905381Y1081299D01*
X904848Y1081432D01*
G01X908315Y1077899D02*
X908781Y1077565D01*
X909315Y1077432D01*
X909848Y1077565D01*
X910315Y1077965D01*
X910648Y1078565D01*
X910781Y1079165D01*
Y1079899D01*
X910648Y1080499D01*
X910315Y1081032D01*
X909915Y1081299D01*
X909448Y1081432D01*
X908915Y1081299D01*
X908515Y1081032D01*
X908248Y1080632D01*
X908115Y1080099D01*
X908248Y1079632D01*
X908581Y1079165D01*
X908981Y1078899D01*
X909448Y1078832D01*
X909981Y1078965D01*
X910381Y1079299D01*
X910781Y1079899D01*
G01X884981Y1420551D02*
X885381Y1420218D01*
X885848Y1420018D01*
X886448Y1419951D01*
X887048Y1420084D01*
X887515Y1420351D01*
X887848Y1420818D01*
X887915Y1421351D01*
X887781Y1421884D01*
X887448Y1422218D01*
X886981Y1422484D01*
X886515Y1422551D01*
X886048Y1422484D01*
X885448Y1422218D01*
X885648Y1423951D01*
X887448D01*
G01X889581Y1420551D02*
X889981Y1420218D01*
X890448Y1420018D01*
X891048Y1419951D01*
X891648Y1420084D01*
X892115Y1420351D01*
X892448Y1420818D01*
X892515Y1421351D01*
X892381Y1421884D01*
X892048Y1422218D01*
X891581Y1422484D01*
X891115Y1422551D01*
X890648Y1422484D01*
X890048Y1422218D01*
X890248Y1423951D01*
X892048D01*
G01X895515Y1419951D02*
X895648Y1420818D01*
X895848Y1421551D01*
X896115Y1422218D01*
X896448Y1422951D01*
X896981Y1423951D01*
X894315D01*
G01X900248Y1419818D02*
X900115Y1419884D01*
Y1420018D01*
X900248Y1420084D01*
X900381Y1420018D01*
Y1419884D01*
X900248Y1419818D01*
G01X904848Y1423951D02*
X904315Y1423818D01*
X903915Y1423484D01*
X903648Y1423084D01*
X903448Y1422551D01*
X903381Y1421951D01*
X903448Y1421351D01*
X903648Y1420818D01*
X903915Y1420418D01*
X904315Y1420084D01*
X904848Y1419951D01*
X905381Y1420084D01*
X905781Y1420418D01*
X906048Y1420818D01*
X906248Y1421351D01*
X906315Y1421951D01*
X906248Y1422551D01*
X906048Y1423084D01*
X905781Y1423484D01*
X905381Y1423818D01*
X904848Y1423951D01*
G01X908315Y1420418D02*
X908781Y1420084D01*
X909315Y1419951D01*
X909848Y1420084D01*
X910315Y1420484D01*
X910648Y1421084D01*
X910781Y1421684D01*
Y1422418D01*
X910648Y1423018D01*
X910315Y1423551D01*
X909915Y1423818D01*
X909448Y1423951D01*
X908915Y1423818D01*
X908515Y1423551D01*
X908248Y1423151D01*
X908115Y1422618D01*
X908248Y1422151D01*
X908581Y1421684D01*
X908981Y1421418D01*
X909448Y1421351D01*
X909981Y1421484D01*
X910381Y1421818D01*
X910781Y1422418D01*
G01X866630Y1668325D02*
Y1658625D01*
X861630Y1663625D01*
X871630D01*
X866630Y1658625D01*
G01X858172Y1668527D02*
X858705Y1668194D01*
X859305Y1667994D01*
X859839D01*
X860372Y1668194D01*
X860772Y1668527D01*
X860972Y1668994D01*
X860839Y1669461D01*
X860505Y1669861D01*
X859905Y1670127D01*
X859105Y1670261D01*
X858639Y1670527D01*
X858439Y1670994D01*
X858572Y1671461D01*
X858905Y1671794D01*
X859372Y1671994D01*
X859839D01*
X860305Y1671861D01*
X860705Y1671527D01*
G01X864172Y1667994D02*
Y1671994D01*
G01X868772Y1670661D02*
Y1667994D01*
G01Y1671727D02*
X868639Y1671794D01*
Y1671927D01*
X868772Y1671994D01*
X868905Y1671927D01*
Y1671794D01*
X868772Y1671727D01*
G01X873372Y1671994D02*
Y1667994D01*
G01X872439Y1670661D02*
X874305D01*
G01X927032Y-57820D02*
G03X962731I17850J-12259D01*
G01X927032Y-57821D02*
G03X962732I17850J-12258D01*
G01X927032Y-57820D02*
G03X935199Y-42571I-64908J44575D01*
G01X954565D02*
G03X935199I-9683J-3885D01*
G01X927032Y-57821D02*
G03X935199Y-42571I-64909J44573D01*
G01X954564D02*
G03X935199I-9682J-3885D01*
G01X926431Y9699D02*
X957821D01*
Y351907D01*
X926431D01*
Y9699D01*
G01X925871Y-16941D02*
Y-12941D01*
X925071Y-13741D01*
G01Y-16941D02*
X926671D01*
G01X929204Y-15274D02*
X929671Y-14808D01*
X930071Y-14541D01*
X930604Y-14408D01*
X931071Y-14541D01*
X931404Y-14808D01*
X931671Y-15208D01*
X931738Y-15674D01*
X931671Y-16074D01*
X931404Y-16474D01*
X931004Y-16808D01*
X930538Y-16941D01*
X930004Y-16808D01*
X929538Y-16408D01*
X929271Y-15808D01*
X929204Y-15141D01*
X929338Y-14274D01*
X929538Y-13808D01*
X929871Y-13341D01*
X930338Y-13008D01*
X930804Y-12941D01*
X931271Y-13074D01*
X931604Y-13408D01*
G01X933804Y-15274D02*
X934271Y-14808D01*
X934671Y-14541D01*
X935204Y-14408D01*
X935671Y-14541D01*
X936004Y-14808D01*
X936271Y-15208D01*
X936338Y-15674D01*
X936271Y-16074D01*
X936004Y-16474D01*
X935604Y-16808D01*
X935138Y-16941D01*
X934604Y-16808D01*
X934138Y-16408D01*
X933871Y-15808D01*
X933804Y-15141D01*
X933938Y-14274D01*
X934138Y-13808D01*
X934471Y-13341D01*
X934938Y-13008D01*
X935404Y-12941D01*
X935871Y-13074D01*
X936204Y-13408D01*
G01X938271Y-16941D02*
X941071Y-12941D01*
G01X938271D02*
X941071Y-16941D01*
G01X943004Y-13608D02*
X943404Y-13208D01*
X943871Y-13008D01*
X944404Y-12941D01*
X945071Y-13074D01*
X945538Y-13408D01*
X945671Y-13808D01*
X945604Y-14208D01*
X945338Y-14541D01*
X944004Y-15208D01*
X943404Y-15674D01*
X943004Y-16341D01*
X942871Y-16941D01*
X945671D01*
G01X949671D02*
Y-12941D01*
X947204Y-15808D01*
X950538D01*
G01X952004Y-16341D02*
X952404Y-16674D01*
X952871Y-16874D01*
X953471Y-16941D01*
X954071Y-16808D01*
X954538Y-16541D01*
X954871Y-16074D01*
X954938Y-15541D01*
X954804Y-15008D01*
X954471Y-14674D01*
X954004Y-14408D01*
X953538Y-14341D01*
X953071Y-14408D01*
X952471Y-14674D01*
X952671Y-12941D01*
X954471D01*
G01X926431Y388832D02*
X957821D01*
Y731040D01*
X926431D01*
Y388832D01*
G01X944512Y1089122D02*
G03X978323I16905J-13531D01*
G01X944512Y1089121D02*
G03X978323I16905J-13531D01*
G01X902320Y1088578D02*
X902720Y1088978D01*
X903187Y1089178D01*
X903720Y1089245D01*
X904387Y1089112D01*
X904854Y1088778D01*
X904987Y1088378D01*
X904920Y1087978D01*
X904654Y1087645D01*
X903320Y1086978D01*
X902720Y1086512D01*
X902320Y1085845D01*
X902187Y1085245D01*
X904987D01*
G01X906720Y1086045D02*
X907120Y1085578D01*
X907654Y1085312D01*
X908254Y1085245D01*
X908787Y1085312D01*
X909320Y1085645D01*
X909654Y1086045D01*
X909720Y1086445D01*
X909587Y1086912D01*
X909120Y1087245D01*
X908654Y1087378D01*
X908054D01*
G01X908654D02*
X909054Y1087578D01*
X909387Y1087912D01*
X909520Y1088312D01*
X909387Y1088712D01*
X909054Y1089045D01*
X908454Y1089245D01*
X907854Y1089178D01*
X907254Y1088912D01*
G01X911520Y1086912D02*
X911987Y1087378D01*
X912387Y1087645D01*
X912920Y1087778D01*
X913387Y1087645D01*
X913720Y1087378D01*
X913987Y1086978D01*
X914054Y1086512D01*
X913987Y1086112D01*
X913720Y1085712D01*
X913320Y1085378D01*
X912854Y1085245D01*
X912320Y1085378D01*
X911854Y1085778D01*
X911587Y1086378D01*
X911520Y1087045D01*
X911654Y1087912D01*
X911854Y1088378D01*
X912187Y1088845D01*
X912654Y1089178D01*
X913120Y1089245D01*
X913587Y1089112D01*
X913920Y1088778D01*
G01X917387Y1085112D02*
X917254Y1085178D01*
Y1085312D01*
X917387Y1085378D01*
X917520Y1085312D01*
Y1085178D01*
X917387Y1085112D01*
G01X920720Y1088578D02*
X921120Y1088978D01*
X921587Y1089178D01*
X922120Y1089245D01*
X922787Y1089112D01*
X923254Y1088778D01*
X923387Y1088378D01*
X923320Y1087978D01*
X923054Y1087645D01*
X921720Y1086978D01*
X921120Y1086512D01*
X920720Y1085845D01*
X920587Y1085245D01*
X923387D01*
G01X925320Y1088578D02*
X925720Y1088978D01*
X926187Y1089178D01*
X926720Y1089245D01*
X927387Y1089112D01*
X927854Y1088778D01*
X927987Y1088378D01*
X927920Y1087978D01*
X927654Y1087645D01*
X926320Y1086978D01*
X925720Y1086512D01*
X925320Y1085845D01*
X925187Y1085245D01*
X927987D01*
G01X944512Y1431641D02*
G03X978323I16905J-13531D01*
G01X944512D02*
G03X978323I16905J-13531D01*
G01X902320Y1431097D02*
X902720Y1431497D01*
X903187Y1431697D01*
X903720Y1431764D01*
X904387Y1431631D01*
X904854Y1431297D01*
X904987Y1430897D01*
X904920Y1430497D01*
X904654Y1430164D01*
X903320Y1429497D01*
X902720Y1429031D01*
X902320Y1428364D01*
X902187Y1427764D01*
X904987D01*
G01X906720Y1428564D02*
X907120Y1428097D01*
X907654Y1427831D01*
X908254Y1427764D01*
X908787Y1427831D01*
X909320Y1428164D01*
X909654Y1428564D01*
X909720Y1428964D01*
X909587Y1429431D01*
X909120Y1429764D01*
X908654Y1429897D01*
X908054D01*
G01X908654D02*
X909054Y1430097D01*
X909387Y1430431D01*
X909520Y1430831D01*
X909387Y1431231D01*
X909054Y1431564D01*
X908454Y1431764D01*
X907854Y1431697D01*
X907254Y1431431D01*
G01X911520Y1429431D02*
X911987Y1429897D01*
X912387Y1430164D01*
X912920Y1430297D01*
X913387Y1430164D01*
X913720Y1429897D01*
X913987Y1429497D01*
X914054Y1429031D01*
X913987Y1428631D01*
X913720Y1428231D01*
X913320Y1427897D01*
X912854Y1427764D01*
X912320Y1427897D01*
X911854Y1428297D01*
X911587Y1428897D01*
X911520Y1429564D01*
X911654Y1430431D01*
X911854Y1430897D01*
X912187Y1431364D01*
X912654Y1431697D01*
X913120Y1431764D01*
X913587Y1431631D01*
X913920Y1431297D01*
G01X917387Y1427631D02*
X917254Y1427697D01*
Y1427831D01*
X917387Y1427897D01*
X917520Y1427831D01*
Y1427697D01*
X917387Y1427631D01*
G01X920720Y1431097D02*
X921120Y1431497D01*
X921587Y1431697D01*
X922120Y1431764D01*
X922787Y1431631D01*
X923254Y1431297D01*
X923387Y1430897D01*
X923320Y1430497D01*
X923054Y1430164D01*
X921720Y1429497D01*
X921120Y1429031D01*
X920720Y1428364D01*
X920587Y1427764D01*
X923387D01*
G01X925320Y1431097D02*
X925720Y1431497D01*
X926187Y1431697D01*
X926720Y1431764D01*
X927387Y1431631D01*
X927854Y1431297D01*
X927987Y1430897D01*
X927920Y1430497D01*
X927654Y1430164D01*
X926320Y1429497D01*
X925720Y1429031D01*
X925320Y1428364D01*
X925187Y1427764D01*
X927987D01*
G01X1116190Y1668157D02*
Y1664157D01*
X1114590D01*
X1114057Y1664357D01*
X1113657Y1664824D01*
X1113524Y1665357D01*
X1113657Y1665890D01*
X1113990Y1666290D01*
X1114590Y1666490D01*
X1116190D01*
G01X1111190Y1668157D02*
Y1665490D01*
G01Y1666024D02*
X1110857Y1665757D01*
X1110524Y1665557D01*
X1110057Y1665490D01*
X1109724Y1665557D01*
X1109324Y1665757D01*
G01X1106657Y1666357D02*
X1104524D01*
X1104724Y1665890D01*
X1105057Y1665624D01*
X1105524Y1665490D01*
X1105990Y1665557D01*
X1106390Y1665757D01*
X1106657Y1666224D01*
X1106790Y1666624D01*
Y1667024D01*
X1106657Y1667424D01*
X1106324Y1667824D01*
X1105924Y1668090D01*
X1105457Y1668157D01*
X1104990Y1668024D01*
X1104524Y1667624D01*
G01X1102057Y1667690D02*
X1101724Y1667957D01*
X1101257Y1668157D01*
X1100857D01*
X1100457Y1668024D01*
X1100190Y1667824D01*
X1100057Y1667557D01*
X1100124Y1667157D01*
X1100390Y1666957D01*
X1101590Y1666557D01*
X1101857Y1666090D01*
X1101724Y1665757D01*
X1101457Y1665557D01*
X1101057Y1665490D01*
X1100657Y1665557D01*
X1100257Y1665757D01*
G01X1097457Y1667690D02*
X1097124Y1667957D01*
X1096657Y1668157D01*
X1096257D01*
X1095857Y1668024D01*
X1095590Y1667824D01*
X1095457Y1667557D01*
X1095524Y1667157D01*
X1095790Y1666957D01*
X1096990Y1666557D01*
X1097257Y1666090D01*
X1097124Y1665757D01*
X1096857Y1665557D01*
X1096457Y1665490D01*
X1096057Y1665557D01*
X1095657Y1665757D01*
G01X1092724Y1666824D02*
X1090990D01*
G01X1087657Y1668157D02*
Y1664757D01*
X1087524Y1664424D01*
X1087257Y1664224D01*
X1086857Y1664157D01*
X1086457Y1664290D01*
X1086257Y1664624D01*
G01X1087057Y1665757D02*
X1088390D01*
G01X1082657Y1665490D02*
Y1668157D01*
G01Y1664424D02*
X1082790Y1664357D01*
Y1664224D01*
X1082657Y1664157D01*
X1082524Y1664224D01*
Y1664357D01*
X1082657Y1664424D01*
G01X1078057Y1664157D02*
Y1668157D01*
G01X1078990Y1665490D02*
X1077124D01*
G01X1070190Y1668157D02*
Y1664157D01*
X1068590D01*
X1068057Y1664357D01*
X1067657Y1664824D01*
X1067524Y1665357D01*
X1067657Y1665890D01*
X1067990Y1666290D01*
X1068590Y1666490D01*
X1070190D01*
G01X1064257Y1664157D02*
Y1668157D01*
G01X1065790Y1664157D02*
X1062724D01*
G01X1061057Y1668157D02*
Y1664157D01*
G01X1058257D02*
Y1668157D01*
G01Y1666157D02*
X1061057D01*
G01X1051590Y1668157D02*
Y1664157D01*
G01X1049457Y1665490D02*
X1051590Y1667024D01*
G01X1050724Y1666424D02*
X1049324Y1668157D01*
G01X1046857Y1666357D02*
X1044724D01*
X1044924Y1665890D01*
X1045257Y1665624D01*
X1045724Y1665490D01*
X1046190Y1665557D01*
X1046590Y1665757D01*
X1046857Y1666224D01*
X1046990Y1666624D01*
Y1667024D01*
X1046857Y1667424D01*
X1046524Y1667824D01*
X1046124Y1668090D01*
X1045657Y1668157D01*
X1045190Y1668024D01*
X1044724Y1667624D01*
G01X1042257Y1666357D02*
X1040124D01*
X1040324Y1665890D01*
X1040657Y1665624D01*
X1041124Y1665490D01*
X1041590Y1665557D01*
X1041990Y1665757D01*
X1042257Y1666224D01*
X1042390Y1666624D01*
Y1667024D01*
X1042257Y1667424D01*
X1041924Y1667824D01*
X1041524Y1668090D01*
X1041057Y1668157D01*
X1040590Y1668024D01*
X1040124Y1667624D01*
G01X1037857Y1669490D02*
Y1665490D01*
G01Y1666090D02*
X1037524Y1665757D01*
X1037190Y1665557D01*
X1036657Y1665490D01*
X1036190Y1665557D01*
X1035724Y1665890D01*
X1035524Y1666357D01*
X1035457Y1666824D01*
X1035524Y1667290D01*
X1035724Y1667757D01*
X1036124Y1668024D01*
X1036657Y1668157D01*
X1037124Y1668090D01*
X1037590Y1667890D01*
X1037857Y1667624D01*
G01X1028590Y1668157D02*
Y1664157D01*
G01Y1666090D02*
X1028257Y1665757D01*
X1027924Y1665557D01*
X1027390Y1665490D01*
X1026990Y1665557D01*
X1026524Y1665824D01*
X1026324Y1666224D01*
Y1668157D01*
G01X1022857D02*
X1023257Y1668090D01*
X1023657Y1667824D01*
X1023924Y1667357D01*
X1024057Y1666824D01*
X1023924Y1666290D01*
X1023657Y1665824D01*
X1023257Y1665557D01*
X1022857Y1665490D01*
X1022457Y1665557D01*
X1022057Y1665824D01*
X1021790Y1666290D01*
X1021724Y1666824D01*
X1021790Y1667357D01*
X1022057Y1667824D01*
X1022457Y1668090D01*
X1022857Y1668157D01*
G01X1018257D02*
Y1664157D01*
G01X1014657Y1666357D02*
X1012524D01*
X1012724Y1665890D01*
X1013057Y1665624D01*
X1013524Y1665490D01*
X1013990Y1665557D01*
X1014390Y1665757D01*
X1014657Y1666224D01*
X1014790Y1666624D01*
Y1667024D01*
X1014657Y1667424D01*
X1014324Y1667824D01*
X1013924Y1668090D01*
X1013457Y1668157D01*
X1012990Y1668024D01*
X1012524Y1667624D01*
G01X1005457Y1667690D02*
X1005124Y1667957D01*
X1004657Y1668157D01*
X1004257D01*
X1003857Y1668024D01*
X1003590Y1667824D01*
X1003457Y1667557D01*
X1003524Y1667157D01*
X1003790Y1666957D01*
X1004990Y1666557D01*
X1005257Y1666090D01*
X1005124Y1665757D01*
X1004857Y1665557D01*
X1004457Y1665490D01*
X1004057Y1665557D01*
X1003657Y1665757D01*
G01X999857Y1665490D02*
Y1668157D01*
G01Y1664424D02*
X999990Y1664357D01*
Y1664224D01*
X999857Y1664157D01*
X999724Y1664224D01*
Y1664357D01*
X999857Y1664424D01*
G01X996257Y1665490D02*
X994257D01*
X996257Y1668157D01*
X994257D01*
G01X991657Y1666357D02*
X989524D01*
X989724Y1665890D01*
X990057Y1665624D01*
X990524Y1665490D01*
X990990Y1665557D01*
X991390Y1665757D01*
X991657Y1666224D01*
X991790Y1666624D01*
Y1667024D01*
X991657Y1667424D01*
X991324Y1667824D01*
X990924Y1668090D01*
X990457Y1668157D01*
X989990Y1668024D01*
X989524Y1667624D01*
G01X981457Y1664157D02*
Y1668157D01*
G01X982390Y1665490D02*
X980524D01*
G01X976857Y1668157D02*
X977257Y1668090D01*
X977657Y1667824D01*
X977924Y1667357D01*
X978057Y1666824D01*
X977924Y1666290D01*
X977657Y1665824D01*
X977257Y1665557D01*
X976857Y1665490D01*
X976457Y1665557D01*
X976057Y1665824D01*
X975790Y1666290D01*
X975724Y1666824D01*
X975790Y1667357D01*
X976057Y1667824D01*
X976457Y1668090D01*
X976857Y1668157D01*
G01X972257D02*
Y1664157D01*
G01X968657Y1666357D02*
X966524D01*
X966724Y1665890D01*
X967057Y1665624D01*
X967524Y1665490D01*
X967990Y1665557D01*
X968390Y1665757D01*
X968657Y1666224D01*
X968790Y1666624D01*
Y1667024D01*
X968657Y1667424D01*
X968324Y1667824D01*
X967924Y1668090D01*
X967457Y1668157D01*
X966990Y1668024D01*
X966524Y1667624D01*
G01X963990Y1668157D02*
Y1665490D01*
G01Y1666024D02*
X963657Y1665757D01*
X963324Y1665557D01*
X962857Y1665490D01*
X962524Y1665557D01*
X962124Y1665757D01*
G01X957257Y1668157D02*
Y1665490D01*
G01Y1665957D02*
X957524Y1665690D01*
X957924Y1665557D01*
X958390Y1665490D01*
X958857Y1665624D01*
X959257Y1665890D01*
X959524Y1666290D01*
X959657Y1666824D01*
X959524Y1667357D01*
X959257Y1667757D01*
X958857Y1668024D01*
X958390Y1668157D01*
X957924Y1668090D01*
X957524Y1667890D01*
X957257Y1667624D01*
G01X954990Y1668157D02*
Y1665490D01*
G01Y1666157D02*
X954724Y1665824D01*
X954324Y1665557D01*
X953790Y1665490D01*
X953324Y1665557D01*
X952924Y1665824D01*
X952724Y1666290D01*
Y1668157D01*
G01X948190Y1665824D02*
X948657Y1665557D01*
X949057Y1665490D01*
X949590Y1665624D01*
X949990Y1665890D01*
X950257Y1666357D01*
X950324Y1666824D01*
X950257Y1667290D01*
X949990Y1667690D01*
X949590Y1668024D01*
X949057Y1668157D01*
X948590Y1668024D01*
X948190Y1667757D01*
G01X945657Y1666357D02*
X943524D01*
X943724Y1665890D01*
X944057Y1665624D01*
X944524Y1665490D01*
X944990Y1665557D01*
X945390Y1665757D01*
X945657Y1666224D01*
X945790Y1666624D01*
Y1667024D01*
X945657Y1667424D01*
X945324Y1667824D01*
X944924Y1668090D01*
X944457Y1668157D01*
X943990Y1668024D01*
X943524Y1667624D01*
G01X936190Y1666824D02*
X934590D01*
G01X935457Y1665957D02*
Y1667690D01*
G01X932057Y1668290D02*
X929657Y1664157D01*
G01X927124Y1666824D02*
X925390D01*
G01X922924Y1664824D02*
X922524Y1664424D01*
X922057Y1664224D01*
X921524Y1664157D01*
X920857Y1664290D01*
X920390Y1664624D01*
X920257Y1665024D01*
X920324Y1665424D01*
X920590Y1665757D01*
X921924Y1666424D01*
X922524Y1666890D01*
X922924Y1667557D01*
X923057Y1668157D01*
X920257D01*
G01X914457D02*
Y1665490D01*
G01Y1666224D02*
X914257Y1665890D01*
X913924Y1665624D01*
X913457Y1665490D01*
X912990Y1665624D01*
X912657Y1665890D01*
X912457Y1666224D01*
Y1668157D01*
G01Y1666224D02*
X912257Y1665890D01*
X911924Y1665624D01*
X911457Y1665490D01*
X910990Y1665624D01*
X910657Y1665890D01*
X910457Y1666290D01*
Y1668157D01*
G01X907857Y1665490D02*
Y1668157D01*
G01Y1664424D02*
X907990Y1664357D01*
Y1664224D01*
X907857Y1664157D01*
X907724Y1664224D01*
Y1664357D01*
X907857Y1664424D01*
G01X903257Y1668157D02*
Y1664157D01*
G01X899657Y1667690D02*
X899324Y1667957D01*
X898857Y1668157D01*
X898457D01*
X898057Y1668024D01*
X897790Y1667824D01*
X897657Y1667557D01*
X897724Y1667157D01*
X897990Y1666957D01*
X899190Y1666557D01*
X899457Y1666090D01*
X899324Y1665757D01*
X899057Y1665557D01*
X898657Y1665490D01*
X898257Y1665557D01*
X897857Y1665757D01*
G01X992825Y-82667D02*
Y-78667D01*
X990358Y-81534D01*
X993692D01*
G01X995158Y-81867D02*
X995558Y-82334D01*
X996092Y-82600D01*
X996692Y-82667D01*
X997225Y-82600D01*
X997758Y-82267D01*
X998092Y-81867D01*
X998158Y-81467D01*
X998025Y-81000D01*
X997558Y-80667D01*
X997092Y-80534D01*
X996492D01*
G01X997092D02*
X997492Y-80334D01*
X997825Y-80000D01*
X997958Y-79600D01*
X997825Y-79200D01*
X997492Y-78867D01*
X996892Y-78667D01*
X996292Y-78734D01*
X995692Y-79000D01*
G01X999758Y-81867D02*
X1000158Y-82334D01*
X1000692Y-82600D01*
X1001292Y-82667D01*
X1001825Y-82600D01*
X1002358Y-82267D01*
X1002692Y-81867D01*
X1002758Y-81467D01*
X1002625Y-81000D01*
X1002158Y-80667D01*
X1001692Y-80534D01*
X1001092D01*
G01X1001692D02*
X1002092Y-80334D01*
X1002425Y-80000D01*
X1002558Y-79600D01*
X1002425Y-79200D01*
X1002092Y-78867D01*
X1001492Y-78667D01*
X1000892Y-78734D01*
X1000292Y-79000D01*
G01X1005825Y-82800D02*
X1005692Y-82734D01*
Y-82600D01*
X1005825Y-82534D01*
X1005958Y-82600D01*
Y-82734D01*
X1005825Y-82800D01*
G01X1010425Y-78667D02*
X1009892Y-78800D01*
X1009492Y-79134D01*
X1009225Y-79534D01*
X1009025Y-80067D01*
X1008958Y-80667D01*
X1009025Y-81267D01*
X1009225Y-81800D01*
X1009492Y-82200D01*
X1009892Y-82534D01*
X1010425Y-82667D01*
X1010958Y-82534D01*
X1011358Y-82200D01*
X1011625Y-81800D01*
X1011825Y-81267D01*
X1011892Y-80667D01*
X1011825Y-80067D01*
X1011625Y-79534D01*
X1011358Y-79134D01*
X1010958Y-78800D01*
X1010425Y-78667D01*
G01X1015025Y-82667D02*
X1015492Y-82600D01*
X1016025Y-82400D01*
X1016358Y-82067D01*
X1016492Y-81600D01*
X1016358Y-81134D01*
X1015958Y-80734D01*
X1015358Y-80534D01*
X1014692D01*
X1014292Y-80400D01*
X1013958Y-80067D01*
X1013825Y-79600D01*
X1014025Y-79134D01*
X1014492Y-78800D01*
X1015025Y-78667D01*
X1015558Y-78800D01*
X1016025Y-79134D01*
X1016225Y-79600D01*
X1016092Y-80067D01*
X1015758Y-80400D01*
X1015358Y-80534D01*
X1014692D01*
X1014092Y-80734D01*
X1013692Y-81134D01*
X1013558Y-81600D01*
X1013692Y-82067D01*
X1014025Y-82400D01*
X1014558Y-82600D01*
X1015025Y-82667D01*
G01X980492Y-66167D02*
Y-62167D01*
X981826D01*
X982359Y-62367D01*
X982759Y-62634D01*
X983092Y-63034D01*
X983359Y-63500D01*
X983426Y-64167D01*
X983359Y-64834D01*
X983092Y-65300D01*
X982759Y-65700D01*
X982359Y-65967D01*
X981826Y-66167D01*
X980492D01*
G01X985626D02*
Y-63500D01*
G01Y-64034D02*
X985959Y-63767D01*
X986292Y-63567D01*
X986759Y-63500D01*
X987092Y-63567D01*
X987492Y-63767D01*
G01X991159Y-63500D02*
Y-66167D01*
G01Y-62434D02*
X991026Y-62367D01*
Y-62234D01*
X991159Y-62167D01*
X991292Y-62234D01*
Y-62367D01*
X991159Y-62434D01*
G01X995759Y-66167D02*
Y-62167D01*
G01X1000359Y-66167D02*
Y-62167D01*
G01X1009159Y-66167D02*
Y-62767D01*
X1009292Y-62434D01*
X1009559Y-62234D01*
X1009959Y-62167D01*
X1010359Y-62300D01*
X1010559Y-62634D01*
G01X1009759Y-63767D02*
X1008426D01*
G01X1013159Y-64367D02*
X1015292D01*
X1015092Y-63900D01*
X1014759Y-63634D01*
X1014292Y-63500D01*
X1013826Y-63567D01*
X1013426Y-63767D01*
X1013159Y-64234D01*
X1013026Y-64634D01*
Y-65034D01*
X1013159Y-65434D01*
X1013492Y-65834D01*
X1013892Y-66100D01*
X1014359Y-66167D01*
X1014826Y-66034D01*
X1015292Y-65634D01*
G01X1019959Y-66167D02*
Y-63500D01*
G01Y-63967D02*
X1019692Y-63700D01*
X1019292Y-63567D01*
X1018826Y-63500D01*
X1018359Y-63634D01*
X1017959Y-63900D01*
X1017692Y-64300D01*
X1017559Y-64834D01*
X1017692Y-65367D01*
X1017959Y-65767D01*
X1018359Y-66034D01*
X1018826Y-66167D01*
X1019292Y-66100D01*
X1019692Y-65900D01*
X1019959Y-65634D01*
G01X1023359Y-62167D02*
Y-66167D01*
G01X1022426Y-63500D02*
X1024292D01*
G01X1026826D02*
Y-65367D01*
X1027092Y-65834D01*
X1027492Y-66100D01*
X1027959Y-66167D01*
X1028426Y-66100D01*
X1028826Y-65834D01*
X1029092Y-65367D01*
G01Y-66167D02*
Y-63500D01*
G01X1031626Y-66167D02*
Y-63500D01*
G01Y-64034D02*
X1031959Y-63767D01*
X1032292Y-63567D01*
X1032759Y-63500D01*
X1033092Y-63567D01*
X1033492Y-63767D01*
G01X1036159Y-64367D02*
X1038292D01*
X1038092Y-63900D01*
X1037759Y-63634D01*
X1037292Y-63500D01*
X1036826Y-63567D01*
X1036426Y-63767D01*
X1036159Y-64234D01*
X1036026Y-64634D01*
Y-65034D01*
X1036159Y-65434D01*
X1036492Y-65834D01*
X1036892Y-66100D01*
X1037359Y-66167D01*
X1037826Y-66034D01*
X1038292Y-65634D01*
G01X954565Y-42571D02*
G03X962731Y-57820I73077J29322D01*
G01X954564Y-42570D02*
G03X962732Y-57821I73076J29324D01*
G01X988245Y-22272D02*
X988645Y-21872D01*
X989112Y-21672D01*
X989645Y-21605D01*
X990312Y-21738D01*
X990779Y-22072D01*
X990912Y-22472D01*
X990845Y-22872D01*
X990579Y-23205D01*
X989245Y-23872D01*
X988645Y-24338D01*
X988245Y-25005D01*
X988112Y-25605D01*
X990912D01*
G01X994112Y-21605D02*
X993579Y-21738D01*
X993179Y-22072D01*
X992912Y-22472D01*
X992712Y-23005D01*
X992645Y-23605D01*
X992712Y-24205D01*
X992912Y-24738D01*
X993179Y-25138D01*
X993579Y-25472D01*
X994112Y-25605D01*
X994645Y-25472D01*
X995045Y-25138D01*
X995312Y-24738D01*
X995512Y-24205D01*
X995579Y-23605D01*
X995512Y-23005D01*
X995312Y-22472D01*
X995045Y-22072D01*
X994645Y-21738D01*
X994112Y-21605D01*
G01X998712Y-25605D02*
X999179Y-25538D01*
X999712Y-25338D01*
X1000045Y-25005D01*
X1000179Y-24538D01*
X1000045Y-24072D01*
X999645Y-23672D01*
X999045Y-23472D01*
X998379D01*
X997979Y-23338D01*
X997645Y-23005D01*
X997512Y-22538D01*
X997712Y-22072D01*
X998179Y-21738D01*
X998712Y-21605D01*
X999245Y-21738D01*
X999712Y-22072D01*
X999912Y-22538D01*
X999779Y-23005D01*
X999445Y-23338D01*
X999045Y-23472D01*
X998379D01*
X997779Y-23672D01*
X997379Y-24072D01*
X997245Y-24538D01*
X997379Y-25005D01*
X997712Y-25338D01*
X998245Y-25538D01*
X998712Y-25605D01*
G01X1003312Y-25738D02*
X1003179Y-25672D01*
Y-25538D01*
X1003312Y-25472D01*
X1003445Y-25538D01*
Y-25672D01*
X1003312Y-25738D01*
G01X1006645Y-23938D02*
X1007112Y-23472D01*
X1007512Y-23205D01*
X1008045Y-23072D01*
X1008512Y-23205D01*
X1008845Y-23472D01*
X1009112Y-23872D01*
X1009179Y-24338D01*
X1009112Y-24738D01*
X1008845Y-25138D01*
X1008445Y-25472D01*
X1007979Y-25605D01*
X1007445Y-25472D01*
X1006979Y-25072D01*
X1006712Y-24472D01*
X1006645Y-23805D01*
X1006779Y-22938D01*
X1006979Y-22472D01*
X1007312Y-22005D01*
X1007779Y-21672D01*
X1008245Y-21605D01*
X1008712Y-21738D01*
X1009045Y-22072D01*
G01X1011245Y-23938D02*
X1011712Y-23472D01*
X1012112Y-23205D01*
X1012645Y-23072D01*
X1013112Y-23205D01*
X1013445Y-23472D01*
X1013712Y-23872D01*
X1013779Y-24338D01*
X1013712Y-24738D01*
X1013445Y-25138D01*
X1013045Y-25472D01*
X1012579Y-25605D01*
X1012045Y-25472D01*
X1011579Y-25072D01*
X1011312Y-24472D01*
X1011245Y-23805D01*
X1011379Y-22938D01*
X1011579Y-22472D01*
X1011912Y-22005D01*
X1012379Y-21672D01*
X1012845Y-21605D01*
X1013312Y-21738D01*
X1013645Y-22072D01*
G01X971460Y51032D02*
X967460D01*
Y52632D01*
X967660Y53165D01*
X968127Y53565D01*
X968660Y53698D01*
X969193Y53565D01*
X969593Y53232D01*
X969793Y52632D01*
Y51032D01*
G01X971460Y56032D02*
X968793D01*
G01X969327D02*
X969060Y56365D01*
X968860Y56698D01*
X968793Y57165D01*
X968860Y57498D01*
X969060Y57898D01*
G01X969660Y60565D02*
Y62698D01*
X969193Y62498D01*
X968927Y62165D01*
X968793Y61698D01*
X968860Y61232D01*
X969060Y60832D01*
X969527Y60565D01*
X969927Y60432D01*
X970327D01*
X970727Y60565D01*
X971127Y60898D01*
X971393Y61298D01*
X971460Y61765D01*
X971327Y62232D01*
X970927Y62698D01*
G01X970993Y65165D02*
X971260Y65498D01*
X971460Y65965D01*
Y66365D01*
X971327Y66765D01*
X971127Y67032D01*
X970860Y67165D01*
X970460Y67098D01*
X970260Y66832D01*
X969860Y65632D01*
X969393Y65365D01*
X969060Y65498D01*
X968860Y65765D01*
X968793Y66165D01*
X968860Y66565D01*
X969060Y66965D01*
G01X970993Y69765D02*
X971260Y70098D01*
X971460Y70565D01*
Y70965D01*
X971327Y71365D01*
X971127Y71632D01*
X970860Y71765D01*
X970460Y71698D01*
X970260Y71432D01*
X969860Y70232D01*
X969393Y69965D01*
X969060Y70098D01*
X968860Y70365D01*
X968793Y70765D01*
X968860Y71165D01*
X969060Y71565D01*
G01X970127Y74498D02*
Y76232D01*
G01X971460Y79565D02*
X968060D01*
X967727Y79698D01*
X967527Y79965D01*
X967460Y80365D01*
X967593Y80765D01*
X967927Y80965D01*
G01X969060Y80165D02*
Y78832D01*
G01X968793Y84565D02*
X971460D01*
G01X967727D02*
X967660Y84432D01*
X967527D01*
X967460Y84565D01*
X967527Y84698D01*
X967660D01*
X967727Y84565D01*
G01X967460Y89165D02*
X971460D01*
G01X968793Y88232D02*
Y90098D01*
G01X971460Y97032D02*
X967460D01*
Y98632D01*
X967660Y99165D01*
X968127Y99565D01*
X968660Y99698D01*
X969193Y99565D01*
X969593Y99232D01*
X969793Y98632D01*
Y97032D01*
G01X967460Y102965D02*
X971460D01*
G01X967460Y101432D02*
Y104498D01*
G01X971460Y106165D02*
X967460D01*
G01Y108965D02*
X971460D01*
G01X969460D02*
Y106165D01*
G01X971460Y115632D02*
X967460D01*
G01X968793Y117765D02*
X970327Y115632D01*
G01X969727Y116498D02*
X971460Y117898D01*
G01X969660Y120365D02*
Y122498D01*
X969193Y122298D01*
X968927Y121965D01*
X968793Y121498D01*
X968860Y121032D01*
X969060Y120632D01*
X969527Y120365D01*
X969927Y120232D01*
X970327D01*
X970727Y120365D01*
X971127Y120698D01*
X971393Y121098D01*
X971460Y121565D01*
X971327Y122032D01*
X970927Y122498D01*
G01X969660Y124965D02*
Y127098D01*
X969193Y126898D01*
X968927Y126565D01*
X968793Y126098D01*
X968860Y125632D01*
X969060Y125232D01*
X969527Y124965D01*
X969927Y124832D01*
X970327D01*
X970727Y124965D01*
X971127Y125298D01*
X971393Y125698D01*
X971460Y126165D01*
X971327Y126632D01*
X970927Y127098D01*
G01X972793Y129365D02*
X968793D01*
G01X969393D02*
X969060Y129698D01*
X968860Y130032D01*
X968793Y130565D01*
X968860Y131032D01*
X969193Y131498D01*
X969660Y131698D01*
X970127Y131765D01*
X970593Y131698D01*
X971060Y131498D01*
X971327Y131098D01*
X971460Y130565D01*
X971393Y130098D01*
X971193Y129632D01*
X970927Y129365D01*
G01X971460Y138632D02*
X967460D01*
G01X969393D02*
X969060Y138965D01*
X968860Y139298D01*
X968793Y139832D01*
X968860Y140232D01*
X969127Y140698D01*
X969527Y140898D01*
X971460D01*
G01Y144365D02*
X971393Y143965D01*
X971127Y143565D01*
X970660Y143298D01*
X970127Y143165D01*
X969593Y143298D01*
X969127Y143565D01*
X968860Y143965D01*
X968793Y144365D01*
X968860Y144765D01*
X969127Y145165D01*
X969593Y145432D01*
X970127Y145498D01*
X970660Y145432D01*
X971127Y145165D01*
X971393Y144765D01*
X971460Y144365D01*
G01Y148965D02*
X967460D01*
G01X969660Y152565D02*
Y154698D01*
X969193Y154498D01*
X968927Y154165D01*
X968793Y153698D01*
X968860Y153232D01*
X969060Y152832D01*
X969527Y152565D01*
X969927Y152432D01*
X970327D01*
X970727Y152565D01*
X971127Y152898D01*
X971393Y153298D01*
X971460Y153765D01*
X971327Y154232D01*
X970927Y154698D01*
G01X970993Y161765D02*
X971260Y162098D01*
X971460Y162565D01*
Y162965D01*
X971327Y163365D01*
X971127Y163632D01*
X970860Y163765D01*
X970460Y163698D01*
X970260Y163432D01*
X969860Y162232D01*
X969393Y161965D01*
X969060Y162098D01*
X968860Y162365D01*
X968793Y162765D01*
X968860Y163165D01*
X969060Y163565D01*
G01X968793Y167365D02*
X971460D01*
G01X967727D02*
X967660Y167232D01*
X967527D01*
X967460Y167365D01*
X967527Y167498D01*
X967660D01*
X967727Y167365D01*
G01X968793Y170965D02*
Y172965D01*
X971460Y170965D01*
Y172965D01*
G01X969660Y175565D02*
Y177698D01*
X969193Y177498D01*
X968927Y177165D01*
X968793Y176698D01*
X968860Y176232D01*
X969060Y175832D01*
X969527Y175565D01*
X969927Y175432D01*
X970327D01*
X970727Y175565D01*
X971127Y175898D01*
X971393Y176298D01*
X971460Y176765D01*
X971327Y177232D01*
X970927Y177698D01*
G01X967460Y185765D02*
X971460D01*
G01X968793Y184832D02*
Y186698D01*
G01X971460Y190365D02*
X971393Y189965D01*
X971127Y189565D01*
X970660Y189298D01*
X970127Y189165D01*
X969593Y189298D01*
X969127Y189565D01*
X968860Y189965D01*
X968793Y190365D01*
X968860Y190765D01*
X969127Y191165D01*
X969593Y191432D01*
X970127Y191498D01*
X970660Y191432D01*
X971127Y191165D01*
X971393Y190765D01*
X971460Y190365D01*
G01Y194965D02*
X967460D01*
G01X969660Y198565D02*
Y200698D01*
X969193Y200498D01*
X968927Y200165D01*
X968793Y199698D01*
X968860Y199232D01*
X969060Y198832D01*
X969527Y198565D01*
X969927Y198432D01*
X970327D01*
X970727Y198565D01*
X971127Y198898D01*
X971393Y199298D01*
X971460Y199765D01*
X971327Y200232D01*
X970927Y200698D01*
G01X971460Y203232D02*
X968793D01*
G01X969327D02*
X969060Y203565D01*
X968860Y203898D01*
X968793Y204365D01*
X968860Y204698D01*
X969060Y205098D01*
G01X971460Y209965D02*
X968793D01*
G01X969260D02*
X968993Y209698D01*
X968860Y209298D01*
X968793Y208832D01*
X968927Y208365D01*
X969193Y207965D01*
X969593Y207698D01*
X970127Y207565D01*
X970660Y207698D01*
X971060Y207965D01*
X971327Y208365D01*
X971460Y208832D01*
X971393Y209298D01*
X971193Y209698D01*
X970927Y209965D01*
G01X971460Y212232D02*
X968793D01*
G01X969460D02*
X969127Y212498D01*
X968860Y212898D01*
X968793Y213432D01*
X968860Y213898D01*
X969127Y214298D01*
X969593Y214498D01*
X971460D01*
G01X969127Y219032D02*
X968860Y218565D01*
X968793Y218165D01*
X968927Y217632D01*
X969193Y217232D01*
X969660Y216965D01*
X970127Y216898D01*
X970593Y216965D01*
X970993Y217232D01*
X971327Y217632D01*
X971460Y218165D01*
X971327Y218632D01*
X971060Y219032D01*
G01X969660Y221565D02*
Y223698D01*
X969193Y223498D01*
X968927Y223165D01*
X968793Y222698D01*
X968860Y222232D01*
X969060Y221832D01*
X969527Y221565D01*
X969927Y221432D01*
X970327D01*
X970727Y221565D01*
X971127Y221898D01*
X971393Y222298D01*
X971460Y222765D01*
X971327Y223232D01*
X970927Y223698D01*
G01X970127Y231032D02*
Y232632D01*
G01X969260Y231765D02*
X970993D01*
G01X971593Y235165D02*
X967460Y237565D01*
G01X970127Y240098D02*
Y241832D01*
G01X968127Y244298D02*
X967727Y244698D01*
X967527Y245165D01*
X967460Y245698D01*
X967593Y246365D01*
X967927Y246832D01*
X968327Y246965D01*
X968727Y246898D01*
X969060Y246632D01*
X969727Y245298D01*
X970193Y244698D01*
X970860Y244298D01*
X971460Y244165D01*
Y246965D01*
G01Y252765D02*
X968793D01*
G01X969527D02*
X969193Y252965D01*
X968927Y253298D01*
X968793Y253765D01*
X968927Y254232D01*
X969193Y254565D01*
X969527Y254765D01*
X971460D01*
G01X969527D02*
X969193Y254965D01*
X968927Y255298D01*
X968793Y255765D01*
X968927Y256232D01*
X969193Y256565D01*
X969593Y256765D01*
X971460D01*
G01X968793Y259365D02*
X971460D01*
G01X967727D02*
X967660Y259232D01*
X967527D01*
X967460Y259365D01*
X967527Y259498D01*
X967660D01*
X967727Y259365D01*
G01X971460Y263965D02*
X967460D01*
G01X970993Y267565D02*
X971260Y267898D01*
X971460Y268365D01*
Y268765D01*
X971327Y269165D01*
X971127Y269432D01*
X970860Y269565D01*
X970460Y269498D01*
X970260Y269232D01*
X969860Y268032D01*
X969393Y267765D01*
X969060Y267898D01*
X968860Y268165D01*
X968793Y268565D01*
X968860Y268965D01*
X969060Y269365D01*
G01X958126Y136465D02*
X962126Y132465D01*
Y140465D01*
X958126Y136465D01*
X968126D01*
G01X971460Y430165D02*
X967460D01*
Y431765D01*
X967660Y432298D01*
X968127Y432698D01*
X968660Y432831D01*
X969193Y432698D01*
X969593Y432365D01*
X969793Y431765D01*
Y430165D01*
G01X971460Y435165D02*
X968793D01*
G01X969327D02*
X969060Y435498D01*
X968860Y435831D01*
X968793Y436298D01*
X968860Y436631D01*
X969060Y437031D01*
G01X969660Y439698D02*
Y441831D01*
X969193Y441631D01*
X968927Y441298D01*
X968793Y440831D01*
X968860Y440365D01*
X969060Y439965D01*
X969527Y439698D01*
X969927Y439565D01*
X970327D01*
X970727Y439698D01*
X971127Y440031D01*
X971393Y440431D01*
X971460Y440898D01*
X971327Y441365D01*
X970927Y441831D01*
G01X970993Y444298D02*
X971260Y444631D01*
X971460Y445098D01*
Y445498D01*
X971327Y445898D01*
X971127Y446165D01*
X970860Y446298D01*
X970460Y446231D01*
X970260Y445965D01*
X969860Y444765D01*
X969393Y444498D01*
X969060Y444631D01*
X968860Y444898D01*
X968793Y445298D01*
X968860Y445698D01*
X969060Y446098D01*
G01X970993Y448898D02*
X971260Y449231D01*
X971460Y449698D01*
Y450098D01*
X971327Y450498D01*
X971127Y450765D01*
X970860Y450898D01*
X970460Y450831D01*
X970260Y450565D01*
X969860Y449365D01*
X969393Y449098D01*
X969060Y449231D01*
X968860Y449498D01*
X968793Y449898D01*
X968860Y450298D01*
X969060Y450698D01*
G01X970127Y453631D02*
Y455365D01*
G01X971460Y458698D02*
X968060D01*
X967727Y458831D01*
X967527Y459098D01*
X967460Y459498D01*
X967593Y459898D01*
X967927Y460098D01*
G01X969060Y459298D02*
Y457965D01*
G01X968793Y463698D02*
X971460D01*
G01X967727D02*
X967660Y463565D01*
X967527D01*
X967460Y463698D01*
X967527Y463831D01*
X967660D01*
X967727Y463698D01*
G01X967460Y468298D02*
X971460D01*
G01X968793Y467365D02*
Y469231D01*
G01X971460Y476165D02*
X967460D01*
Y477765D01*
X967660Y478298D01*
X968127Y478698D01*
X968660Y478831D01*
X969193Y478698D01*
X969593Y478365D01*
X969793Y477765D01*
Y476165D01*
G01X967460Y482098D02*
X971460D01*
G01X967460Y480565D02*
Y483631D01*
G01X971460Y485298D02*
X967460D01*
G01Y488098D02*
X971460D01*
G01X969460D02*
Y485298D01*
G01X971460Y494765D02*
X967460D01*
G01X968793Y496898D02*
X970327Y494765D01*
G01X969727Y495631D02*
X971460Y497031D01*
G01X969660Y499498D02*
Y501631D01*
X969193Y501431D01*
X968927Y501098D01*
X968793Y500631D01*
X968860Y500165D01*
X969060Y499765D01*
X969527Y499498D01*
X969927Y499365D01*
X970327D01*
X970727Y499498D01*
X971127Y499831D01*
X971393Y500231D01*
X971460Y500698D01*
X971327Y501165D01*
X970927Y501631D01*
G01X969660Y504098D02*
Y506231D01*
X969193Y506031D01*
X968927Y505698D01*
X968793Y505231D01*
X968860Y504765D01*
X969060Y504365D01*
X969527Y504098D01*
X969927Y503965D01*
X970327D01*
X970727Y504098D01*
X971127Y504431D01*
X971393Y504831D01*
X971460Y505298D01*
X971327Y505765D01*
X970927Y506231D01*
G01X972793Y508498D02*
X968793D01*
G01X969393D02*
X969060Y508831D01*
X968860Y509165D01*
X968793Y509698D01*
X968860Y510165D01*
X969193Y510631D01*
X969660Y510831D01*
X970127Y510898D01*
X970593Y510831D01*
X971060Y510631D01*
X971327Y510231D01*
X971460Y509698D01*
X971393Y509231D01*
X971193Y508765D01*
X970927Y508498D01*
G01X971460Y517765D02*
X967460D01*
G01X969393D02*
X969060Y518098D01*
X968860Y518431D01*
X968793Y518965D01*
X968860Y519365D01*
X969127Y519831D01*
X969527Y520031D01*
X971460D01*
G01Y523498D02*
X971393Y523098D01*
X971127Y522698D01*
X970660Y522431D01*
X970127Y522298D01*
X969593Y522431D01*
X969127Y522698D01*
X968860Y523098D01*
X968793Y523498D01*
X968860Y523898D01*
X969127Y524298D01*
X969593Y524565D01*
X970127Y524631D01*
X970660Y524565D01*
X971127Y524298D01*
X971393Y523898D01*
X971460Y523498D01*
G01Y528098D02*
X967460D01*
G01X969660Y531698D02*
Y533831D01*
X969193Y533631D01*
X968927Y533298D01*
X968793Y532831D01*
X968860Y532365D01*
X969060Y531965D01*
X969527Y531698D01*
X969927Y531565D01*
X970327D01*
X970727Y531698D01*
X971127Y532031D01*
X971393Y532431D01*
X971460Y532898D01*
X971327Y533365D01*
X970927Y533831D01*
G01X970993Y540898D02*
X971260Y541231D01*
X971460Y541698D01*
Y542098D01*
X971327Y542498D01*
X971127Y542765D01*
X970860Y542898D01*
X970460Y542831D01*
X970260Y542565D01*
X969860Y541365D01*
X969393Y541098D01*
X969060Y541231D01*
X968860Y541498D01*
X968793Y541898D01*
X968860Y542298D01*
X969060Y542698D01*
G01X968793Y546498D02*
X971460D01*
G01X967727D02*
X967660Y546365D01*
X967527D01*
X967460Y546498D01*
X967527Y546631D01*
X967660D01*
X967727Y546498D01*
G01X968793Y550098D02*
Y552098D01*
X971460Y550098D01*
Y552098D01*
G01X969660Y554698D02*
Y556831D01*
X969193Y556631D01*
X968927Y556298D01*
X968793Y555831D01*
X968860Y555365D01*
X969060Y554965D01*
X969527Y554698D01*
X969927Y554565D01*
X970327D01*
X970727Y554698D01*
X971127Y555031D01*
X971393Y555431D01*
X971460Y555898D01*
X971327Y556365D01*
X970927Y556831D01*
G01X967460Y564898D02*
X971460D01*
G01X968793Y563965D02*
Y565831D01*
G01X971460Y569498D02*
X971393Y569098D01*
X971127Y568698D01*
X970660Y568431D01*
X970127Y568298D01*
X969593Y568431D01*
X969127Y568698D01*
X968860Y569098D01*
X968793Y569498D01*
X968860Y569898D01*
X969127Y570298D01*
X969593Y570565D01*
X970127Y570631D01*
X970660Y570565D01*
X971127Y570298D01*
X971393Y569898D01*
X971460Y569498D01*
G01Y574098D02*
X967460D01*
G01X969660Y577698D02*
Y579831D01*
X969193Y579631D01*
X968927Y579298D01*
X968793Y578831D01*
X968860Y578365D01*
X969060Y577965D01*
X969527Y577698D01*
X969927Y577565D01*
X970327D01*
X970727Y577698D01*
X971127Y578031D01*
X971393Y578431D01*
X971460Y578898D01*
X971327Y579365D01*
X970927Y579831D01*
G01X971460Y582365D02*
X968793D01*
G01X969327D02*
X969060Y582698D01*
X968860Y583031D01*
X968793Y583498D01*
X968860Y583831D01*
X969060Y584231D01*
G01X971460Y589098D02*
X968793D01*
G01X969260D02*
X968993Y588831D01*
X968860Y588431D01*
X968793Y587965D01*
X968927Y587498D01*
X969193Y587098D01*
X969593Y586831D01*
X970127Y586698D01*
X970660Y586831D01*
X971060Y587098D01*
X971327Y587498D01*
X971460Y587965D01*
X971393Y588431D01*
X971193Y588831D01*
X970927Y589098D01*
G01X971460Y591365D02*
X968793D01*
G01X969460D02*
X969127Y591631D01*
X968860Y592031D01*
X968793Y592565D01*
X968860Y593031D01*
X969127Y593431D01*
X969593Y593631D01*
X971460D01*
G01X969127Y598165D02*
X968860Y597698D01*
X968793Y597298D01*
X968927Y596765D01*
X969193Y596365D01*
X969660Y596098D01*
X970127Y596031D01*
X970593Y596098D01*
X970993Y596365D01*
X971327Y596765D01*
X971460Y597298D01*
X971327Y597765D01*
X971060Y598165D01*
G01X969660Y600698D02*
Y602831D01*
X969193Y602631D01*
X968927Y602298D01*
X968793Y601831D01*
X968860Y601365D01*
X969060Y600965D01*
X969527Y600698D01*
X969927Y600565D01*
X970327D01*
X970727Y600698D01*
X971127Y601031D01*
X971393Y601431D01*
X971460Y601898D01*
X971327Y602365D01*
X970927Y602831D01*
G01X970127Y610165D02*
Y611765D01*
G01X969260Y610898D02*
X970993D01*
G01X971593Y614298D02*
X967460Y616698D01*
G01X970127Y619231D02*
Y620965D01*
G01X968127Y623431D02*
X967727Y623831D01*
X967527Y624298D01*
X967460Y624831D01*
X967593Y625498D01*
X967927Y625965D01*
X968327Y626098D01*
X968727Y626031D01*
X969060Y625765D01*
X969727Y624431D01*
X970193Y623831D01*
X970860Y623431D01*
X971460Y623298D01*
Y626098D01*
G01Y631898D02*
X968793D01*
G01X969527D02*
X969193Y632098D01*
X968927Y632431D01*
X968793Y632898D01*
X968927Y633365D01*
X969193Y633698D01*
X969527Y633898D01*
X971460D01*
G01X969527D02*
X969193Y634098D01*
X968927Y634431D01*
X968793Y634898D01*
X968927Y635365D01*
X969193Y635698D01*
X969593Y635898D01*
X971460D01*
G01X968793Y638498D02*
X971460D01*
G01X967727D02*
X967660Y638365D01*
X967527D01*
X967460Y638498D01*
X967527Y638631D01*
X967660D01*
X967727Y638498D01*
G01X971460Y643098D02*
X967460D01*
G01X970993Y646698D02*
X971260Y647031D01*
X971460Y647498D01*
Y647898D01*
X971327Y648298D01*
X971127Y648565D01*
X970860Y648698D01*
X970460Y648631D01*
X970260Y648365D01*
X969860Y647165D01*
X969393Y646898D01*
X969060Y647031D01*
X968860Y647298D01*
X968793Y647698D01*
X968860Y648098D01*
X969060Y648498D01*
G01X958126Y515598D02*
X962126Y511598D01*
Y519598D01*
X958126Y515598D01*
X968126D01*
G01X971398Y1102252D02*
G03X978323Y1089122I37661J11472D01*
G01X971398Y1102252D02*
G03X978323Y1089121I37662J11471D01*
G01X971398Y1102252D02*
G03X951437I-9980J-3039D01*
G01X971398D02*
G03X951437I-9980J-3039D01*
G01X944512Y1089122D02*
G03X951437Y1102252I-30737J24602D01*
G01X944512Y1089121D02*
G03X951437Y1102252I-30737J24602D01*
G01X971398Y1444772D02*
G03X978323Y1431641I37662J11471D01*
G01X971398Y1444772D02*
G03X978323Y1431641I37662J11471D01*
G01X971398Y1444772D02*
G03X951437I-9980J-3040D01*
G01X944512Y1431641D02*
G03X951437Y1444772I-30737J24602D01*
G01X944512Y1431641D02*
G03X951437Y1444772I-30737J24602D01*
G01X971398D02*
G03X951437I-9980J-3039D01*
G01X1046657Y1587870D02*
X970666D01*
Y1651657D01*
X1046657D01*
Y1587870D01*
G01X1063229Y1658268D02*
X953658D01*
G01X994987Y-17540D02*
Y-13540D01*
X994187Y-14340D01*
G01Y-17540D02*
X995787D01*
G01X999587D02*
Y-13540D01*
X998787Y-14340D01*
G01Y-17540D02*
X1000387D01*
G01X1003054Y-17073D02*
X1003520Y-17407D01*
X1004054Y-17540D01*
X1004587Y-17407D01*
X1005054Y-17007D01*
X1005387Y-16407D01*
X1005520Y-15807D01*
Y-15073D01*
X1005387Y-14473D01*
X1005054Y-13940D01*
X1004654Y-13673D01*
X1004187Y-13540D01*
X1003654Y-13673D01*
X1003254Y-13940D01*
X1002987Y-14340D01*
X1002854Y-14873D01*
X1002987Y-15340D01*
X1003320Y-15807D01*
X1003720Y-16073D01*
X1004187Y-16140D01*
X1004720Y-16007D01*
X1005120Y-15673D01*
X1005520Y-15073D01*
G01X1007387Y-17540D02*
X1010187Y-13540D01*
G01X1007387D02*
X1010187Y-17540D01*
G01X1013387D02*
Y-13540D01*
X1012587Y-14340D01*
G01Y-17540D02*
X1014187D01*
G01X1016854Y-17073D02*
X1017320Y-17407D01*
X1017854Y-17540D01*
X1018387Y-17407D01*
X1018854Y-17007D01*
X1019187Y-16407D01*
X1019320Y-15807D01*
Y-15073D01*
X1019187Y-14473D01*
X1018854Y-13940D01*
X1018454Y-13673D01*
X1017987Y-13540D01*
X1017454Y-13673D01*
X1017054Y-13940D01*
X1016787Y-14340D01*
X1016654Y-14873D01*
X1016787Y-15340D01*
X1017120Y-15807D01*
X1017520Y-16073D01*
X1017987Y-16140D01*
X1018520Y-16007D01*
X1018920Y-15673D01*
X1019320Y-15073D01*
G01X1022454Y-17540D02*
X1022587Y-16673D01*
X1022787Y-15940D01*
X1023054Y-15273D01*
X1023387Y-14540D01*
X1023920Y-13540D01*
X1021254D01*
G01X1003015Y1044984D02*
Y1048984D01*
X1000548Y1046117D01*
X1003882D01*
G01X1005348Y1045784D02*
X1005748Y1045317D01*
X1006282Y1045051D01*
X1006882Y1044984D01*
X1007415Y1045051D01*
X1007948Y1045384D01*
X1008282Y1045784D01*
X1008348Y1046184D01*
X1008215Y1046651D01*
X1007748Y1046984D01*
X1007282Y1047117D01*
X1006682D01*
G01X1007282D02*
X1007682Y1047317D01*
X1008015Y1047651D01*
X1008148Y1048051D01*
X1008015Y1048451D01*
X1007682Y1048784D01*
X1007082Y1048984D01*
X1006482Y1048917D01*
X1005882Y1048651D01*
G01X1009948Y1045784D02*
X1010348Y1045317D01*
X1010882Y1045051D01*
X1011482Y1044984D01*
X1012015Y1045051D01*
X1012548Y1045384D01*
X1012882Y1045784D01*
X1012948Y1046184D01*
X1012815Y1046651D01*
X1012348Y1046984D01*
X1011882Y1047117D01*
X1011282D01*
G01X1011882D02*
X1012282Y1047317D01*
X1012615Y1047651D01*
X1012748Y1048051D01*
X1012615Y1048451D01*
X1012282Y1048784D01*
X1011682Y1048984D01*
X1011082Y1048917D01*
X1010482Y1048651D01*
G01X1016015Y1044851D02*
X1015882Y1044917D01*
Y1045051D01*
X1016015Y1045117D01*
X1016148Y1045051D01*
Y1044917D01*
X1016015Y1044851D01*
G01X1020615Y1048984D02*
X1020082Y1048851D01*
X1019682Y1048517D01*
X1019415Y1048117D01*
X1019215Y1047584D01*
X1019148Y1046984D01*
X1019215Y1046384D01*
X1019415Y1045851D01*
X1019682Y1045451D01*
X1020082Y1045117D01*
X1020615Y1044984D01*
X1021148Y1045117D01*
X1021548Y1045451D01*
X1021815Y1045851D01*
X1022015Y1046384D01*
X1022082Y1046984D01*
X1022015Y1047584D01*
X1021815Y1048117D01*
X1021548Y1048517D01*
X1021148Y1048851D01*
X1020615Y1048984D01*
G01X1025215Y1044984D02*
X1025682Y1045051D01*
X1026215Y1045251D01*
X1026548Y1045584D01*
X1026682Y1046051D01*
X1026548Y1046517D01*
X1026148Y1046917D01*
X1025548Y1047117D01*
X1024882D01*
X1024482Y1047251D01*
X1024148Y1047584D01*
X1024015Y1048051D01*
X1024215Y1048517D01*
X1024682Y1048851D01*
X1025215Y1048984D01*
X1025748Y1048851D01*
X1026215Y1048517D01*
X1026415Y1048051D01*
X1026282Y1047584D01*
X1025948Y1047251D01*
X1025548Y1047117D01*
X1024882D01*
X1024282Y1046917D01*
X1023882Y1046517D01*
X1023748Y1046051D01*
X1023882Y1045584D01*
X1024215Y1045251D01*
X1024748Y1045051D01*
X1025215Y1044984D01*
G01X1003107Y1129308D02*
X1003507Y1129708D01*
X1003974Y1129908D01*
X1004507Y1129975D01*
X1005174Y1129842D01*
X1005641Y1129508D01*
X1005774Y1129108D01*
X1005707Y1128708D01*
X1005441Y1128375D01*
X1004107Y1127708D01*
X1003507Y1127242D01*
X1003107Y1126575D01*
X1002974Y1125975D01*
X1005774D01*
G01X1008974Y1129975D02*
X1008441Y1129842D01*
X1008041Y1129508D01*
X1007774Y1129108D01*
X1007574Y1128575D01*
X1007507Y1127975D01*
X1007574Y1127375D01*
X1007774Y1126842D01*
X1008041Y1126442D01*
X1008441Y1126108D01*
X1008974Y1125975D01*
X1009507Y1126108D01*
X1009907Y1126442D01*
X1010174Y1126842D01*
X1010374Y1127375D01*
X1010441Y1127975D01*
X1010374Y1128575D01*
X1010174Y1129108D01*
X1009907Y1129508D01*
X1009507Y1129842D01*
X1008974Y1129975D01*
G01X1013574Y1125975D02*
X1014041Y1126042D01*
X1014574Y1126242D01*
X1014907Y1126575D01*
X1015041Y1127042D01*
X1014907Y1127508D01*
X1014507Y1127908D01*
X1013907Y1128108D01*
X1013241D01*
X1012841Y1128242D01*
X1012507Y1128575D01*
X1012374Y1129042D01*
X1012574Y1129508D01*
X1013041Y1129842D01*
X1013574Y1129975D01*
X1014107Y1129842D01*
X1014574Y1129508D01*
X1014774Y1129042D01*
X1014641Y1128575D01*
X1014307Y1128242D01*
X1013907Y1128108D01*
X1013241D01*
X1012641Y1127908D01*
X1012241Y1127508D01*
X1012107Y1127042D01*
X1012241Y1126575D01*
X1012574Y1126242D01*
X1013107Y1126042D01*
X1013574Y1125975D01*
G01X1018174Y1125842D02*
X1018041Y1125908D01*
Y1126042D01*
X1018174Y1126108D01*
X1018307Y1126042D01*
Y1125908D01*
X1018174Y1125842D01*
G01X1021507Y1127642D02*
X1021974Y1128108D01*
X1022374Y1128375D01*
X1022907Y1128508D01*
X1023374Y1128375D01*
X1023707Y1128108D01*
X1023974Y1127708D01*
X1024041Y1127242D01*
X1023974Y1126842D01*
X1023707Y1126442D01*
X1023307Y1126108D01*
X1022841Y1125975D01*
X1022307Y1126108D01*
X1021841Y1126508D01*
X1021574Y1127108D01*
X1021507Y1127775D01*
X1021641Y1128642D01*
X1021841Y1129108D01*
X1022174Y1129575D01*
X1022641Y1129908D01*
X1023107Y1129975D01*
X1023574Y1129842D01*
X1023907Y1129508D01*
G01X1026107Y1127642D02*
X1026574Y1128108D01*
X1026974Y1128375D01*
X1027507Y1128508D01*
X1027974Y1128375D01*
X1028307Y1128108D01*
X1028574Y1127708D01*
X1028641Y1127242D01*
X1028574Y1126842D01*
X1028307Y1126442D01*
X1027907Y1126108D01*
X1027441Y1125975D01*
X1026907Y1126108D01*
X1026441Y1126508D01*
X1026174Y1127108D01*
X1026107Y1127775D01*
X1026241Y1128642D01*
X1026441Y1129108D01*
X1026774Y1129575D01*
X1027241Y1129908D01*
X1027707Y1129975D01*
X1028174Y1129842D01*
X1028507Y1129508D01*
G01X996552Y1087141D02*
Y1091141D01*
X997886D01*
X998419Y1090941D01*
X998819Y1090674D01*
X999152Y1090274D01*
X999419Y1089808D01*
X999486Y1089141D01*
X999419Y1088474D01*
X999152Y1088008D01*
X998819Y1087608D01*
X998419Y1087341D01*
X997886Y1087141D01*
X996552D01*
G01X1001686D02*
Y1089808D01*
G01Y1089274D02*
X1002019Y1089541D01*
X1002352Y1089741D01*
X1002819Y1089808D01*
X1003152Y1089741D01*
X1003552Y1089541D01*
G01X1007219Y1089808D02*
Y1087141D01*
G01Y1090874D02*
X1007086Y1090941D01*
Y1091074D01*
X1007219Y1091141D01*
X1007352Y1091074D01*
Y1090941D01*
X1007219Y1090874D01*
G01X1011819Y1087141D02*
Y1091141D01*
G01X1016419Y1087141D02*
Y1091141D01*
G01X1025219Y1087141D02*
Y1090541D01*
X1025352Y1090874D01*
X1025619Y1091074D01*
X1026019Y1091141D01*
X1026419Y1091008D01*
X1026619Y1090674D01*
G01X1025819Y1089541D02*
X1024486D01*
G01X1029219Y1088941D02*
X1031352D01*
X1031152Y1089408D01*
X1030819Y1089674D01*
X1030352Y1089808D01*
X1029886Y1089741D01*
X1029486Y1089541D01*
X1029219Y1089074D01*
X1029086Y1088674D01*
Y1088274D01*
X1029219Y1087874D01*
X1029552Y1087474D01*
X1029952Y1087208D01*
X1030419Y1087141D01*
X1030886Y1087274D01*
X1031352Y1087674D01*
G01X1036019Y1087141D02*
Y1089808D01*
G01Y1089341D02*
X1035752Y1089608D01*
X1035352Y1089741D01*
X1034886Y1089808D01*
X1034419Y1089674D01*
X1034019Y1089408D01*
X1033752Y1089008D01*
X1033619Y1088474D01*
X1033752Y1087941D01*
X1034019Y1087541D01*
X1034419Y1087274D01*
X1034886Y1087141D01*
X1035352Y1087208D01*
X1035752Y1087408D01*
X1036019Y1087674D01*
G01X1039419Y1091141D02*
Y1087141D01*
G01X1038486Y1089808D02*
X1040352D01*
G01X1042886D02*
Y1087941D01*
X1043152Y1087474D01*
X1043552Y1087208D01*
X1044019Y1087141D01*
X1044486Y1087208D01*
X1044886Y1087474D01*
X1045152Y1087941D01*
G01Y1087141D02*
Y1089808D01*
G01X1047686Y1087141D02*
Y1089808D01*
G01Y1089274D02*
X1048019Y1089541D01*
X1048352Y1089741D01*
X1048819Y1089808D01*
X1049152Y1089741D01*
X1049552Y1089541D01*
G01X1052219Y1088941D02*
X1054352D01*
X1054152Y1089408D01*
X1053819Y1089674D01*
X1053352Y1089808D01*
X1052886Y1089741D01*
X1052486Y1089541D01*
X1052219Y1089074D01*
X1052086Y1088674D01*
Y1088274D01*
X1052219Y1087874D01*
X1052552Y1087474D01*
X1052952Y1087208D01*
X1053419Y1087141D01*
X1053886Y1087274D01*
X1054352Y1087674D01*
G01X1003015Y1387503D02*
Y1391503D01*
X1000548Y1388636D01*
X1003882D01*
G01X1005348Y1388303D02*
X1005748Y1387836D01*
X1006282Y1387570D01*
X1006882Y1387503D01*
X1007415Y1387570D01*
X1007948Y1387903D01*
X1008282Y1388303D01*
X1008348Y1388703D01*
X1008215Y1389170D01*
X1007748Y1389503D01*
X1007282Y1389636D01*
X1006682D01*
G01X1007282D02*
X1007682Y1389836D01*
X1008015Y1390170D01*
X1008148Y1390570D01*
X1008015Y1390970D01*
X1007682Y1391303D01*
X1007082Y1391503D01*
X1006482Y1391436D01*
X1005882Y1391170D01*
G01X1009948Y1388303D02*
X1010348Y1387836D01*
X1010882Y1387570D01*
X1011482Y1387503D01*
X1012015Y1387570D01*
X1012548Y1387903D01*
X1012882Y1388303D01*
X1012948Y1388703D01*
X1012815Y1389170D01*
X1012348Y1389503D01*
X1011882Y1389636D01*
X1011282D01*
G01X1011882D02*
X1012282Y1389836D01*
X1012615Y1390170D01*
X1012748Y1390570D01*
X1012615Y1390970D01*
X1012282Y1391303D01*
X1011682Y1391503D01*
X1011082Y1391436D01*
X1010482Y1391170D01*
G01X1016015Y1387370D02*
X1015882Y1387436D01*
Y1387570D01*
X1016015Y1387636D01*
X1016148Y1387570D01*
Y1387436D01*
X1016015Y1387370D01*
G01X1020615Y1391503D02*
X1020082Y1391370D01*
X1019682Y1391036D01*
X1019415Y1390636D01*
X1019215Y1390103D01*
X1019148Y1389503D01*
X1019215Y1388903D01*
X1019415Y1388370D01*
X1019682Y1387970D01*
X1020082Y1387636D01*
X1020615Y1387503D01*
X1021148Y1387636D01*
X1021548Y1387970D01*
X1021815Y1388370D01*
X1022015Y1388903D01*
X1022082Y1389503D01*
X1022015Y1390103D01*
X1021815Y1390636D01*
X1021548Y1391036D01*
X1021148Y1391370D01*
X1020615Y1391503D01*
G01X1025215Y1387503D02*
X1025682Y1387570D01*
X1026215Y1387770D01*
X1026548Y1388103D01*
X1026682Y1388570D01*
X1026548Y1389036D01*
X1026148Y1389436D01*
X1025548Y1389636D01*
X1024882D01*
X1024482Y1389770D01*
X1024148Y1390103D01*
X1024015Y1390570D01*
X1024215Y1391036D01*
X1024682Y1391370D01*
X1025215Y1391503D01*
X1025748Y1391370D01*
X1026215Y1391036D01*
X1026415Y1390570D01*
X1026282Y1390103D01*
X1025948Y1389770D01*
X1025548Y1389636D01*
X1024882D01*
X1024282Y1389436D01*
X1023882Y1389036D01*
X1023748Y1388570D01*
X1023882Y1388103D01*
X1024215Y1387770D01*
X1024748Y1387570D01*
X1025215Y1387503D01*
G01X1003107Y1471827D02*
X1003507Y1472227D01*
X1003974Y1472427D01*
X1004507Y1472494D01*
X1005174Y1472361D01*
X1005641Y1472027D01*
X1005774Y1471627D01*
X1005707Y1471227D01*
X1005441Y1470894D01*
X1004107Y1470227D01*
X1003507Y1469761D01*
X1003107Y1469094D01*
X1002974Y1468494D01*
X1005774D01*
G01X1008974Y1472494D02*
X1008441Y1472361D01*
X1008041Y1472027D01*
X1007774Y1471627D01*
X1007574Y1471094D01*
X1007507Y1470494D01*
X1007574Y1469894D01*
X1007774Y1469361D01*
X1008041Y1468961D01*
X1008441Y1468627D01*
X1008974Y1468494D01*
X1009507Y1468627D01*
X1009907Y1468961D01*
X1010174Y1469361D01*
X1010374Y1469894D01*
X1010441Y1470494D01*
X1010374Y1471094D01*
X1010174Y1471627D01*
X1009907Y1472027D01*
X1009507Y1472361D01*
X1008974Y1472494D01*
G01X1013574Y1468494D02*
X1014041Y1468561D01*
X1014574Y1468761D01*
X1014907Y1469094D01*
X1015041Y1469561D01*
X1014907Y1470027D01*
X1014507Y1470427D01*
X1013907Y1470627D01*
X1013241D01*
X1012841Y1470761D01*
X1012507Y1471094D01*
X1012374Y1471561D01*
X1012574Y1472027D01*
X1013041Y1472361D01*
X1013574Y1472494D01*
X1014107Y1472361D01*
X1014574Y1472027D01*
X1014774Y1471561D01*
X1014641Y1471094D01*
X1014307Y1470761D01*
X1013907Y1470627D01*
X1013241D01*
X1012641Y1470427D01*
X1012241Y1470027D01*
X1012107Y1469561D01*
X1012241Y1469094D01*
X1012574Y1468761D01*
X1013107Y1468561D01*
X1013574Y1468494D01*
G01X1018174Y1468361D02*
X1018041Y1468427D01*
Y1468561D01*
X1018174Y1468627D01*
X1018307Y1468561D01*
Y1468427D01*
X1018174Y1468361D01*
G01X1021507Y1470161D02*
X1021974Y1470627D01*
X1022374Y1470894D01*
X1022907Y1471027D01*
X1023374Y1470894D01*
X1023707Y1470627D01*
X1023974Y1470227D01*
X1024041Y1469761D01*
X1023974Y1469361D01*
X1023707Y1468961D01*
X1023307Y1468627D01*
X1022841Y1468494D01*
X1022307Y1468627D01*
X1021841Y1469027D01*
X1021574Y1469627D01*
X1021507Y1470294D01*
X1021641Y1471161D01*
X1021841Y1471627D01*
X1022174Y1472094D01*
X1022641Y1472427D01*
X1023107Y1472494D01*
X1023574Y1472361D01*
X1023907Y1472027D01*
G01X1026107Y1470161D02*
X1026574Y1470627D01*
X1026974Y1470894D01*
X1027507Y1471027D01*
X1027974Y1470894D01*
X1028307Y1470627D01*
X1028574Y1470227D01*
X1028641Y1469761D01*
X1028574Y1469361D01*
X1028307Y1468961D01*
X1027907Y1468627D01*
X1027441Y1468494D01*
X1026907Y1468627D01*
X1026441Y1469027D01*
X1026174Y1469627D01*
X1026107Y1470294D01*
X1026241Y1471161D01*
X1026441Y1471627D01*
X1026774Y1472094D01*
X1027241Y1472427D01*
X1027707Y1472494D01*
X1028174Y1472361D01*
X1028507Y1472027D01*
G01X996552Y1429660D02*
Y1433660D01*
X997886D01*
X998419Y1433460D01*
X998819Y1433193D01*
X999152Y1432793D01*
X999419Y1432327D01*
X999486Y1431660D01*
X999419Y1430993D01*
X999152Y1430527D01*
X998819Y1430127D01*
X998419Y1429860D01*
X997886Y1429660D01*
X996552D01*
G01X1001686D02*
Y1432327D01*
G01Y1431793D02*
X1002019Y1432060D01*
X1002352Y1432260D01*
X1002819Y1432327D01*
X1003152Y1432260D01*
X1003552Y1432060D01*
G01X1007219Y1432327D02*
Y1429660D01*
G01Y1433393D02*
X1007086Y1433460D01*
Y1433593D01*
X1007219Y1433660D01*
X1007352Y1433593D01*
Y1433460D01*
X1007219Y1433393D01*
G01X1011819Y1429660D02*
Y1433660D01*
G01X1016419Y1429660D02*
Y1433660D01*
G01X1025219Y1429660D02*
Y1433060D01*
X1025352Y1433393D01*
X1025619Y1433593D01*
X1026019Y1433660D01*
X1026419Y1433527D01*
X1026619Y1433193D01*
G01X1025819Y1432060D02*
X1024486D01*
G01X1029219Y1431460D02*
X1031352D01*
X1031152Y1431927D01*
X1030819Y1432193D01*
X1030352Y1432327D01*
X1029886Y1432260D01*
X1029486Y1432060D01*
X1029219Y1431593D01*
X1029086Y1431193D01*
Y1430793D01*
X1029219Y1430393D01*
X1029552Y1429993D01*
X1029952Y1429727D01*
X1030419Y1429660D01*
X1030886Y1429793D01*
X1031352Y1430193D01*
G01X1036019Y1429660D02*
Y1432327D01*
G01Y1431860D02*
X1035752Y1432127D01*
X1035352Y1432260D01*
X1034886Y1432327D01*
X1034419Y1432193D01*
X1034019Y1431927D01*
X1033752Y1431527D01*
X1033619Y1430993D01*
X1033752Y1430460D01*
X1034019Y1430060D01*
X1034419Y1429793D01*
X1034886Y1429660D01*
X1035352Y1429727D01*
X1035752Y1429927D01*
X1036019Y1430193D01*
G01X1039419Y1433660D02*
Y1429660D01*
G01X1038486Y1432327D02*
X1040352D01*
G01X1042886D02*
Y1430460D01*
X1043152Y1429993D01*
X1043552Y1429727D01*
X1044019Y1429660D01*
X1044486Y1429727D01*
X1044886Y1429993D01*
X1045152Y1430460D01*
G01Y1429660D02*
Y1432327D01*
G01X1047686Y1429660D02*
Y1432327D01*
G01Y1431793D02*
X1048019Y1432060D01*
X1048352Y1432260D01*
X1048819Y1432327D01*
X1049152Y1432260D01*
X1049552Y1432060D01*
G01X1052219Y1431460D02*
X1054352D01*
X1054152Y1431927D01*
X1053819Y1432193D01*
X1053352Y1432327D01*
X1052886Y1432260D01*
X1052486Y1432060D01*
X1052219Y1431593D01*
X1052086Y1431193D01*
Y1430793D01*
X1052219Y1430393D01*
X1052552Y1429993D01*
X1052952Y1429727D01*
X1053419Y1429660D01*
X1053886Y1429793D01*
X1054352Y1430193D01*
G01X1023407Y1664207D02*
X1023307Y1651607D01*
X1018307Y1656607D01*
X1028307D01*
X1023307Y1651607D01*
G01X1075865Y1120631D02*
X1079865D01*
Y1119031D01*
X1079665Y1118498D01*
X1079198Y1118098D01*
X1078665Y1117965D01*
X1078132Y1118098D01*
X1077732Y1118431D01*
X1077532Y1119031D01*
Y1120631D01*
G01X1075865Y1115631D02*
X1078532D01*
G01X1077998D02*
X1078265Y1115298D01*
X1078465Y1114965D01*
X1078532Y1114498D01*
X1078465Y1114165D01*
X1078265Y1113765D01*
G01X1077665Y1111098D02*
Y1108965D01*
X1078132Y1109165D01*
X1078398Y1109498D01*
X1078532Y1109965D01*
X1078465Y1110431D01*
X1078265Y1110831D01*
X1077798Y1111098D01*
X1077398Y1111231D01*
X1076998D01*
X1076598Y1111098D01*
X1076198Y1110765D01*
X1075932Y1110365D01*
X1075865Y1109898D01*
X1075998Y1109431D01*
X1076398Y1108965D01*
G01X1076332Y1106498D02*
X1076065Y1106165D01*
X1075865Y1105698D01*
Y1105298D01*
X1075998Y1104898D01*
X1076198Y1104631D01*
X1076465Y1104498D01*
X1076865Y1104565D01*
X1077065Y1104831D01*
X1077465Y1106031D01*
X1077932Y1106298D01*
X1078265Y1106165D01*
X1078465Y1105898D01*
X1078532Y1105498D01*
X1078465Y1105098D01*
X1078265Y1104698D01*
G01X1076332Y1101898D02*
X1076065Y1101565D01*
X1075865Y1101098D01*
Y1100698D01*
X1075998Y1100298D01*
X1076198Y1100031D01*
X1076465Y1099898D01*
X1076865Y1099965D01*
X1077065Y1100231D01*
X1077465Y1101431D01*
X1077932Y1101698D01*
X1078265Y1101565D01*
X1078465Y1101298D01*
X1078532Y1100898D01*
X1078465Y1100498D01*
X1078265Y1100098D01*
G01X1077198Y1097165D02*
Y1095431D01*
G01X1075865Y1092098D02*
X1079265D01*
X1079598Y1091965D01*
X1079798Y1091698D01*
X1079865Y1091298D01*
X1079732Y1090898D01*
X1079398Y1090698D01*
G01X1078265Y1091498D02*
Y1092831D01*
G01X1078532Y1087098D02*
X1075865D01*
G01X1079598D02*
X1079665Y1087231D01*
X1079798D01*
X1079865Y1087098D01*
X1079798Y1086965D01*
X1079665D01*
X1079598Y1087098D01*
G01X1079865Y1082498D02*
X1075865D01*
G01X1078532Y1083431D02*
Y1081565D01*
G01X1075865Y1074631D02*
X1079865D01*
Y1073031D01*
X1079665Y1072498D01*
X1079198Y1072098D01*
X1078665Y1071965D01*
X1078132Y1072098D01*
X1077732Y1072431D01*
X1077532Y1073031D01*
Y1074631D01*
G01X1079865Y1068698D02*
X1075865D01*
G01X1079865Y1070231D02*
Y1067165D01*
G01X1075865Y1065498D02*
X1079865D01*
G01Y1062698D02*
X1075865D01*
G01X1077865D02*
Y1065498D01*
G01X1075865Y1056031D02*
X1079865D01*
G01X1078532Y1053898D02*
X1076998Y1056031D01*
G01X1077598Y1055165D02*
X1075865Y1053765D01*
G01X1077665Y1051298D02*
Y1049165D01*
X1078132Y1049365D01*
X1078398Y1049698D01*
X1078532Y1050165D01*
X1078465Y1050631D01*
X1078265Y1051031D01*
X1077798Y1051298D01*
X1077398Y1051431D01*
X1076998D01*
X1076598Y1051298D01*
X1076198Y1050965D01*
X1075932Y1050565D01*
X1075865Y1050098D01*
X1075998Y1049631D01*
X1076398Y1049165D01*
G01X1077665Y1046698D02*
Y1044565D01*
X1078132Y1044765D01*
X1078398Y1045098D01*
X1078532Y1045565D01*
X1078465Y1046031D01*
X1078265Y1046431D01*
X1077798Y1046698D01*
X1077398Y1046831D01*
X1076998D01*
X1076598Y1046698D01*
X1076198Y1046365D01*
X1075932Y1045965D01*
X1075865Y1045498D01*
X1075998Y1045031D01*
X1076398Y1044565D01*
G01X1074532Y1042298D02*
X1078532D01*
G01X1077932D02*
X1078265Y1041965D01*
X1078465Y1041631D01*
X1078532Y1041098D01*
X1078465Y1040631D01*
X1078132Y1040165D01*
X1077665Y1039965D01*
X1077198Y1039898D01*
X1076732Y1039965D01*
X1076265Y1040165D01*
X1075998Y1040565D01*
X1075865Y1041098D01*
X1075932Y1041565D01*
X1076132Y1042031D01*
X1076398Y1042298D01*
G01X1075865Y1033031D02*
X1079865D01*
G01X1077932D02*
X1078265Y1032698D01*
X1078465Y1032365D01*
X1078532Y1031831D01*
X1078465Y1031431D01*
X1078198Y1030965D01*
X1077798Y1030765D01*
X1075865D01*
G01Y1027298D02*
X1075932Y1027698D01*
X1076198Y1028098D01*
X1076665Y1028365D01*
X1077198Y1028498D01*
X1077732Y1028365D01*
X1078198Y1028098D01*
X1078465Y1027698D01*
X1078532Y1027298D01*
X1078465Y1026898D01*
X1078198Y1026498D01*
X1077732Y1026231D01*
X1077198Y1026165D01*
X1076665Y1026231D01*
X1076198Y1026498D01*
X1075932Y1026898D01*
X1075865Y1027298D01*
G01Y1022698D02*
X1079865D01*
G01X1077665Y1019098D02*
Y1016965D01*
X1078132Y1017165D01*
X1078398Y1017498D01*
X1078532Y1017965D01*
X1078465Y1018431D01*
X1078265Y1018831D01*
X1077798Y1019098D01*
X1077398Y1019231D01*
X1076998D01*
X1076598Y1019098D01*
X1076198Y1018765D01*
X1075932Y1018365D01*
X1075865Y1017898D01*
X1075998Y1017431D01*
X1076398Y1016965D01*
G01X1076332Y1009898D02*
X1076065Y1009565D01*
X1075865Y1009098D01*
Y1008698D01*
X1075998Y1008298D01*
X1076198Y1008031D01*
X1076465Y1007898D01*
X1076865Y1007965D01*
X1077065Y1008231D01*
X1077465Y1009431D01*
X1077932Y1009698D01*
X1078265Y1009565D01*
X1078465Y1009298D01*
X1078532Y1008898D01*
X1078465Y1008498D01*
X1078265Y1008098D01*
G01X1078532Y1004298D02*
X1075865D01*
G01X1079598D02*
X1079665Y1004431D01*
X1079798D01*
X1079865Y1004298D01*
X1079798Y1004165D01*
X1079665D01*
X1079598Y1004298D01*
G01X1078532Y1000698D02*
Y998698D01*
X1075865Y1000698D01*
Y998698D01*
G01X1077665Y996098D02*
Y993965D01*
X1078132Y994165D01*
X1078398Y994498D01*
X1078532Y994965D01*
X1078465Y995431D01*
X1078265Y995831D01*
X1077798Y996098D01*
X1077398Y996231D01*
X1076998D01*
X1076598Y996098D01*
X1076198Y995765D01*
X1075932Y995365D01*
X1075865Y994898D01*
X1075998Y994431D01*
X1076398Y993965D01*
G01X1079865Y985898D02*
X1075865D01*
G01X1078532Y986831D02*
Y984965D01*
G01X1075865Y981298D02*
X1075932Y981698D01*
X1076198Y982098D01*
X1076665Y982365D01*
X1077198Y982498D01*
X1077732Y982365D01*
X1078198Y982098D01*
X1078465Y981698D01*
X1078532Y981298D01*
X1078465Y980898D01*
X1078198Y980498D01*
X1077732Y980231D01*
X1077198Y980165D01*
X1076665Y980231D01*
X1076198Y980498D01*
X1075932Y980898D01*
X1075865Y981298D01*
G01Y976698D02*
X1079865D01*
G01X1077665Y973098D02*
Y970965D01*
X1078132Y971165D01*
X1078398Y971498D01*
X1078532Y971965D01*
X1078465Y972431D01*
X1078265Y972831D01*
X1077798Y973098D01*
X1077398Y973231D01*
X1076998D01*
X1076598Y973098D01*
X1076198Y972765D01*
X1075932Y972365D01*
X1075865Y971898D01*
X1075998Y971431D01*
X1076398Y970965D01*
G01X1075865Y968431D02*
X1078532D01*
G01X1077998D02*
X1078265Y968098D01*
X1078465Y967765D01*
X1078532Y967298D01*
X1078465Y966965D01*
X1078265Y966565D01*
G01X1075865Y961698D02*
X1078532D01*
G01X1078065D02*
X1078332Y961965D01*
X1078465Y962365D01*
X1078532Y962831D01*
X1078398Y963298D01*
X1078132Y963698D01*
X1077732Y963965D01*
X1077198Y964098D01*
X1076665Y963965D01*
X1076265Y963698D01*
X1075998Y963298D01*
X1075865Y962831D01*
X1075932Y962365D01*
X1076132Y961965D01*
X1076398Y961698D01*
G01X1075865Y959431D02*
X1078532D01*
G01X1077865D02*
X1078198Y959165D01*
X1078465Y958765D01*
X1078532Y958231D01*
X1078465Y957765D01*
X1078198Y957365D01*
X1077732Y957165D01*
X1075865D01*
G01X1078198Y952631D02*
X1078465Y953098D01*
X1078532Y953498D01*
X1078398Y954031D01*
X1078132Y954431D01*
X1077665Y954698D01*
X1077198Y954765D01*
X1076732Y954698D01*
X1076332Y954431D01*
X1075998Y954031D01*
X1075865Y953498D01*
X1075998Y953031D01*
X1076265Y952631D01*
G01X1077665Y950098D02*
Y947965D01*
X1078132Y948165D01*
X1078398Y948498D01*
X1078532Y948965D01*
X1078465Y949431D01*
X1078265Y949831D01*
X1077798Y950098D01*
X1077398Y950231D01*
X1076998D01*
X1076598Y950098D01*
X1076198Y949765D01*
X1075932Y949365D01*
X1075865Y948898D01*
X1075998Y948431D01*
X1076398Y947965D01*
G01X1077198Y940631D02*
Y939031D01*
G01X1078065Y939898D02*
X1076332D01*
G01X1075732Y936498D02*
X1079865Y934098D01*
G01X1077198Y931565D02*
Y929831D01*
G01X1079198Y927365D02*
X1079598Y926965D01*
X1079798Y926498D01*
X1079865Y925965D01*
X1079732Y925298D01*
X1079398Y924831D01*
X1078998Y924698D01*
X1078598Y924765D01*
X1078265Y925031D01*
X1077598Y926365D01*
X1077132Y926965D01*
X1076465Y927365D01*
X1075865Y927498D01*
Y924698D01*
G01Y918898D02*
X1078532D01*
G01X1077798D02*
X1078132Y918698D01*
X1078398Y918365D01*
X1078532Y917898D01*
X1078398Y917431D01*
X1078132Y917098D01*
X1077798Y916898D01*
X1075865D01*
G01X1077798D02*
X1078132Y916698D01*
X1078398Y916365D01*
X1078532Y915898D01*
X1078398Y915431D01*
X1078132Y915098D01*
X1077732Y914898D01*
X1075865D01*
G01X1078532Y912298D02*
X1075865D01*
G01X1079598D02*
X1079665Y912431D01*
X1079798D01*
X1079865Y912298D01*
X1079798Y912165D01*
X1079665D01*
X1079598Y912298D01*
G01X1075865Y907698D02*
X1079865D01*
G01X1076332Y904098D02*
X1076065Y903765D01*
X1075865Y903298D01*
Y902898D01*
X1075998Y902498D01*
X1076198Y902231D01*
X1076465Y902098D01*
X1076865Y902165D01*
X1077065Y902431D01*
X1077465Y903631D01*
X1077932Y903898D01*
X1078265Y903765D01*
X1078465Y903498D01*
X1078532Y903098D01*
X1078465Y902698D01*
X1078265Y902298D01*
G01X1078589Y1014198D02*
X1088289D01*
X1083289Y1009198D01*
Y1019198D01*
X1088289Y1014198D01*
G01X1076715Y1406121D02*
X1080715D01*
Y1404521D01*
X1080515Y1403988D01*
X1080048Y1403588D01*
X1079515Y1403455D01*
X1078982Y1403588D01*
X1078582Y1403921D01*
X1078382Y1404521D01*
Y1406121D01*
G01X1076715Y1401121D02*
X1079382D01*
G01X1078848D02*
X1079115Y1400788D01*
X1079315Y1400455D01*
X1079382Y1399988D01*
X1079315Y1399655D01*
X1079115Y1399255D01*
G01X1078515Y1396588D02*
Y1394455D01*
X1078982Y1394655D01*
X1079248Y1394988D01*
X1079382Y1395455D01*
X1079315Y1395921D01*
X1079115Y1396321D01*
X1078648Y1396588D01*
X1078248Y1396721D01*
X1077848D01*
X1077448Y1396588D01*
X1077048Y1396255D01*
X1076782Y1395855D01*
X1076715Y1395388D01*
X1076848Y1394921D01*
X1077248Y1394455D01*
G01X1077182Y1391988D02*
X1076915Y1391655D01*
X1076715Y1391188D01*
Y1390788D01*
X1076848Y1390388D01*
X1077048Y1390121D01*
X1077315Y1389988D01*
X1077715Y1390055D01*
X1077915Y1390321D01*
X1078315Y1391521D01*
X1078782Y1391788D01*
X1079115Y1391655D01*
X1079315Y1391388D01*
X1079382Y1390988D01*
X1079315Y1390588D01*
X1079115Y1390188D01*
G01X1077182Y1387388D02*
X1076915Y1387055D01*
X1076715Y1386588D01*
Y1386188D01*
X1076848Y1385788D01*
X1077048Y1385521D01*
X1077315Y1385388D01*
X1077715Y1385455D01*
X1077915Y1385721D01*
X1078315Y1386921D01*
X1078782Y1387188D01*
X1079115Y1387055D01*
X1079315Y1386788D01*
X1079382Y1386388D01*
X1079315Y1385988D01*
X1079115Y1385588D01*
G01X1078048Y1382655D02*
Y1380921D01*
G01X1076715Y1377588D02*
X1080115D01*
X1080448Y1377455D01*
X1080648Y1377188D01*
X1080715Y1376788D01*
X1080582Y1376388D01*
X1080248Y1376188D01*
G01X1079115Y1376988D02*
Y1378321D01*
G01X1079382Y1372588D02*
X1076715D01*
G01X1080448D02*
X1080515Y1372721D01*
X1080648D01*
X1080715Y1372588D01*
X1080648Y1372455D01*
X1080515D01*
X1080448Y1372588D01*
G01X1080715Y1367988D02*
X1076715D01*
G01X1079382Y1368921D02*
Y1367055D01*
G01X1076715Y1360121D02*
X1080715D01*
Y1358521D01*
X1080515Y1357988D01*
X1080048Y1357588D01*
X1079515Y1357455D01*
X1078982Y1357588D01*
X1078582Y1357921D01*
X1078382Y1358521D01*
Y1360121D01*
G01X1080715Y1354188D02*
X1076715D01*
G01X1080715Y1355721D02*
Y1352655D01*
G01X1076715Y1350988D02*
X1080715D01*
G01Y1348188D02*
X1076715D01*
G01X1078715D02*
Y1350988D01*
G01X1076715Y1341521D02*
X1080715D01*
G01X1079382Y1339388D02*
X1077848Y1341521D01*
G01X1078448Y1340655D02*
X1076715Y1339255D01*
G01X1078515Y1336788D02*
Y1334655D01*
X1078982Y1334855D01*
X1079248Y1335188D01*
X1079382Y1335655D01*
X1079315Y1336121D01*
X1079115Y1336521D01*
X1078648Y1336788D01*
X1078248Y1336921D01*
X1077848D01*
X1077448Y1336788D01*
X1077048Y1336455D01*
X1076782Y1336055D01*
X1076715Y1335588D01*
X1076848Y1335121D01*
X1077248Y1334655D01*
G01X1078515Y1332188D02*
Y1330055D01*
X1078982Y1330255D01*
X1079248Y1330588D01*
X1079382Y1331055D01*
X1079315Y1331521D01*
X1079115Y1331921D01*
X1078648Y1332188D01*
X1078248Y1332321D01*
X1077848D01*
X1077448Y1332188D01*
X1077048Y1331855D01*
X1076782Y1331455D01*
X1076715Y1330988D01*
X1076848Y1330521D01*
X1077248Y1330055D01*
G01X1075382Y1327788D02*
X1079382D01*
G01X1078782D02*
X1079115Y1327455D01*
X1079315Y1327121D01*
X1079382Y1326588D01*
X1079315Y1326121D01*
X1078982Y1325655D01*
X1078515Y1325455D01*
X1078048Y1325388D01*
X1077582Y1325455D01*
X1077115Y1325655D01*
X1076848Y1326055D01*
X1076715Y1326588D01*
X1076782Y1327055D01*
X1076982Y1327521D01*
X1077248Y1327788D01*
G01X1076715Y1318521D02*
X1080715D01*
G01X1078782D02*
X1079115Y1318188D01*
X1079315Y1317855D01*
X1079382Y1317321D01*
X1079315Y1316921D01*
X1079048Y1316455D01*
X1078648Y1316255D01*
X1076715D01*
G01Y1312788D02*
X1076782Y1313188D01*
X1077048Y1313588D01*
X1077515Y1313855D01*
X1078048Y1313988D01*
X1078582Y1313855D01*
X1079048Y1313588D01*
X1079315Y1313188D01*
X1079382Y1312788D01*
X1079315Y1312388D01*
X1079048Y1311988D01*
X1078582Y1311721D01*
X1078048Y1311655D01*
X1077515Y1311721D01*
X1077048Y1311988D01*
X1076782Y1312388D01*
X1076715Y1312788D01*
G01Y1308188D02*
X1080715D01*
G01X1078515Y1304588D02*
Y1302455D01*
X1078982Y1302655D01*
X1079248Y1302988D01*
X1079382Y1303455D01*
X1079315Y1303921D01*
X1079115Y1304321D01*
X1078648Y1304588D01*
X1078248Y1304721D01*
X1077848D01*
X1077448Y1304588D01*
X1077048Y1304255D01*
X1076782Y1303855D01*
X1076715Y1303388D01*
X1076848Y1302921D01*
X1077248Y1302455D01*
G01X1077182Y1295388D02*
X1076915Y1295055D01*
X1076715Y1294588D01*
Y1294188D01*
X1076848Y1293788D01*
X1077048Y1293521D01*
X1077315Y1293388D01*
X1077715Y1293455D01*
X1077915Y1293721D01*
X1078315Y1294921D01*
X1078782Y1295188D01*
X1079115Y1295055D01*
X1079315Y1294788D01*
X1079382Y1294388D01*
X1079315Y1293988D01*
X1079115Y1293588D01*
G01X1079382Y1289788D02*
X1076715D01*
G01X1080448D02*
X1080515Y1289921D01*
X1080648D01*
X1080715Y1289788D01*
X1080648Y1289655D01*
X1080515D01*
X1080448Y1289788D01*
G01X1079382Y1286188D02*
Y1284188D01*
X1076715Y1286188D01*
Y1284188D01*
G01X1078515Y1281588D02*
Y1279455D01*
X1078982Y1279655D01*
X1079248Y1279988D01*
X1079382Y1280455D01*
X1079315Y1280921D01*
X1079115Y1281321D01*
X1078648Y1281588D01*
X1078248Y1281721D01*
X1077848D01*
X1077448Y1281588D01*
X1077048Y1281255D01*
X1076782Y1280855D01*
X1076715Y1280388D01*
X1076848Y1279921D01*
X1077248Y1279455D01*
G01X1080715Y1271388D02*
X1076715D01*
G01X1079382Y1272321D02*
Y1270455D01*
G01X1076715Y1266788D02*
X1076782Y1267188D01*
X1077048Y1267588D01*
X1077515Y1267855D01*
X1078048Y1267988D01*
X1078582Y1267855D01*
X1079048Y1267588D01*
X1079315Y1267188D01*
X1079382Y1266788D01*
X1079315Y1266388D01*
X1079048Y1265988D01*
X1078582Y1265721D01*
X1078048Y1265655D01*
X1077515Y1265721D01*
X1077048Y1265988D01*
X1076782Y1266388D01*
X1076715Y1266788D01*
G01Y1262188D02*
X1080715D01*
G01X1078515Y1258588D02*
Y1256455D01*
X1078982Y1256655D01*
X1079248Y1256988D01*
X1079382Y1257455D01*
X1079315Y1257921D01*
X1079115Y1258321D01*
X1078648Y1258588D01*
X1078248Y1258721D01*
X1077848D01*
X1077448Y1258588D01*
X1077048Y1258255D01*
X1076782Y1257855D01*
X1076715Y1257388D01*
X1076848Y1256921D01*
X1077248Y1256455D01*
G01X1076715Y1253921D02*
X1079382D01*
G01X1078848D02*
X1079115Y1253588D01*
X1079315Y1253255D01*
X1079382Y1252788D01*
X1079315Y1252455D01*
X1079115Y1252055D01*
G01X1076715Y1247188D02*
X1079382D01*
G01X1078915D02*
X1079182Y1247455D01*
X1079315Y1247855D01*
X1079382Y1248321D01*
X1079248Y1248788D01*
X1078982Y1249188D01*
X1078582Y1249455D01*
X1078048Y1249588D01*
X1077515Y1249455D01*
X1077115Y1249188D01*
X1076848Y1248788D01*
X1076715Y1248321D01*
X1076782Y1247855D01*
X1076982Y1247455D01*
X1077248Y1247188D01*
G01X1076715Y1244921D02*
X1079382D01*
G01X1078715D02*
X1079048Y1244655D01*
X1079315Y1244255D01*
X1079382Y1243721D01*
X1079315Y1243255D01*
X1079048Y1242855D01*
X1078582Y1242655D01*
X1076715D01*
G01X1079048Y1238121D02*
X1079315Y1238588D01*
X1079382Y1238988D01*
X1079248Y1239521D01*
X1078982Y1239921D01*
X1078515Y1240188D01*
X1078048Y1240255D01*
X1077582Y1240188D01*
X1077182Y1239921D01*
X1076848Y1239521D01*
X1076715Y1238988D01*
X1076848Y1238521D01*
X1077115Y1238121D01*
G01X1078515Y1235588D02*
Y1233455D01*
X1078982Y1233655D01*
X1079248Y1233988D01*
X1079382Y1234455D01*
X1079315Y1234921D01*
X1079115Y1235321D01*
X1078648Y1235588D01*
X1078248Y1235721D01*
X1077848D01*
X1077448Y1235588D01*
X1077048Y1235255D01*
X1076782Y1234855D01*
X1076715Y1234388D01*
X1076848Y1233921D01*
X1077248Y1233455D01*
G01X1078048Y1226121D02*
Y1224521D01*
G01X1078915Y1225388D02*
X1077182D01*
G01X1076582Y1221988D02*
X1080715Y1219588D01*
G01X1078048Y1217055D02*
Y1215321D01*
G01X1080048Y1212855D02*
X1080448Y1212455D01*
X1080648Y1211988D01*
X1080715Y1211455D01*
X1080582Y1210788D01*
X1080248Y1210321D01*
X1079848Y1210188D01*
X1079448Y1210255D01*
X1079115Y1210521D01*
X1078448Y1211855D01*
X1077982Y1212455D01*
X1077315Y1212855D01*
X1076715Y1212988D01*
Y1210188D01*
G01Y1204388D02*
X1079382D01*
G01X1078648D02*
X1078982Y1204188D01*
X1079248Y1203855D01*
X1079382Y1203388D01*
X1079248Y1202921D01*
X1078982Y1202588D01*
X1078648Y1202388D01*
X1076715D01*
G01X1078648D02*
X1078982Y1202188D01*
X1079248Y1201855D01*
X1079382Y1201388D01*
X1079248Y1200921D01*
X1078982Y1200588D01*
X1078582Y1200388D01*
X1076715D01*
G01X1079382Y1197788D02*
X1076715D01*
G01X1080448D02*
X1080515Y1197921D01*
X1080648D01*
X1080715Y1197788D01*
X1080648Y1197655D01*
X1080515D01*
X1080448Y1197788D01*
G01X1076715Y1193188D02*
X1080715D01*
G01X1077182Y1189588D02*
X1076915Y1189255D01*
X1076715Y1188788D01*
Y1188388D01*
X1076848Y1187988D01*
X1077048Y1187721D01*
X1077315Y1187588D01*
X1077715Y1187655D01*
X1077915Y1187921D01*
X1078315Y1189121D01*
X1078782Y1189388D01*
X1079115Y1189255D01*
X1079315Y1188988D01*
X1079382Y1188588D01*
X1079315Y1188188D01*
X1079115Y1187788D01*
G01X1078748Y1276436D02*
X1088448D01*
X1083448Y1271436D01*
Y1281436D01*
X1088448Y1276436D01*
G01X1086378Y1702514D02*
X1090378D01*
Y1700914D01*
X1090178Y1700381D01*
X1089711Y1699981D01*
X1089178Y1699848D01*
X1088645Y1699981D01*
X1088245Y1700314D01*
X1088045Y1700914D01*
Y1702514D01*
G01X1086378Y1697514D02*
X1089045D01*
G01X1088511D02*
X1088778Y1697181D01*
X1088978Y1696848D01*
X1089045Y1696381D01*
X1088978Y1696048D01*
X1088778Y1695648D01*
G01X1088178Y1692981D02*
Y1690848D01*
X1088645Y1691048D01*
X1088911Y1691381D01*
X1089045Y1691848D01*
X1088978Y1692314D01*
X1088778Y1692714D01*
X1088311Y1692981D01*
X1087911Y1693114D01*
X1087511D01*
X1087111Y1692981D01*
X1086711Y1692648D01*
X1086445Y1692248D01*
X1086378Y1691781D01*
X1086511Y1691314D01*
X1086911Y1690848D01*
G01X1086845Y1688381D02*
X1086578Y1688048D01*
X1086378Y1687581D01*
Y1687181D01*
X1086511Y1686781D01*
X1086711Y1686514D01*
X1086978Y1686381D01*
X1087378Y1686448D01*
X1087578Y1686714D01*
X1087978Y1687914D01*
X1088445Y1688181D01*
X1088778Y1688048D01*
X1088978Y1687781D01*
X1089045Y1687381D01*
X1088978Y1686981D01*
X1088778Y1686581D01*
G01X1086845Y1683781D02*
X1086578Y1683448D01*
X1086378Y1682981D01*
Y1682581D01*
X1086511Y1682181D01*
X1086711Y1681914D01*
X1086978Y1681781D01*
X1087378Y1681848D01*
X1087578Y1682114D01*
X1087978Y1683314D01*
X1088445Y1683581D01*
X1088778Y1683448D01*
X1088978Y1683181D01*
X1089045Y1682781D01*
X1088978Y1682381D01*
X1088778Y1681981D01*
G01X1087711Y1679048D02*
Y1677314D01*
G01X1086378Y1673981D02*
X1089778D01*
X1090111Y1673848D01*
X1090311Y1673581D01*
X1090378Y1673181D01*
X1090245Y1672781D01*
X1089911Y1672581D01*
G01X1088778Y1673381D02*
Y1674714D01*
G01X1089045Y1668981D02*
X1086378D01*
G01X1090111D02*
X1090178Y1669114D01*
X1090311D01*
X1090378Y1668981D01*
X1090311Y1668848D01*
X1090178D01*
X1090111Y1668981D01*
G01X1090378Y1664381D02*
X1086378D01*
G01X1089045Y1665314D02*
Y1663448D01*
G01X1086378Y1656514D02*
X1090378D01*
Y1654914D01*
X1090178Y1654381D01*
X1089711Y1653981D01*
X1089178Y1653848D01*
X1088645Y1653981D01*
X1088245Y1654314D01*
X1088045Y1654914D01*
Y1656514D01*
G01X1090378Y1650581D02*
X1086378D01*
G01X1090378Y1652114D02*
Y1649048D01*
G01X1086378Y1647381D02*
X1090378D01*
G01Y1644581D02*
X1086378D01*
G01X1088378D02*
Y1647381D01*
G01X1086378Y1637914D02*
X1090378D01*
G01X1089045Y1635781D02*
X1087511Y1637914D01*
G01X1088111Y1637048D02*
X1086378Y1635648D01*
G01X1088178Y1633181D02*
Y1631048D01*
X1088645Y1631248D01*
X1088911Y1631581D01*
X1089045Y1632048D01*
X1088978Y1632514D01*
X1088778Y1632914D01*
X1088311Y1633181D01*
X1087911Y1633314D01*
X1087511D01*
X1087111Y1633181D01*
X1086711Y1632848D01*
X1086445Y1632448D01*
X1086378Y1631981D01*
X1086511Y1631514D01*
X1086911Y1631048D01*
G01X1088178Y1628581D02*
Y1626448D01*
X1088645Y1626648D01*
X1088911Y1626981D01*
X1089045Y1627448D01*
X1088978Y1627914D01*
X1088778Y1628314D01*
X1088311Y1628581D01*
X1087911Y1628714D01*
X1087511D01*
X1087111Y1628581D01*
X1086711Y1628248D01*
X1086445Y1627848D01*
X1086378Y1627381D01*
X1086511Y1626914D01*
X1086911Y1626448D01*
G01X1085045Y1624181D02*
X1089045D01*
G01X1088445D02*
X1088778Y1623848D01*
X1088978Y1623514D01*
X1089045Y1622981D01*
X1088978Y1622514D01*
X1088645Y1622048D01*
X1088178Y1621848D01*
X1087711Y1621781D01*
X1087245Y1621848D01*
X1086778Y1622048D01*
X1086511Y1622448D01*
X1086378Y1622981D01*
X1086445Y1623448D01*
X1086645Y1623914D01*
X1086911Y1624181D01*
G01X1086378Y1614914D02*
X1090378D01*
G01X1088445D02*
X1088778Y1614581D01*
X1088978Y1614248D01*
X1089045Y1613714D01*
X1088978Y1613314D01*
X1088711Y1612848D01*
X1088311Y1612648D01*
X1086378D01*
G01Y1609181D02*
X1086445Y1609581D01*
X1086711Y1609981D01*
X1087178Y1610248D01*
X1087711Y1610381D01*
X1088245Y1610248D01*
X1088711Y1609981D01*
X1088978Y1609581D01*
X1089045Y1609181D01*
X1088978Y1608781D01*
X1088711Y1608381D01*
X1088245Y1608114D01*
X1087711Y1608048D01*
X1087178Y1608114D01*
X1086711Y1608381D01*
X1086445Y1608781D01*
X1086378Y1609181D01*
G01Y1604581D02*
X1090378D01*
G01X1088178Y1600981D02*
Y1598848D01*
X1088645Y1599048D01*
X1088911Y1599381D01*
X1089045Y1599848D01*
X1088978Y1600314D01*
X1088778Y1600714D01*
X1088311Y1600981D01*
X1087911Y1601114D01*
X1087511D01*
X1087111Y1600981D01*
X1086711Y1600648D01*
X1086445Y1600248D01*
X1086378Y1599781D01*
X1086511Y1599314D01*
X1086911Y1598848D01*
G01X1086845Y1591781D02*
X1086578Y1591448D01*
X1086378Y1590981D01*
Y1590581D01*
X1086511Y1590181D01*
X1086711Y1589914D01*
X1086978Y1589781D01*
X1087378Y1589848D01*
X1087578Y1590114D01*
X1087978Y1591314D01*
X1088445Y1591581D01*
X1088778Y1591448D01*
X1088978Y1591181D01*
X1089045Y1590781D01*
X1088978Y1590381D01*
X1088778Y1589981D01*
G01X1089045Y1586181D02*
X1086378D01*
G01X1090111D02*
X1090178Y1586314D01*
X1090311D01*
X1090378Y1586181D01*
X1090311Y1586048D01*
X1090178D01*
X1090111Y1586181D01*
G01X1089045Y1582581D02*
Y1580581D01*
X1086378Y1582581D01*
Y1580581D01*
G01X1088178Y1577981D02*
Y1575848D01*
X1088645Y1576048D01*
X1088911Y1576381D01*
X1089045Y1576848D01*
X1088978Y1577314D01*
X1088778Y1577714D01*
X1088311Y1577981D01*
X1087911Y1578114D01*
X1087511D01*
X1087111Y1577981D01*
X1086711Y1577648D01*
X1086445Y1577248D01*
X1086378Y1576781D01*
X1086511Y1576314D01*
X1086911Y1575848D01*
G01X1090378Y1567781D02*
X1086378D01*
G01X1089045Y1568714D02*
Y1566848D01*
G01X1086378Y1563181D02*
X1086445Y1563581D01*
X1086711Y1563981D01*
X1087178Y1564248D01*
X1087711Y1564381D01*
X1088245Y1564248D01*
X1088711Y1563981D01*
X1088978Y1563581D01*
X1089045Y1563181D01*
X1088978Y1562781D01*
X1088711Y1562381D01*
X1088245Y1562114D01*
X1087711Y1562048D01*
X1087178Y1562114D01*
X1086711Y1562381D01*
X1086445Y1562781D01*
X1086378Y1563181D01*
G01Y1558581D02*
X1090378D01*
G01X1088178Y1554981D02*
Y1552848D01*
X1088645Y1553048D01*
X1088911Y1553381D01*
X1089045Y1553848D01*
X1088978Y1554314D01*
X1088778Y1554714D01*
X1088311Y1554981D01*
X1087911Y1555114D01*
X1087511D01*
X1087111Y1554981D01*
X1086711Y1554648D01*
X1086445Y1554248D01*
X1086378Y1553781D01*
X1086511Y1553314D01*
X1086911Y1552848D01*
G01X1086378Y1550314D02*
X1089045D01*
G01X1088511D02*
X1088778Y1549981D01*
X1088978Y1549648D01*
X1089045Y1549181D01*
X1088978Y1548848D01*
X1088778Y1548448D01*
G01X1086378Y1543581D02*
X1089045D01*
G01X1088578D02*
X1088845Y1543848D01*
X1088978Y1544248D01*
X1089045Y1544714D01*
X1088911Y1545181D01*
X1088645Y1545581D01*
X1088245Y1545848D01*
X1087711Y1545981D01*
X1087178Y1545848D01*
X1086778Y1545581D01*
X1086511Y1545181D01*
X1086378Y1544714D01*
X1086445Y1544248D01*
X1086645Y1543848D01*
X1086911Y1543581D01*
G01X1086378Y1541314D02*
X1089045D01*
G01X1088378D02*
X1088711Y1541048D01*
X1088978Y1540648D01*
X1089045Y1540114D01*
X1088978Y1539648D01*
X1088711Y1539248D01*
X1088245Y1539048D01*
X1086378D01*
G01X1088711Y1534514D02*
X1088978Y1534981D01*
X1089045Y1535381D01*
X1088911Y1535914D01*
X1088645Y1536314D01*
X1088178Y1536581D01*
X1087711Y1536648D01*
X1087245Y1536581D01*
X1086845Y1536314D01*
X1086511Y1535914D01*
X1086378Y1535381D01*
X1086511Y1534914D01*
X1086778Y1534514D01*
G01X1088178Y1531981D02*
Y1529848D01*
X1088645Y1530048D01*
X1088911Y1530381D01*
X1089045Y1530848D01*
X1088978Y1531314D01*
X1088778Y1531714D01*
X1088311Y1531981D01*
X1087911Y1532114D01*
X1087511D01*
X1087111Y1531981D01*
X1086711Y1531648D01*
X1086445Y1531248D01*
X1086378Y1530781D01*
X1086511Y1530314D01*
X1086911Y1529848D01*
G01X1087711Y1522514D02*
Y1520914D01*
G01X1088578Y1521781D02*
X1086845D01*
G01X1086245Y1518381D02*
X1090378Y1515981D01*
G01X1087711Y1513448D02*
Y1511714D01*
G01X1089711Y1509248D02*
X1090111Y1508848D01*
X1090311Y1508381D01*
X1090378Y1507848D01*
X1090245Y1507181D01*
X1089911Y1506714D01*
X1089511Y1506581D01*
X1089111Y1506648D01*
X1088778Y1506914D01*
X1088111Y1508248D01*
X1087645Y1508848D01*
X1086978Y1509248D01*
X1086378Y1509381D01*
Y1506581D01*
G01Y1500781D02*
X1089045D01*
G01X1088311D02*
X1088645Y1500581D01*
X1088911Y1500248D01*
X1089045Y1499781D01*
X1088911Y1499314D01*
X1088645Y1498981D01*
X1088311Y1498781D01*
X1086378D01*
G01X1088311D02*
X1088645Y1498581D01*
X1088911Y1498248D01*
X1089045Y1497781D01*
X1088911Y1497314D01*
X1088645Y1496981D01*
X1088245Y1496781D01*
X1086378D01*
G01X1089045Y1494181D02*
X1086378D01*
G01X1090111D02*
X1090178Y1494314D01*
X1090311D01*
X1090378Y1494181D01*
X1090311Y1494048D01*
X1090178D01*
X1090111Y1494181D01*
G01X1086378Y1489581D02*
X1090378D01*
G01X1086845Y1485981D02*
X1086578Y1485648D01*
X1086378Y1485181D01*
Y1484781D01*
X1086511Y1484381D01*
X1086711Y1484114D01*
X1086978Y1483981D01*
X1087378Y1484048D01*
X1087578Y1484314D01*
X1087978Y1485514D01*
X1088445Y1485781D01*
X1088778Y1485648D01*
X1088978Y1485381D01*
X1089045Y1484981D01*
X1088978Y1484581D01*
X1088778Y1484181D01*
G01X1094541Y9699D02*
X1125931D01*
Y351907D01*
X1094541D01*
Y9699D01*
G01X1139570Y51032D02*
X1135570D01*
Y52632D01*
X1135770Y53165D01*
X1136237Y53565D01*
X1136770Y53698D01*
X1137303Y53565D01*
X1137703Y53232D01*
X1137903Y52632D01*
Y51032D01*
G01X1139570Y56032D02*
X1136903D01*
G01X1137437D02*
X1137170Y56365D01*
X1136970Y56698D01*
X1136903Y57165D01*
X1136970Y57498D01*
X1137170Y57898D01*
G01X1137770Y60565D02*
Y62698D01*
X1137303Y62498D01*
X1137037Y62165D01*
X1136903Y61698D01*
X1136970Y61232D01*
X1137170Y60832D01*
X1137637Y60565D01*
X1138037Y60432D01*
X1138437D01*
X1138837Y60565D01*
X1139237Y60898D01*
X1139503Y61298D01*
X1139570Y61765D01*
X1139437Y62232D01*
X1139037Y62698D01*
G01X1139103Y65165D02*
X1139370Y65498D01*
X1139570Y65965D01*
Y66365D01*
X1139437Y66765D01*
X1139237Y67032D01*
X1138970Y67165D01*
X1138570Y67098D01*
X1138370Y66832D01*
X1137970Y65632D01*
X1137503Y65365D01*
X1137170Y65498D01*
X1136970Y65765D01*
X1136903Y66165D01*
X1136970Y66565D01*
X1137170Y66965D01*
G01X1139103Y69765D02*
X1139370Y70098D01*
X1139570Y70565D01*
Y70965D01*
X1139437Y71365D01*
X1139237Y71632D01*
X1138970Y71765D01*
X1138570Y71698D01*
X1138370Y71432D01*
X1137970Y70232D01*
X1137503Y69965D01*
X1137170Y70098D01*
X1136970Y70365D01*
X1136903Y70765D01*
X1136970Y71165D01*
X1137170Y71565D01*
G01X1138237Y74498D02*
Y76232D01*
G01X1139570Y79565D02*
X1136170D01*
X1135837Y79698D01*
X1135637Y79965D01*
X1135570Y80365D01*
X1135703Y80765D01*
X1136037Y80965D01*
G01X1137170Y80165D02*
Y78832D01*
G01X1136903Y84565D02*
X1139570D01*
G01X1135837D02*
X1135770Y84432D01*
X1135637D01*
X1135570Y84565D01*
X1135637Y84698D01*
X1135770D01*
X1135837Y84565D01*
G01X1135570Y89165D02*
X1139570D01*
G01X1136903Y88232D02*
Y90098D01*
G01X1139570Y97032D02*
X1135570D01*
Y98632D01*
X1135770Y99165D01*
X1136237Y99565D01*
X1136770Y99698D01*
X1137303Y99565D01*
X1137703Y99232D01*
X1137903Y98632D01*
Y97032D01*
G01X1135570Y102965D02*
X1139570D01*
G01X1135570Y101432D02*
Y104498D01*
G01X1139570Y106165D02*
X1135570D01*
G01Y108965D02*
X1139570D01*
G01X1137570D02*
Y106165D01*
G01X1139570Y115632D02*
X1135570D01*
G01X1136903Y117765D02*
X1138437Y115632D01*
G01X1137837Y116498D02*
X1139570Y117898D01*
G01X1137770Y120365D02*
Y122498D01*
X1137303Y122298D01*
X1137037Y121965D01*
X1136903Y121498D01*
X1136970Y121032D01*
X1137170Y120632D01*
X1137637Y120365D01*
X1138037Y120232D01*
X1138437D01*
X1138837Y120365D01*
X1139237Y120698D01*
X1139503Y121098D01*
X1139570Y121565D01*
X1139437Y122032D01*
X1139037Y122498D01*
G01X1137770Y124965D02*
Y127098D01*
X1137303Y126898D01*
X1137037Y126565D01*
X1136903Y126098D01*
X1136970Y125632D01*
X1137170Y125232D01*
X1137637Y124965D01*
X1138037Y124832D01*
X1138437D01*
X1138837Y124965D01*
X1139237Y125298D01*
X1139503Y125698D01*
X1139570Y126165D01*
X1139437Y126632D01*
X1139037Y127098D01*
G01X1140903Y129365D02*
X1136903D01*
G01X1137503D02*
X1137170Y129698D01*
X1136970Y130032D01*
X1136903Y130565D01*
X1136970Y131032D01*
X1137303Y131498D01*
X1137770Y131698D01*
X1138237Y131765D01*
X1138703Y131698D01*
X1139170Y131498D01*
X1139437Y131098D01*
X1139570Y130565D01*
X1139503Y130098D01*
X1139303Y129632D01*
X1139037Y129365D01*
G01X1139570Y138632D02*
X1135570D01*
G01X1137503D02*
X1137170Y138965D01*
X1136970Y139298D01*
X1136903Y139832D01*
X1136970Y140232D01*
X1137237Y140698D01*
X1137637Y140898D01*
X1139570D01*
G01Y144365D02*
X1139503Y143965D01*
X1139237Y143565D01*
X1138770Y143298D01*
X1138237Y143165D01*
X1137703Y143298D01*
X1137237Y143565D01*
X1136970Y143965D01*
X1136903Y144365D01*
X1136970Y144765D01*
X1137237Y145165D01*
X1137703Y145432D01*
X1138237Y145498D01*
X1138770Y145432D01*
X1139237Y145165D01*
X1139503Y144765D01*
X1139570Y144365D01*
G01Y148965D02*
X1135570D01*
G01X1137770Y152565D02*
Y154698D01*
X1137303Y154498D01*
X1137037Y154165D01*
X1136903Y153698D01*
X1136970Y153232D01*
X1137170Y152832D01*
X1137637Y152565D01*
X1138037Y152432D01*
X1138437D01*
X1138837Y152565D01*
X1139237Y152898D01*
X1139503Y153298D01*
X1139570Y153765D01*
X1139437Y154232D01*
X1139037Y154698D01*
G01X1139103Y161765D02*
X1139370Y162098D01*
X1139570Y162565D01*
Y162965D01*
X1139437Y163365D01*
X1139237Y163632D01*
X1138970Y163765D01*
X1138570Y163698D01*
X1138370Y163432D01*
X1137970Y162232D01*
X1137503Y161965D01*
X1137170Y162098D01*
X1136970Y162365D01*
X1136903Y162765D01*
X1136970Y163165D01*
X1137170Y163565D01*
G01X1136903Y167365D02*
X1139570D01*
G01X1135837D02*
X1135770Y167232D01*
X1135637D01*
X1135570Y167365D01*
X1135637Y167498D01*
X1135770D01*
X1135837Y167365D01*
G01X1136903Y170965D02*
Y172965D01*
X1139570Y170965D01*
Y172965D01*
G01X1137770Y175565D02*
Y177698D01*
X1137303Y177498D01*
X1137037Y177165D01*
X1136903Y176698D01*
X1136970Y176232D01*
X1137170Y175832D01*
X1137637Y175565D01*
X1138037Y175432D01*
X1138437D01*
X1138837Y175565D01*
X1139237Y175898D01*
X1139503Y176298D01*
X1139570Y176765D01*
X1139437Y177232D01*
X1139037Y177698D01*
G01X1135570Y185765D02*
X1139570D01*
G01X1136903Y184832D02*
Y186698D01*
G01X1139570Y190365D02*
X1139503Y189965D01*
X1139237Y189565D01*
X1138770Y189298D01*
X1138237Y189165D01*
X1137703Y189298D01*
X1137237Y189565D01*
X1136970Y189965D01*
X1136903Y190365D01*
X1136970Y190765D01*
X1137237Y191165D01*
X1137703Y191432D01*
X1138237Y191498D01*
X1138770Y191432D01*
X1139237Y191165D01*
X1139503Y190765D01*
X1139570Y190365D01*
G01Y194965D02*
X1135570D01*
G01X1137770Y198565D02*
Y200698D01*
X1137303Y200498D01*
X1137037Y200165D01*
X1136903Y199698D01*
X1136970Y199232D01*
X1137170Y198832D01*
X1137637Y198565D01*
X1138037Y198432D01*
X1138437D01*
X1138837Y198565D01*
X1139237Y198898D01*
X1139503Y199298D01*
X1139570Y199765D01*
X1139437Y200232D01*
X1139037Y200698D01*
G01X1139570Y203232D02*
X1136903D01*
G01X1137437D02*
X1137170Y203565D01*
X1136970Y203898D01*
X1136903Y204365D01*
X1136970Y204698D01*
X1137170Y205098D01*
G01X1139570Y209965D02*
X1136903D01*
G01X1137370D02*
X1137103Y209698D01*
X1136970Y209298D01*
X1136903Y208832D01*
X1137037Y208365D01*
X1137303Y207965D01*
X1137703Y207698D01*
X1138237Y207565D01*
X1138770Y207698D01*
X1139170Y207965D01*
X1139437Y208365D01*
X1139570Y208832D01*
X1139503Y209298D01*
X1139303Y209698D01*
X1139037Y209965D01*
G01X1139570Y212232D02*
X1136903D01*
G01X1137570D02*
X1137237Y212498D01*
X1136970Y212898D01*
X1136903Y213432D01*
X1136970Y213898D01*
X1137237Y214298D01*
X1137703Y214498D01*
X1139570D01*
G01X1137237Y219032D02*
X1136970Y218565D01*
X1136903Y218165D01*
X1137037Y217632D01*
X1137303Y217232D01*
X1137770Y216965D01*
X1138237Y216898D01*
X1138703Y216965D01*
X1139103Y217232D01*
X1139437Y217632D01*
X1139570Y218165D01*
X1139437Y218632D01*
X1139170Y219032D01*
G01X1137770Y221565D02*
Y223698D01*
X1137303Y223498D01*
X1137037Y223165D01*
X1136903Y222698D01*
X1136970Y222232D01*
X1137170Y221832D01*
X1137637Y221565D01*
X1138037Y221432D01*
X1138437D01*
X1138837Y221565D01*
X1139237Y221898D01*
X1139503Y222298D01*
X1139570Y222765D01*
X1139437Y223232D01*
X1139037Y223698D01*
G01X1138237Y231032D02*
Y232632D01*
G01X1137370Y231765D02*
X1139103D01*
G01X1139703Y235165D02*
X1135570Y237565D01*
G01X1138237Y240098D02*
Y241832D01*
G01X1136237Y244298D02*
X1135837Y244698D01*
X1135637Y245165D01*
X1135570Y245698D01*
X1135703Y246365D01*
X1136037Y246832D01*
X1136437Y246965D01*
X1136837Y246898D01*
X1137170Y246632D01*
X1137837Y245298D01*
X1138303Y244698D01*
X1138970Y244298D01*
X1139570Y244165D01*
Y246965D01*
G01Y252765D02*
X1136903D01*
G01X1137637D02*
X1137303Y252965D01*
X1137037Y253298D01*
X1136903Y253765D01*
X1137037Y254232D01*
X1137303Y254565D01*
X1137637Y254765D01*
X1139570D01*
G01X1137637D02*
X1137303Y254965D01*
X1137037Y255298D01*
X1136903Y255765D01*
X1137037Y256232D01*
X1137303Y256565D01*
X1137703Y256765D01*
X1139570D01*
G01X1136903Y259365D02*
X1139570D01*
G01X1135837D02*
X1135770Y259232D01*
X1135637D01*
X1135570Y259365D01*
X1135637Y259498D01*
X1135770D01*
X1135837Y259365D01*
G01X1139570Y263965D02*
X1135570D01*
G01X1139103Y267565D02*
X1139370Y267898D01*
X1139570Y268365D01*
Y268765D01*
X1139437Y269165D01*
X1139237Y269432D01*
X1138970Y269565D01*
X1138570Y269498D01*
X1138370Y269232D01*
X1137970Y268032D01*
X1137503Y267765D01*
X1137170Y267898D01*
X1136970Y268165D01*
X1136903Y268565D01*
X1136970Y268965D01*
X1137170Y269365D01*
G01X1126236Y136465D02*
X1130236Y132465D01*
Y140465D01*
X1126236Y136465D01*
X1136236D01*
G01X1094541Y388832D02*
X1125931D01*
Y731040D01*
X1094541D01*
Y388832D01*
G01X1139570Y430165D02*
X1135570D01*
Y431765D01*
X1135770Y432298D01*
X1136237Y432698D01*
X1136770Y432831D01*
X1137303Y432698D01*
X1137703Y432365D01*
X1137903Y431765D01*
Y430165D01*
G01X1139570Y435165D02*
X1136903D01*
G01X1137437D02*
X1137170Y435498D01*
X1136970Y435831D01*
X1136903Y436298D01*
X1136970Y436631D01*
X1137170Y437031D01*
G01X1137770Y439698D02*
Y441831D01*
X1137303Y441631D01*
X1137037Y441298D01*
X1136903Y440831D01*
X1136970Y440365D01*
X1137170Y439965D01*
X1137637Y439698D01*
X1138037Y439565D01*
X1138437D01*
X1138837Y439698D01*
X1139237Y440031D01*
X1139503Y440431D01*
X1139570Y440898D01*
X1139437Y441365D01*
X1139037Y441831D01*
G01X1139103Y444298D02*
X1139370Y444631D01*
X1139570Y445098D01*
Y445498D01*
X1139437Y445898D01*
X1139237Y446165D01*
X1138970Y446298D01*
X1138570Y446231D01*
X1138370Y445965D01*
X1137970Y444765D01*
X1137503Y444498D01*
X1137170Y444631D01*
X1136970Y444898D01*
X1136903Y445298D01*
X1136970Y445698D01*
X1137170Y446098D01*
G01X1139103Y448898D02*
X1139370Y449231D01*
X1139570Y449698D01*
Y450098D01*
X1139437Y450498D01*
X1139237Y450765D01*
X1138970Y450898D01*
X1138570Y450831D01*
X1138370Y450565D01*
X1137970Y449365D01*
X1137503Y449098D01*
X1137170Y449231D01*
X1136970Y449498D01*
X1136903Y449898D01*
X1136970Y450298D01*
X1137170Y450698D01*
G01X1138237Y453631D02*
Y455365D01*
G01X1139570Y458698D02*
X1136170D01*
X1135837Y458831D01*
X1135637Y459098D01*
X1135570Y459498D01*
X1135703Y459898D01*
X1136037Y460098D01*
G01X1137170Y459298D02*
Y457965D01*
G01X1136903Y463698D02*
X1139570D01*
G01X1135837D02*
X1135770Y463565D01*
X1135637D01*
X1135570Y463698D01*
X1135637Y463831D01*
X1135770D01*
X1135837Y463698D01*
G01X1135570Y468298D02*
X1139570D01*
G01X1136903Y467365D02*
Y469231D01*
G01X1139570Y476165D02*
X1135570D01*
Y477765D01*
X1135770Y478298D01*
X1136237Y478698D01*
X1136770Y478831D01*
X1137303Y478698D01*
X1137703Y478365D01*
X1137903Y477765D01*
Y476165D01*
G01X1135570Y482098D02*
X1139570D01*
G01X1135570Y480565D02*
Y483631D01*
G01X1139570Y485298D02*
X1135570D01*
G01Y488098D02*
X1139570D01*
G01X1137570D02*
Y485298D01*
G01X1139570Y494765D02*
X1135570D01*
G01X1136903Y496898D02*
X1138437Y494765D01*
G01X1137837Y495631D02*
X1139570Y497031D01*
G01X1137770Y499498D02*
Y501631D01*
X1137303Y501431D01*
X1137037Y501098D01*
X1136903Y500631D01*
X1136970Y500165D01*
X1137170Y499765D01*
X1137637Y499498D01*
X1138037Y499365D01*
X1138437D01*
X1138837Y499498D01*
X1139237Y499831D01*
X1139503Y500231D01*
X1139570Y500698D01*
X1139437Y501165D01*
X1139037Y501631D01*
G01X1137770Y504098D02*
Y506231D01*
X1137303Y506031D01*
X1137037Y505698D01*
X1136903Y505231D01*
X1136970Y504765D01*
X1137170Y504365D01*
X1137637Y504098D01*
X1138037Y503965D01*
X1138437D01*
X1138837Y504098D01*
X1139237Y504431D01*
X1139503Y504831D01*
X1139570Y505298D01*
X1139437Y505765D01*
X1139037Y506231D01*
G01X1140903Y508498D02*
X1136903D01*
G01X1137503D02*
X1137170Y508831D01*
X1136970Y509165D01*
X1136903Y509698D01*
X1136970Y510165D01*
X1137303Y510631D01*
X1137770Y510831D01*
X1138237Y510898D01*
X1138703Y510831D01*
X1139170Y510631D01*
X1139437Y510231D01*
X1139570Y509698D01*
X1139503Y509231D01*
X1139303Y508765D01*
X1139037Y508498D01*
G01X1139570Y517765D02*
X1135570D01*
G01X1137503D02*
X1137170Y518098D01*
X1136970Y518431D01*
X1136903Y518965D01*
X1136970Y519365D01*
X1137237Y519831D01*
X1137637Y520031D01*
X1139570D01*
G01Y523498D02*
X1139503Y523098D01*
X1139237Y522698D01*
X1138770Y522431D01*
X1138237Y522298D01*
X1137703Y522431D01*
X1137237Y522698D01*
X1136970Y523098D01*
X1136903Y523498D01*
X1136970Y523898D01*
X1137237Y524298D01*
X1137703Y524565D01*
X1138237Y524631D01*
X1138770Y524565D01*
X1139237Y524298D01*
X1139503Y523898D01*
X1139570Y523498D01*
G01Y528098D02*
X1135570D01*
G01X1137770Y531698D02*
Y533831D01*
X1137303Y533631D01*
X1137037Y533298D01*
X1136903Y532831D01*
X1136970Y532365D01*
X1137170Y531965D01*
X1137637Y531698D01*
X1138037Y531565D01*
X1138437D01*
X1138837Y531698D01*
X1139237Y532031D01*
X1139503Y532431D01*
X1139570Y532898D01*
X1139437Y533365D01*
X1139037Y533831D01*
G01X1139103Y540898D02*
X1139370Y541231D01*
X1139570Y541698D01*
Y542098D01*
X1139437Y542498D01*
X1139237Y542765D01*
X1138970Y542898D01*
X1138570Y542831D01*
X1138370Y542565D01*
X1137970Y541365D01*
X1137503Y541098D01*
X1137170Y541231D01*
X1136970Y541498D01*
X1136903Y541898D01*
X1136970Y542298D01*
X1137170Y542698D01*
G01X1136903Y546498D02*
X1139570D01*
G01X1135837D02*
X1135770Y546365D01*
X1135637D01*
X1135570Y546498D01*
X1135637Y546631D01*
X1135770D01*
X1135837Y546498D01*
G01X1136903Y550098D02*
Y552098D01*
X1139570Y550098D01*
Y552098D01*
G01X1137770Y554698D02*
Y556831D01*
X1137303Y556631D01*
X1137037Y556298D01*
X1136903Y555831D01*
X1136970Y555365D01*
X1137170Y554965D01*
X1137637Y554698D01*
X1138037Y554565D01*
X1138437D01*
X1138837Y554698D01*
X1139237Y555031D01*
X1139503Y555431D01*
X1139570Y555898D01*
X1139437Y556365D01*
X1139037Y556831D01*
G01X1135570Y564898D02*
X1139570D01*
G01X1136903Y563965D02*
Y565831D01*
G01X1139570Y569498D02*
X1139503Y569098D01*
X1139237Y568698D01*
X1138770Y568431D01*
X1138237Y568298D01*
X1137703Y568431D01*
X1137237Y568698D01*
X1136970Y569098D01*
X1136903Y569498D01*
X1136970Y569898D01*
X1137237Y570298D01*
X1137703Y570565D01*
X1138237Y570631D01*
X1138770Y570565D01*
X1139237Y570298D01*
X1139503Y569898D01*
X1139570Y569498D01*
G01Y574098D02*
X1135570D01*
G01X1137770Y577698D02*
Y579831D01*
X1137303Y579631D01*
X1137037Y579298D01*
X1136903Y578831D01*
X1136970Y578365D01*
X1137170Y577965D01*
X1137637Y577698D01*
X1138037Y577565D01*
X1138437D01*
X1138837Y577698D01*
X1139237Y578031D01*
X1139503Y578431D01*
X1139570Y578898D01*
X1139437Y579365D01*
X1139037Y579831D01*
G01X1139570Y582365D02*
X1136903D01*
G01X1137437D02*
X1137170Y582698D01*
X1136970Y583031D01*
X1136903Y583498D01*
X1136970Y583831D01*
X1137170Y584231D01*
G01X1139570Y589098D02*
X1136903D01*
G01X1137370D02*
X1137103Y588831D01*
X1136970Y588431D01*
X1136903Y587965D01*
X1137037Y587498D01*
X1137303Y587098D01*
X1137703Y586831D01*
X1138237Y586698D01*
X1138770Y586831D01*
X1139170Y587098D01*
X1139437Y587498D01*
X1139570Y587965D01*
X1139503Y588431D01*
X1139303Y588831D01*
X1139037Y589098D01*
G01X1139570Y591365D02*
X1136903D01*
G01X1137570D02*
X1137237Y591631D01*
X1136970Y592031D01*
X1136903Y592565D01*
X1136970Y593031D01*
X1137237Y593431D01*
X1137703Y593631D01*
X1139570D01*
G01X1137237Y598165D02*
X1136970Y597698D01*
X1136903Y597298D01*
X1137037Y596765D01*
X1137303Y596365D01*
X1137770Y596098D01*
X1138237Y596031D01*
X1138703Y596098D01*
X1139103Y596365D01*
X1139437Y596765D01*
X1139570Y597298D01*
X1139437Y597765D01*
X1139170Y598165D01*
G01X1137770Y600698D02*
Y602831D01*
X1137303Y602631D01*
X1137037Y602298D01*
X1136903Y601831D01*
X1136970Y601365D01*
X1137170Y600965D01*
X1137637Y600698D01*
X1138037Y600565D01*
X1138437D01*
X1138837Y600698D01*
X1139237Y601031D01*
X1139503Y601431D01*
X1139570Y601898D01*
X1139437Y602365D01*
X1139037Y602831D01*
G01X1138237Y610165D02*
Y611765D01*
G01X1137370Y610898D02*
X1139103D01*
G01X1139703Y614298D02*
X1135570Y616698D01*
G01X1138237Y619231D02*
Y620965D01*
G01X1136237Y623431D02*
X1135837Y623831D01*
X1135637Y624298D01*
X1135570Y624831D01*
X1135703Y625498D01*
X1136037Y625965D01*
X1136437Y626098D01*
X1136837Y626031D01*
X1137170Y625765D01*
X1137837Y624431D01*
X1138303Y623831D01*
X1138970Y623431D01*
X1139570Y623298D01*
Y626098D01*
G01Y631898D02*
X1136903D01*
G01X1137637D02*
X1137303Y632098D01*
X1137037Y632431D01*
X1136903Y632898D01*
X1137037Y633365D01*
X1137303Y633698D01*
X1137637Y633898D01*
X1139570D01*
G01X1137637D02*
X1137303Y634098D01*
X1137037Y634431D01*
X1136903Y634898D01*
X1137037Y635365D01*
X1137303Y635698D01*
X1137703Y635898D01*
X1139570D01*
G01X1136903Y638498D02*
X1139570D01*
G01X1135837D02*
X1135770Y638365D01*
X1135637D01*
X1135570Y638498D01*
X1135637Y638631D01*
X1135770D01*
X1135837Y638498D01*
G01X1139570Y643098D02*
X1135570D01*
G01X1139103Y646698D02*
X1139370Y647031D01*
X1139570Y647498D01*
Y647898D01*
X1139437Y648298D01*
X1139237Y648565D01*
X1138970Y648698D01*
X1138570Y648631D01*
X1138370Y648365D01*
X1137970Y647165D01*
X1137503Y646898D01*
X1137170Y647031D01*
X1136970Y647298D01*
X1136903Y647698D01*
X1136970Y648098D01*
X1137170Y648498D01*
G01X1105453Y546536D02*
X1105853Y546203D01*
X1106320Y546003D01*
X1106920Y545936D01*
X1107520Y546069D01*
X1107987Y546336D01*
X1108320Y546803D01*
X1108387Y547336D01*
X1108253Y547869D01*
X1107920Y548203D01*
X1107453Y548469D01*
X1106987Y548536D01*
X1106520Y548469D01*
X1105920Y548203D01*
X1106120Y549936D01*
X1107920D01*
G01X1110053Y546536D02*
X1110453Y546203D01*
X1110920Y546003D01*
X1111520Y545936D01*
X1112120Y546069D01*
X1112587Y546336D01*
X1112920Y546803D01*
X1112987Y547336D01*
X1112853Y547869D01*
X1112520Y548203D01*
X1112053Y548469D01*
X1111587Y548536D01*
X1111120Y548469D01*
X1110520Y548203D01*
X1110720Y549936D01*
X1112520D01*
G01X1115987Y545936D02*
X1116120Y546803D01*
X1116320Y547536D01*
X1116587Y548203D01*
X1116920Y548936D01*
X1117453Y549936D01*
X1114787D01*
G01X1120720Y545803D02*
X1120587Y545869D01*
Y546003D01*
X1120720Y546069D01*
X1120853Y546003D01*
Y545869D01*
X1120720Y545803D01*
G01X1125320Y549936D02*
X1124787Y549803D01*
X1124387Y549469D01*
X1124120Y549069D01*
X1123920Y548536D01*
X1123853Y547936D01*
X1123920Y547336D01*
X1124120Y546803D01*
X1124387Y546403D01*
X1124787Y546069D01*
X1125320Y545936D01*
X1125853Y546069D01*
X1126253Y546403D01*
X1126520Y546803D01*
X1126720Y547336D01*
X1126787Y547936D01*
X1126720Y548536D01*
X1126520Y549069D01*
X1126253Y549469D01*
X1125853Y549803D01*
X1125320Y549936D01*
G01X1128787Y546403D02*
X1129253Y546069D01*
X1129787Y545936D01*
X1130320Y546069D01*
X1130787Y546469D01*
X1131120Y547069D01*
X1131253Y547669D01*
Y548403D01*
X1131120Y549003D01*
X1130787Y549536D01*
X1130387Y549803D01*
X1129920Y549936D01*
X1129387Y549803D01*
X1128987Y549536D01*
X1128720Y549136D01*
X1128587Y548603D01*
X1128720Y548136D01*
X1129053Y547669D01*
X1129453Y547403D01*
X1129920Y547336D01*
X1130453Y547469D01*
X1130853Y547803D01*
X1131253Y548403D01*
G01X1126236Y515598D02*
X1130236Y511598D01*
Y519598D01*
X1126236Y515598D01*
X1136236D01*
G01X1122792Y557082D02*
X1123192Y557482D01*
X1123659Y557682D01*
X1124192Y557749D01*
X1124859Y557616D01*
X1125326Y557282D01*
X1125459Y556882D01*
X1125392Y556482D01*
X1125126Y556149D01*
X1123792Y555482D01*
X1123192Y555016D01*
X1122792Y554349D01*
X1122659Y553749D01*
X1125459D01*
G01X1127192Y554549D02*
X1127592Y554082D01*
X1128126Y553816D01*
X1128726Y553749D01*
X1129259Y553816D01*
X1129792Y554149D01*
X1130126Y554549D01*
X1130192Y554949D01*
X1130059Y555416D01*
X1129592Y555749D01*
X1129126Y555882D01*
X1128526D01*
G01X1129126D02*
X1129526Y556082D01*
X1129859Y556416D01*
X1129992Y556816D01*
X1129859Y557216D01*
X1129526Y557549D01*
X1128926Y557749D01*
X1128326Y557682D01*
X1127726Y557416D01*
G01X1131992Y555416D02*
X1132459Y555882D01*
X1132859Y556149D01*
X1133392Y556282D01*
X1133859Y556149D01*
X1134192Y555882D01*
X1134459Y555482D01*
X1134526Y555016D01*
X1134459Y554616D01*
X1134192Y554216D01*
X1133792Y553882D01*
X1133326Y553749D01*
X1132792Y553882D01*
X1132326Y554282D01*
X1132059Y554882D01*
X1131992Y555549D01*
X1132126Y556416D01*
X1132326Y556882D01*
X1132659Y557349D01*
X1133126Y557682D01*
X1133592Y557749D01*
X1134059Y557616D01*
X1134392Y557282D01*
G01X1137859Y553616D02*
X1137726Y553682D01*
Y553816D01*
X1137859Y553882D01*
X1137992Y553816D01*
Y553682D01*
X1137859Y553616D01*
G01X1141192Y557082D02*
X1141592Y557482D01*
X1142059Y557682D01*
X1142592Y557749D01*
X1143259Y557616D01*
X1143726Y557282D01*
X1143859Y556882D01*
X1143792Y556482D01*
X1143526Y556149D01*
X1142192Y555482D01*
X1141592Y555016D01*
X1141192Y554349D01*
X1141059Y553749D01*
X1143859D01*
G01X1145792Y557082D02*
X1146192Y557482D01*
X1146659Y557682D01*
X1147192Y557749D01*
X1147859Y557616D01*
X1148326Y557282D01*
X1148459Y556882D01*
X1148392Y556482D01*
X1148126Y556149D01*
X1146792Y555482D01*
X1146192Y555016D01*
X1145792Y554349D01*
X1145659Y553749D01*
X1148459D01*
G01X1105433Y959899D02*
X1105833Y959566D01*
X1106300Y959366D01*
X1106900Y959299D01*
X1107500Y959432D01*
X1107967Y959699D01*
X1108300Y960166D01*
X1108367Y960699D01*
X1108233Y961232D01*
X1107900Y961566D01*
X1107433Y961832D01*
X1106967Y961899D01*
X1106500Y961832D01*
X1105900Y961566D01*
X1106100Y963299D01*
X1107900D01*
G01X1110033Y959899D02*
X1110433Y959566D01*
X1110900Y959366D01*
X1111500Y959299D01*
X1112100Y959432D01*
X1112567Y959699D01*
X1112900Y960166D01*
X1112967Y960699D01*
X1112833Y961232D01*
X1112500Y961566D01*
X1112033Y961832D01*
X1111567Y961899D01*
X1111100Y961832D01*
X1110500Y961566D01*
X1110700Y963299D01*
X1112500D01*
G01X1115967Y959299D02*
X1116100Y960166D01*
X1116300Y960899D01*
X1116567Y961566D01*
X1116900Y962299D01*
X1117433Y963299D01*
X1114767D01*
G01X1120700Y959166D02*
X1120567Y959232D01*
Y959366D01*
X1120700Y959432D01*
X1120833Y959366D01*
Y959232D01*
X1120700Y959166D01*
G01X1125300Y963299D02*
X1124767Y963166D01*
X1124367Y962832D01*
X1124100Y962432D01*
X1123900Y961899D01*
X1123833Y961299D01*
X1123900Y960699D01*
X1124100Y960166D01*
X1124367Y959766D01*
X1124767Y959432D01*
X1125300Y959299D01*
X1125833Y959432D01*
X1126233Y959766D01*
X1126500Y960166D01*
X1126700Y960699D01*
X1126767Y961299D01*
X1126700Y961899D01*
X1126500Y962432D01*
X1126233Y962832D01*
X1125833Y963166D01*
X1125300Y963299D01*
G01X1128767Y959766D02*
X1129233Y959432D01*
X1129767Y959299D01*
X1130300Y959432D01*
X1130767Y959832D01*
X1131100Y960432D01*
X1131233Y961032D01*
Y961766D01*
X1131100Y962366D01*
X1130767Y962899D01*
X1130367Y963166D01*
X1129900Y963299D01*
X1129367Y963166D01*
X1128967Y962899D01*
X1128700Y962499D01*
X1128567Y961966D01*
X1128700Y961499D01*
X1129033Y961032D01*
X1129433Y960766D01*
X1129900Y960699D01*
X1130433Y960832D01*
X1130833Y961166D01*
X1131233Y961766D01*
G01X1122772Y970445D02*
X1123172Y970845D01*
X1123639Y971045D01*
X1124172Y971112D01*
X1124839Y970979D01*
X1125306Y970645D01*
X1125439Y970245D01*
X1125372Y969845D01*
X1125106Y969512D01*
X1123772Y968845D01*
X1123172Y968379D01*
X1122772Y967712D01*
X1122639Y967112D01*
X1125439D01*
G01X1127172Y967912D02*
X1127572Y967445D01*
X1128106Y967179D01*
X1128706Y967112D01*
X1129239Y967179D01*
X1129772Y967512D01*
X1130106Y967912D01*
X1130172Y968312D01*
X1130039Y968779D01*
X1129572Y969112D01*
X1129106Y969245D01*
X1128506D01*
G01X1129106D02*
X1129506Y969445D01*
X1129839Y969779D01*
X1129972Y970179D01*
X1129839Y970579D01*
X1129506Y970912D01*
X1128906Y971112D01*
X1128306Y971045D01*
X1127706Y970779D01*
G01X1131972Y968779D02*
X1132439Y969245D01*
X1132839Y969512D01*
X1133372Y969645D01*
X1133839Y969512D01*
X1134172Y969245D01*
X1134439Y968845D01*
X1134506Y968379D01*
X1134439Y967979D01*
X1134172Y967579D01*
X1133772Y967245D01*
X1133306Y967112D01*
X1132772Y967245D01*
X1132306Y967645D01*
X1132039Y968245D01*
X1131972Y968912D01*
X1132106Y969779D01*
X1132306Y970245D01*
X1132639Y970712D01*
X1133106Y971045D01*
X1133572Y971112D01*
X1134039Y970979D01*
X1134372Y970645D01*
G01X1137839Y966979D02*
X1137706Y967045D01*
Y967179D01*
X1137839Y967245D01*
X1137972Y967179D01*
Y967045D01*
X1137839Y966979D01*
G01X1141172Y970445D02*
X1141572Y970845D01*
X1142039Y971045D01*
X1142572Y971112D01*
X1143239Y970979D01*
X1143706Y970645D01*
X1143839Y970245D01*
X1143772Y969845D01*
X1143506Y969512D01*
X1142172Y968845D01*
X1141572Y968379D01*
X1141172Y967712D01*
X1141039Y967112D01*
X1143839D01*
G01X1145772Y970445D02*
X1146172Y970845D01*
X1146639Y971045D01*
X1147172Y971112D01*
X1147839Y970979D01*
X1148306Y970645D01*
X1148439Y970245D01*
X1148372Y969845D01*
X1148106Y969512D01*
X1146772Y968845D01*
X1146172Y968379D01*
X1145772Y967712D01*
X1145639Y967112D01*
X1148439D01*
G01X1136109Y1040698D02*
Y986092D01*
X1088589D01*
Y1040698D01*
X1136109D01*
G01Y1410788D02*
Y1157757D01*
X1088589D01*
Y1410788D01*
X1136109D01*
G01X1105453Y1550473D02*
X1105853Y1550140D01*
X1106320Y1549940D01*
X1106920Y1549873D01*
X1107520Y1550006D01*
X1107987Y1550273D01*
X1108320Y1550740D01*
X1108387Y1551273D01*
X1108253Y1551806D01*
X1107920Y1552140D01*
X1107453Y1552406D01*
X1106987Y1552473D01*
X1106520Y1552406D01*
X1105920Y1552140D01*
X1106120Y1553873D01*
X1107920D01*
G01X1110053Y1550473D02*
X1110453Y1550140D01*
X1110920Y1549940D01*
X1111520Y1549873D01*
X1112120Y1550006D01*
X1112587Y1550273D01*
X1112920Y1550740D01*
X1112987Y1551273D01*
X1112853Y1551806D01*
X1112520Y1552140D01*
X1112053Y1552406D01*
X1111587Y1552473D01*
X1111120Y1552406D01*
X1110520Y1552140D01*
X1110720Y1553873D01*
X1112520D01*
G01X1115987Y1549873D02*
X1116120Y1550740D01*
X1116320Y1551473D01*
X1116587Y1552140D01*
X1116920Y1552873D01*
X1117453Y1553873D01*
X1114787D01*
G01X1120720Y1549740D02*
X1120587Y1549806D01*
Y1549940D01*
X1120720Y1550006D01*
X1120853Y1549940D01*
Y1549806D01*
X1120720Y1549740D01*
G01X1125320Y1553873D02*
X1124787Y1553740D01*
X1124387Y1553406D01*
X1124120Y1553006D01*
X1123920Y1552473D01*
X1123853Y1551873D01*
X1123920Y1551273D01*
X1124120Y1550740D01*
X1124387Y1550340D01*
X1124787Y1550006D01*
X1125320Y1549873D01*
X1125853Y1550006D01*
X1126253Y1550340D01*
X1126520Y1550740D01*
X1126720Y1551273D01*
X1126787Y1551873D01*
X1126720Y1552473D01*
X1126520Y1553006D01*
X1126253Y1553406D01*
X1125853Y1553740D01*
X1125320Y1553873D01*
G01X1128787Y1550340D02*
X1129253Y1550006D01*
X1129787Y1549873D01*
X1130320Y1550006D01*
X1130787Y1550406D01*
X1131120Y1551006D01*
X1131253Y1551606D01*
Y1552340D01*
X1131120Y1552940D01*
X1130787Y1553473D01*
X1130387Y1553740D01*
X1129920Y1553873D01*
X1129387Y1553740D01*
X1128987Y1553473D01*
X1128720Y1553073D01*
X1128587Y1552540D01*
X1128720Y1552073D01*
X1129053Y1551606D01*
X1129453Y1551340D01*
X1129920Y1551273D01*
X1130453Y1551406D01*
X1130853Y1551740D01*
X1131253Y1552340D01*
G01X1122792Y1561019D02*
X1123192Y1561419D01*
X1123659Y1561619D01*
X1124192Y1561686D01*
X1124859Y1561553D01*
X1125326Y1561219D01*
X1125459Y1560819D01*
X1125392Y1560419D01*
X1125126Y1560086D01*
X1123792Y1559419D01*
X1123192Y1558953D01*
X1122792Y1558286D01*
X1122659Y1557686D01*
X1125459D01*
G01X1127192Y1558486D02*
X1127592Y1558019D01*
X1128126Y1557753D01*
X1128726Y1557686D01*
X1129259Y1557753D01*
X1129792Y1558086D01*
X1130126Y1558486D01*
X1130192Y1558886D01*
X1130059Y1559353D01*
X1129592Y1559686D01*
X1129126Y1559819D01*
X1128526D01*
G01X1129126D02*
X1129526Y1560019D01*
X1129859Y1560353D01*
X1129992Y1560753D01*
X1129859Y1561153D01*
X1129526Y1561486D01*
X1128926Y1561686D01*
X1128326Y1561619D01*
X1127726Y1561353D01*
G01X1131992Y1559353D02*
X1132459Y1559819D01*
X1132859Y1560086D01*
X1133392Y1560219D01*
X1133859Y1560086D01*
X1134192Y1559819D01*
X1134459Y1559419D01*
X1134526Y1558953D01*
X1134459Y1558553D01*
X1134192Y1558153D01*
X1133792Y1557819D01*
X1133326Y1557686D01*
X1132792Y1557819D01*
X1132326Y1558219D01*
X1132059Y1558819D01*
X1131992Y1559486D01*
X1132126Y1560353D01*
X1132326Y1560819D01*
X1132659Y1561286D01*
X1133126Y1561619D01*
X1133592Y1561686D01*
X1134059Y1561553D01*
X1134392Y1561219D01*
G01X1137859Y1557553D02*
X1137726Y1557619D01*
Y1557753D01*
X1137859Y1557819D01*
X1137992Y1557753D01*
Y1557619D01*
X1137859Y1557553D01*
G01X1141192Y1561019D02*
X1141592Y1561419D01*
X1142059Y1561619D01*
X1142592Y1561686D01*
X1143259Y1561553D01*
X1143726Y1561219D01*
X1143859Y1560819D01*
X1143792Y1560419D01*
X1143526Y1560086D01*
X1142192Y1559419D01*
X1141592Y1558953D01*
X1141192Y1558286D01*
X1141059Y1557686D01*
X1143859D01*
G01X1145792Y1561019D02*
X1146192Y1561419D01*
X1146659Y1561619D01*
X1147192Y1561686D01*
X1147859Y1561553D01*
X1148326Y1561219D01*
X1148459Y1560819D01*
X1148392Y1560419D01*
X1148126Y1560086D01*
X1146792Y1559419D01*
X1146192Y1558953D01*
X1145792Y1558286D01*
X1145659Y1557686D01*
X1148459D01*
G01X1088054Y1595181D02*
X1097754D01*
X1092754Y1590181D01*
Y1600181D01*
X1097754Y1595181D01*
G01X1129782Y1604581D02*
Y1585183D01*
X1098054D01*
Y1604581D01*
X1129782D01*
G01X1181102Y-148819D02*
Y-3937D01*
G01X1177165Y-152756D02*
G03X1181102Y-148819I0J3937D01*
G01X1177165Y-152756D02*
G03X1181102Y-148819I0J3937D01*
G01D02*
Y-3937D01*
G01Y-94488D02*
G03X1188976I3937J0D01*
G01X1181102D02*
G03X1188976I3937J0D01*
G01Y-125197D02*
G03X1181102I-3937J0D01*
G01X1188976D02*
G03X1181102I-3937J0D01*
G01X1185039Y0D02*
G03X1181102Y-3937I0J-3937D01*
G01X1185039Y0D02*
G03X1181102Y-3937I0J-3937D01*
G01X1164984Y557626D02*
G03X1198795I16906J-13531D01*
G01X1164984Y557625D02*
G03X1198795I16906J-13531D01*
G01X1191870Y570756D02*
G03X1171909I-9980J-3039D01*
G01X1191870D02*
G03X1171909I-9980J-3039D01*
G01X1164984Y557626D02*
G03X1171909Y570756I-30736J24602D01*
G01X1164984Y557625D02*
G03X1171909Y570756I-30737J24602D01*
G01X1164984Y971011D02*
G03X1198795I16906J-13531D01*
G01X1164984D02*
G03X1198795I16906J-13531D01*
G01X1191870Y984142D02*
G03X1171909I-9980J-3040D01*
G01X1191870D02*
G03X1171909I-9980J-3039D01*
G01X1164984Y971011D02*
G03X1171909Y984142I-30737J24602D01*
G01X1164984Y971011D02*
G03X1171909Y984142I-30737J24602D01*
G01X1164173Y1378740D02*
Y1468504D01*
G01X1930906Y1374803D02*
X1168110D01*
G01X1164173Y1378740D02*
G03X1168110Y1374803I3937J0D01*
G01X1172047Y1382677D02*
Y1464567D01*
G01X1195669Y1382677D02*
X1172047D01*
G01X1930906Y1374803D02*
X1168110D01*
G01X1164173Y1378740D02*
G03X1168110Y1374804I3937J1D01*
G01X1164173Y1378740D02*
Y1468504D01*
G01X1172047Y1382677D02*
Y1464567D01*
G01X1195669Y1382677D02*
X1172047D01*
G01X1168110Y1472441D02*
G03X1164173Y1468504I0J-3937D01*
G01X1168110Y1472441D02*
G03X1164173Y1468504I0J-3937D01*
G01X1172047Y1464567D02*
X1216535D01*
G01X1172047D02*
X1216535D01*
G01X1168110Y1472441D02*
X1216535D01*
G01X1168110D02*
X1216535D01*
G01X1164984Y1561563D02*
G03X1171909Y1574693I-30736J24602D01*
G01X1164984Y1561562D02*
G03X1171909Y1574693I-30737J24602D01*
G01X1164984Y1561563D02*
G03X1198795I16906J-13531D01*
G01X1164984Y1561562D02*
G03X1198795I16906J-13531D01*
G01X1191870Y1574693D02*
G03X1171909I-9980J-3039D01*
G01X1191870D02*
G03X1171909I-9980J-3039D01*
G01X1188976Y-148819D02*
Y-125197D01*
G01Y-148819D02*
G03X1192913Y-152756I3937J0D01*
G01X1188976Y-148819D02*
Y-125197D01*
G01Y-148819D02*
G03X1192913Y-152756I3937J0D01*
G01D02*
X1919843D01*
G01X1192913D02*
X1919843D01*
G01X1188976Y-94488D02*
Y-7874D01*
G01Y-94488D02*
Y-7874D01*
G01X1185039Y0D02*
X1366142D01*
G01X1188976Y-7874D02*
X1315748D01*
G01X1185039Y0D02*
X1366142D01*
G01X1188976Y-7874D02*
X1315748D01*
G01X1225433Y367773D02*
X1225833Y367440D01*
X1226300Y367240D01*
X1226900Y367173D01*
X1227500Y367306D01*
X1227967Y367573D01*
X1228300Y368040D01*
X1228367Y368573D01*
X1228233Y369106D01*
X1227900Y369440D01*
X1227433Y369706D01*
X1226967Y369773D01*
X1226500Y369706D01*
X1225900Y369440D01*
X1226100Y371173D01*
X1227900D01*
G01X1230033Y367773D02*
X1230433Y367440D01*
X1230900Y367240D01*
X1231500Y367173D01*
X1232100Y367306D01*
X1232567Y367573D01*
X1232900Y368040D01*
X1232967Y368573D01*
X1232833Y369106D01*
X1232500Y369440D01*
X1232033Y369706D01*
X1231567Y369773D01*
X1231100Y369706D01*
X1230500Y369440D01*
X1230700Y371173D01*
X1232500D01*
G01X1235967Y367173D02*
X1236100Y368040D01*
X1236300Y368773D01*
X1236567Y369440D01*
X1236900Y370173D01*
X1237433Y371173D01*
X1234767D01*
G01X1240700Y367040D02*
X1240567Y367106D01*
Y367240D01*
X1240700Y367306D01*
X1240833Y367240D01*
Y367106D01*
X1240700Y367040D01*
G01X1245300Y371173D02*
X1244767Y371040D01*
X1244367Y370706D01*
X1244100Y370306D01*
X1243900Y369773D01*
X1243833Y369173D01*
X1243900Y368573D01*
X1244100Y368040D01*
X1244367Y367640D01*
X1244767Y367306D01*
X1245300Y367173D01*
X1245833Y367306D01*
X1246233Y367640D01*
X1246500Y368040D01*
X1246700Y368573D01*
X1246767Y369173D01*
X1246700Y369773D01*
X1246500Y370306D01*
X1246233Y370706D01*
X1245833Y371040D01*
X1245300Y371173D01*
G01X1248767Y367640D02*
X1249233Y367306D01*
X1249767Y367173D01*
X1250300Y367306D01*
X1250767Y367706D01*
X1251100Y368306D01*
X1251233Y368906D01*
Y369640D01*
X1251100Y370240D01*
X1250767Y370773D01*
X1250367Y371040D01*
X1249900Y371173D01*
X1249367Y371040D01*
X1248967Y370773D01*
X1248700Y370373D01*
X1248567Y369840D01*
X1248700Y369373D01*
X1249033Y368906D01*
X1249433Y368640D01*
X1249900Y368573D01*
X1250433Y368706D01*
X1250833Y369040D01*
X1251233Y369640D01*
G01X1223487Y513488D02*
Y517488D01*
X1221020Y514621D01*
X1224354D01*
G01X1225820Y514288D02*
X1226220Y513821D01*
X1226754Y513555D01*
X1227354Y513488D01*
X1227887Y513555D01*
X1228420Y513888D01*
X1228754Y514288D01*
X1228820Y514688D01*
X1228687Y515155D01*
X1228220Y515488D01*
X1227754Y515621D01*
X1227154D01*
G01X1227754D02*
X1228154Y515821D01*
X1228487Y516155D01*
X1228620Y516555D01*
X1228487Y516955D01*
X1228154Y517288D01*
X1227554Y517488D01*
X1226954Y517421D01*
X1226354Y517155D01*
G01X1230420Y514288D02*
X1230820Y513821D01*
X1231354Y513555D01*
X1231954Y513488D01*
X1232487Y513555D01*
X1233020Y513888D01*
X1233354Y514288D01*
X1233420Y514688D01*
X1233287Y515155D01*
X1232820Y515488D01*
X1232354Y515621D01*
X1231754D01*
G01X1232354D02*
X1232754Y515821D01*
X1233087Y516155D01*
X1233220Y516555D01*
X1233087Y516955D01*
X1232754Y517288D01*
X1232154Y517488D01*
X1231554Y517421D01*
X1230954Y517155D01*
G01X1236487Y513355D02*
X1236354Y513421D01*
Y513555D01*
X1236487Y513621D01*
X1236620Y513555D01*
Y513421D01*
X1236487Y513355D01*
G01X1241087Y517488D02*
X1240554Y517355D01*
X1240154Y517021D01*
X1239887Y516621D01*
X1239687Y516088D01*
X1239620Y515488D01*
X1239687Y514888D01*
X1239887Y514355D01*
X1240154Y513955D01*
X1240554Y513621D01*
X1241087Y513488D01*
X1241620Y513621D01*
X1242020Y513955D01*
X1242287Y514355D01*
X1242487Y514888D01*
X1242554Y515488D01*
X1242487Y516088D01*
X1242287Y516621D01*
X1242020Y517021D01*
X1241620Y517355D01*
X1241087Y517488D01*
G01X1245687Y513488D02*
X1246154Y513555D01*
X1246687Y513755D01*
X1247020Y514088D01*
X1247154Y514555D01*
X1247020Y515021D01*
X1246620Y515421D01*
X1246020Y515621D01*
X1245354D01*
X1244954Y515755D01*
X1244620Y516088D01*
X1244487Y516555D01*
X1244687Y517021D01*
X1245154Y517355D01*
X1245687Y517488D01*
X1246220Y517355D01*
X1246687Y517021D01*
X1246887Y516555D01*
X1246754Y516088D01*
X1246420Y515755D01*
X1246020Y515621D01*
X1245354D01*
X1244754Y515421D01*
X1244354Y515021D01*
X1244220Y514555D01*
X1244354Y514088D01*
X1244687Y513755D01*
X1245220Y513555D01*
X1245687Y513488D01*
G01X1223579Y597812D02*
X1223979Y598212D01*
X1224446Y598412D01*
X1224979Y598479D01*
X1225646Y598346D01*
X1226113Y598012D01*
X1226246Y597612D01*
X1226179Y597212D01*
X1225913Y596879D01*
X1224579Y596212D01*
X1223979Y595746D01*
X1223579Y595079D01*
X1223446Y594479D01*
X1226246D01*
G01X1229446Y598479D02*
X1228913Y598346D01*
X1228513Y598012D01*
X1228246Y597612D01*
X1228046Y597079D01*
X1227979Y596479D01*
X1228046Y595879D01*
X1228246Y595346D01*
X1228513Y594946D01*
X1228913Y594612D01*
X1229446Y594479D01*
X1229979Y594612D01*
X1230379Y594946D01*
X1230646Y595346D01*
X1230846Y595879D01*
X1230913Y596479D01*
X1230846Y597079D01*
X1230646Y597612D01*
X1230379Y598012D01*
X1229979Y598346D01*
X1229446Y598479D01*
G01X1234046Y594479D02*
X1234513Y594546D01*
X1235046Y594746D01*
X1235379Y595079D01*
X1235513Y595546D01*
X1235379Y596012D01*
X1234979Y596412D01*
X1234379Y596612D01*
X1233713D01*
X1233313Y596746D01*
X1232979Y597079D01*
X1232846Y597546D01*
X1233046Y598012D01*
X1233513Y598346D01*
X1234046Y598479D01*
X1234579Y598346D01*
X1235046Y598012D01*
X1235246Y597546D01*
X1235113Y597079D01*
X1234779Y596746D01*
X1234379Y596612D01*
X1233713D01*
X1233113Y596412D01*
X1232713Y596012D01*
X1232579Y595546D01*
X1232713Y595079D01*
X1233046Y594746D01*
X1233579Y594546D01*
X1234046Y594479D01*
G01X1238646Y594346D02*
X1238513Y594412D01*
Y594546D01*
X1238646Y594612D01*
X1238779Y594546D01*
Y594412D01*
X1238646Y594346D01*
G01X1241979Y596146D02*
X1242446Y596612D01*
X1242846Y596879D01*
X1243379Y597012D01*
X1243846Y596879D01*
X1244179Y596612D01*
X1244446Y596212D01*
X1244513Y595746D01*
X1244446Y595346D01*
X1244179Y594946D01*
X1243779Y594612D01*
X1243313Y594479D01*
X1242779Y594612D01*
X1242313Y595012D01*
X1242046Y595612D01*
X1241979Y596279D01*
X1242113Y597146D01*
X1242313Y597612D01*
X1242646Y598079D01*
X1243113Y598412D01*
X1243579Y598479D01*
X1244046Y598346D01*
X1244379Y598012D01*
G01X1246579Y596146D02*
X1247046Y596612D01*
X1247446Y596879D01*
X1247979Y597012D01*
X1248446Y596879D01*
X1248779Y596612D01*
X1249046Y596212D01*
X1249113Y595746D01*
X1249046Y595346D01*
X1248779Y594946D01*
X1248379Y594612D01*
X1247913Y594479D01*
X1247379Y594612D01*
X1246913Y595012D01*
X1246646Y595612D01*
X1246579Y596279D01*
X1246713Y597146D01*
X1246913Y597612D01*
X1247246Y598079D01*
X1247713Y598412D01*
X1248179Y598479D01*
X1248646Y598346D01*
X1248979Y598012D01*
G01X1217024Y555645D02*
Y559645D01*
X1218358D01*
X1218891Y559445D01*
X1219291Y559178D01*
X1219624Y558778D01*
X1219891Y558312D01*
X1219958Y557645D01*
X1219891Y556978D01*
X1219624Y556512D01*
X1219291Y556112D01*
X1218891Y555845D01*
X1218358Y555645D01*
X1217024D01*
G01X1222158D02*
Y558312D01*
G01Y557778D02*
X1222491Y558045D01*
X1222824Y558245D01*
X1223291Y558312D01*
X1223624Y558245D01*
X1224024Y558045D01*
G01X1227691Y558312D02*
Y555645D01*
G01Y559378D02*
X1227558Y559445D01*
Y559578D01*
X1227691Y559645D01*
X1227824Y559578D01*
Y559445D01*
X1227691Y559378D01*
G01X1232291Y555645D02*
Y559645D01*
G01X1236891Y555645D02*
Y559645D01*
G01X1245691Y555645D02*
Y559045D01*
X1245824Y559378D01*
X1246091Y559578D01*
X1246491Y559645D01*
X1246891Y559512D01*
X1247091Y559178D01*
G01X1246291Y558045D02*
X1244958D01*
G01X1249691Y557445D02*
X1251824D01*
X1251624Y557912D01*
X1251291Y558178D01*
X1250824Y558312D01*
X1250358Y558245D01*
X1249958Y558045D01*
X1249691Y557578D01*
X1249558Y557178D01*
Y556778D01*
X1249691Y556378D01*
X1250024Y555978D01*
X1250424Y555712D01*
X1250891Y555645D01*
X1251358Y555778D01*
X1251824Y556178D01*
G01X1256491Y555645D02*
Y558312D01*
G01Y557845D02*
X1256224Y558112D01*
X1255824Y558245D01*
X1255358Y558312D01*
X1254891Y558178D01*
X1254491Y557912D01*
X1254224Y557512D01*
X1254091Y556978D01*
X1254224Y556445D01*
X1254491Y556045D01*
X1254891Y555778D01*
X1255358Y555645D01*
X1255824Y555712D01*
X1256224Y555912D01*
X1256491Y556178D01*
G01X1259891Y559645D02*
Y555645D01*
G01X1258958Y558312D02*
X1260824D01*
G01X1263358D02*
Y556445D01*
X1263624Y555978D01*
X1264024Y555712D01*
X1264491Y555645D01*
X1264958Y555712D01*
X1265358Y555978D01*
X1265624Y556445D01*
G01Y555645D02*
Y558312D01*
G01X1268158Y555645D02*
Y558312D01*
G01Y557778D02*
X1268491Y558045D01*
X1268824Y558245D01*
X1269291Y558312D01*
X1269624Y558245D01*
X1270024Y558045D01*
G01X1272691Y557445D02*
X1274824D01*
X1274624Y557912D01*
X1274291Y558178D01*
X1273824Y558312D01*
X1273358Y558245D01*
X1272958Y558045D01*
X1272691Y557578D01*
X1272558Y557178D01*
Y556778D01*
X1272691Y556378D01*
X1273024Y555978D01*
X1273424Y555712D01*
X1273891Y555645D01*
X1274358Y555778D01*
X1274824Y556178D01*
G01X1191870Y570756D02*
G03X1198795Y557626I37662J11472D01*
G01X1191870Y570756D02*
G03X1198795Y557626I37662J11472D01*
G01X1225433Y820529D02*
X1225833Y820196D01*
X1226300Y819996D01*
X1226900Y819929D01*
X1227500Y820062D01*
X1227967Y820329D01*
X1228300Y820796D01*
X1228367Y821329D01*
X1228233Y821862D01*
X1227900Y822196D01*
X1227433Y822462D01*
X1226967Y822529D01*
X1226500Y822462D01*
X1225900Y822196D01*
X1226100Y823929D01*
X1227900D01*
G01X1230033Y820529D02*
X1230433Y820196D01*
X1230900Y819996D01*
X1231500Y819929D01*
X1232100Y820062D01*
X1232567Y820329D01*
X1232900Y820796D01*
X1232967Y821329D01*
X1232833Y821862D01*
X1232500Y822196D01*
X1232033Y822462D01*
X1231567Y822529D01*
X1231100Y822462D01*
X1230500Y822196D01*
X1230700Y823929D01*
X1232500D01*
G01X1235967Y819929D02*
X1236100Y820796D01*
X1236300Y821529D01*
X1236567Y822196D01*
X1236900Y822929D01*
X1237433Y823929D01*
X1234767D01*
G01X1240700Y819796D02*
X1240567Y819862D01*
Y819996D01*
X1240700Y820062D01*
X1240833Y819996D01*
Y819862D01*
X1240700Y819796D01*
G01X1245300Y823929D02*
X1244767Y823796D01*
X1244367Y823462D01*
X1244100Y823062D01*
X1243900Y822529D01*
X1243833Y821929D01*
X1243900Y821329D01*
X1244100Y820796D01*
X1244367Y820396D01*
X1244767Y820062D01*
X1245300Y819929D01*
X1245833Y820062D01*
X1246233Y820396D01*
X1246500Y820796D01*
X1246700Y821329D01*
X1246767Y821929D01*
X1246700Y822529D01*
X1246500Y823062D01*
X1246233Y823462D01*
X1245833Y823796D01*
X1245300Y823929D01*
G01X1248767Y820396D02*
X1249233Y820062D01*
X1249767Y819929D01*
X1250300Y820062D01*
X1250767Y820462D01*
X1251100Y821062D01*
X1251233Y821662D01*
Y822396D01*
X1251100Y822996D01*
X1250767Y823529D01*
X1250367Y823796D01*
X1249900Y823929D01*
X1249367Y823796D01*
X1248967Y823529D01*
X1248700Y823129D01*
X1248567Y822596D01*
X1248700Y822129D01*
X1249033Y821662D01*
X1249433Y821396D01*
X1249900Y821329D01*
X1250433Y821462D01*
X1250833Y821796D01*
X1251233Y822396D01*
G01X1223467Y926851D02*
Y930851D01*
X1221000Y927984D01*
X1224334D01*
G01X1225800Y927651D02*
X1226200Y927184D01*
X1226734Y926918D01*
X1227334Y926851D01*
X1227867Y926918D01*
X1228400Y927251D01*
X1228734Y927651D01*
X1228800Y928051D01*
X1228667Y928518D01*
X1228200Y928851D01*
X1227734Y928984D01*
X1227134D01*
G01X1227734D02*
X1228134Y929184D01*
X1228467Y929518D01*
X1228600Y929918D01*
X1228467Y930318D01*
X1228134Y930651D01*
X1227534Y930851D01*
X1226934Y930784D01*
X1226334Y930518D01*
G01X1230400Y927651D02*
X1230800Y927184D01*
X1231334Y926918D01*
X1231934Y926851D01*
X1232467Y926918D01*
X1233000Y927251D01*
X1233334Y927651D01*
X1233400Y928051D01*
X1233267Y928518D01*
X1232800Y928851D01*
X1232334Y928984D01*
X1231734D01*
G01X1232334D02*
X1232734Y929184D01*
X1233067Y929518D01*
X1233200Y929918D01*
X1233067Y930318D01*
X1232734Y930651D01*
X1232134Y930851D01*
X1231534Y930784D01*
X1230934Y930518D01*
G01X1236467Y926718D02*
X1236334Y926784D01*
Y926918D01*
X1236467Y926984D01*
X1236600Y926918D01*
Y926784D01*
X1236467Y926718D01*
G01X1241067Y930851D02*
X1240534Y930718D01*
X1240134Y930384D01*
X1239867Y929984D01*
X1239667Y929451D01*
X1239600Y928851D01*
X1239667Y928251D01*
X1239867Y927718D01*
X1240134Y927318D01*
X1240534Y926984D01*
X1241067Y926851D01*
X1241600Y926984D01*
X1242000Y927318D01*
X1242267Y927718D01*
X1242467Y928251D01*
X1242534Y928851D01*
X1242467Y929451D01*
X1242267Y929984D01*
X1242000Y930384D01*
X1241600Y930718D01*
X1241067Y930851D01*
G01X1245667Y926851D02*
X1246134Y926918D01*
X1246667Y927118D01*
X1247000Y927451D01*
X1247134Y927918D01*
X1247000Y928384D01*
X1246600Y928784D01*
X1246000Y928984D01*
X1245334D01*
X1244934Y929118D01*
X1244600Y929451D01*
X1244467Y929918D01*
X1244667Y930384D01*
X1245134Y930718D01*
X1245667Y930851D01*
X1246200Y930718D01*
X1246667Y930384D01*
X1246867Y929918D01*
X1246734Y929451D01*
X1246400Y929118D01*
X1246000Y928984D01*
X1245334D01*
X1244734Y928784D01*
X1244334Y928384D01*
X1244200Y927918D01*
X1244334Y927451D01*
X1244667Y927118D01*
X1245200Y926918D01*
X1245667Y926851D01*
G01X1217004Y969008D02*
Y973008D01*
X1218338D01*
X1218871Y972808D01*
X1219271Y972541D01*
X1219604Y972141D01*
X1219871Y971675D01*
X1219938Y971008D01*
X1219871Y970341D01*
X1219604Y969875D01*
X1219271Y969475D01*
X1218871Y969208D01*
X1218338Y969008D01*
X1217004D01*
G01X1222138D02*
Y971675D01*
G01Y971141D02*
X1222471Y971408D01*
X1222804Y971608D01*
X1223271Y971675D01*
X1223604Y971608D01*
X1224004Y971408D01*
G01X1227671Y971675D02*
Y969008D01*
G01Y972741D02*
X1227538Y972808D01*
Y972941D01*
X1227671Y973008D01*
X1227804Y972941D01*
Y972808D01*
X1227671Y972741D01*
G01X1232271Y969008D02*
Y973008D01*
G01X1236871Y969008D02*
Y973008D01*
G01X1245671Y969008D02*
Y972408D01*
X1245804Y972741D01*
X1246071Y972941D01*
X1246471Y973008D01*
X1246871Y972875D01*
X1247071Y972541D01*
G01X1246271Y971408D02*
X1244938D01*
G01X1249671Y970808D02*
X1251804D01*
X1251604Y971275D01*
X1251271Y971541D01*
X1250804Y971675D01*
X1250338Y971608D01*
X1249938Y971408D01*
X1249671Y970941D01*
X1249538Y970541D01*
Y970141D01*
X1249671Y969741D01*
X1250004Y969341D01*
X1250404Y969075D01*
X1250871Y969008D01*
X1251338Y969141D01*
X1251804Y969541D01*
G01X1256471Y969008D02*
Y971675D01*
G01Y971208D02*
X1256204Y971475D01*
X1255804Y971608D01*
X1255338Y971675D01*
X1254871Y971541D01*
X1254471Y971275D01*
X1254204Y970875D01*
X1254071Y970341D01*
X1254204Y969808D01*
X1254471Y969408D01*
X1254871Y969141D01*
X1255338Y969008D01*
X1255804Y969075D01*
X1256204Y969275D01*
X1256471Y969541D01*
G01X1259871Y973008D02*
Y969008D01*
G01X1258938Y971675D02*
X1260804D01*
G01X1263338D02*
Y969808D01*
X1263604Y969341D01*
X1264004Y969075D01*
X1264471Y969008D01*
X1264938Y969075D01*
X1265338Y969341D01*
X1265604Y969808D01*
G01Y969008D02*
Y971675D01*
G01X1268138Y969008D02*
Y971675D01*
G01Y971141D02*
X1268471Y971408D01*
X1268804Y971608D01*
X1269271Y971675D01*
X1269604Y971608D01*
X1270004Y971408D01*
G01X1272671Y970808D02*
X1274804D01*
X1274604Y971275D01*
X1274271Y971541D01*
X1273804Y971675D01*
X1273338Y971608D01*
X1272938Y971408D01*
X1272671Y970941D01*
X1272538Y970541D01*
Y970141D01*
X1272671Y969741D01*
X1273004Y969341D01*
X1273404Y969075D01*
X1273871Y969008D01*
X1274338Y969141D01*
X1274804Y969541D01*
G01X1191870Y984142D02*
G03X1198795Y971011I37662J11471D01*
G01X1191870Y984142D02*
G03X1198795Y971011I37662J11471D01*
G01X1223559Y1011175D02*
X1223959Y1011575D01*
X1224426Y1011775D01*
X1224959Y1011842D01*
X1225626Y1011709D01*
X1226093Y1011375D01*
X1226226Y1010975D01*
X1226159Y1010575D01*
X1225893Y1010242D01*
X1224559Y1009575D01*
X1223959Y1009109D01*
X1223559Y1008442D01*
X1223426Y1007842D01*
X1226226D01*
G01X1229426Y1011842D02*
X1228893Y1011709D01*
X1228493Y1011375D01*
X1228226Y1010975D01*
X1228026Y1010442D01*
X1227959Y1009842D01*
X1228026Y1009242D01*
X1228226Y1008709D01*
X1228493Y1008309D01*
X1228893Y1007975D01*
X1229426Y1007842D01*
X1229959Y1007975D01*
X1230359Y1008309D01*
X1230626Y1008709D01*
X1230826Y1009242D01*
X1230893Y1009842D01*
X1230826Y1010442D01*
X1230626Y1010975D01*
X1230359Y1011375D01*
X1229959Y1011709D01*
X1229426Y1011842D01*
G01X1234026Y1007842D02*
X1234493Y1007909D01*
X1235026Y1008109D01*
X1235359Y1008442D01*
X1235493Y1008909D01*
X1235359Y1009375D01*
X1234959Y1009775D01*
X1234359Y1009975D01*
X1233693D01*
X1233293Y1010109D01*
X1232959Y1010442D01*
X1232826Y1010909D01*
X1233026Y1011375D01*
X1233493Y1011709D01*
X1234026Y1011842D01*
X1234559Y1011709D01*
X1235026Y1011375D01*
X1235226Y1010909D01*
X1235093Y1010442D01*
X1234759Y1010109D01*
X1234359Y1009975D01*
X1233693D01*
X1233093Y1009775D01*
X1232693Y1009375D01*
X1232559Y1008909D01*
X1232693Y1008442D01*
X1233026Y1008109D01*
X1233559Y1007909D01*
X1234026Y1007842D01*
G01X1238626Y1007709D02*
X1238493Y1007775D01*
Y1007909D01*
X1238626Y1007975D01*
X1238759Y1007909D01*
Y1007775D01*
X1238626Y1007709D01*
G01X1241959Y1009509D02*
X1242426Y1009975D01*
X1242826Y1010242D01*
X1243359Y1010375D01*
X1243826Y1010242D01*
X1244159Y1009975D01*
X1244426Y1009575D01*
X1244493Y1009109D01*
X1244426Y1008709D01*
X1244159Y1008309D01*
X1243759Y1007975D01*
X1243293Y1007842D01*
X1242759Y1007975D01*
X1242293Y1008375D01*
X1242026Y1008975D01*
X1241959Y1009642D01*
X1242093Y1010509D01*
X1242293Y1010975D01*
X1242626Y1011442D01*
X1243093Y1011775D01*
X1243559Y1011842D01*
X1244026Y1011709D01*
X1244359Y1011375D01*
G01X1246559Y1009509D02*
X1247026Y1009975D01*
X1247426Y1010242D01*
X1247959Y1010375D01*
X1248426Y1010242D01*
X1248759Y1009975D01*
X1249026Y1009575D01*
X1249093Y1009109D01*
X1249026Y1008709D01*
X1248759Y1008309D01*
X1248359Y1007975D01*
X1247893Y1007842D01*
X1247359Y1007975D01*
X1246893Y1008375D01*
X1246626Y1008975D01*
X1246559Y1009642D01*
X1246693Y1010509D01*
X1246893Y1010975D01*
X1247226Y1011442D01*
X1247693Y1011775D01*
X1248159Y1011842D01*
X1248626Y1011709D01*
X1248959Y1011375D01*
G01X1225433Y1273285D02*
X1225833Y1272952D01*
X1226300Y1272752D01*
X1226900Y1272685D01*
X1227500Y1272818D01*
X1227967Y1273085D01*
X1228300Y1273552D01*
X1228367Y1274085D01*
X1228233Y1274618D01*
X1227900Y1274952D01*
X1227433Y1275218D01*
X1226967Y1275285D01*
X1226500Y1275218D01*
X1225900Y1274952D01*
X1226100Y1276685D01*
X1227900D01*
G01X1230033Y1273285D02*
X1230433Y1272952D01*
X1230900Y1272752D01*
X1231500Y1272685D01*
X1232100Y1272818D01*
X1232567Y1273085D01*
X1232900Y1273552D01*
X1232967Y1274085D01*
X1232833Y1274618D01*
X1232500Y1274952D01*
X1232033Y1275218D01*
X1231567Y1275285D01*
X1231100Y1275218D01*
X1230500Y1274952D01*
X1230700Y1276685D01*
X1232500D01*
G01X1235967Y1272685D02*
X1236100Y1273552D01*
X1236300Y1274285D01*
X1236567Y1274952D01*
X1236900Y1275685D01*
X1237433Y1276685D01*
X1234767D01*
G01X1240700Y1272552D02*
X1240567Y1272618D01*
Y1272752D01*
X1240700Y1272818D01*
X1240833Y1272752D01*
Y1272618D01*
X1240700Y1272552D01*
G01X1245300Y1276685D02*
X1244767Y1276552D01*
X1244367Y1276218D01*
X1244100Y1275818D01*
X1243900Y1275285D01*
X1243833Y1274685D01*
X1243900Y1274085D01*
X1244100Y1273552D01*
X1244367Y1273152D01*
X1244767Y1272818D01*
X1245300Y1272685D01*
X1245833Y1272818D01*
X1246233Y1273152D01*
X1246500Y1273552D01*
X1246700Y1274085D01*
X1246767Y1274685D01*
X1246700Y1275285D01*
X1246500Y1275818D01*
X1246233Y1276218D01*
X1245833Y1276552D01*
X1245300Y1276685D01*
G01X1248767Y1273152D02*
X1249233Y1272818D01*
X1249767Y1272685D01*
X1250300Y1272818D01*
X1250767Y1273218D01*
X1251100Y1273818D01*
X1251233Y1274418D01*
Y1275152D01*
X1251100Y1275752D01*
X1250767Y1276285D01*
X1250367Y1276552D01*
X1249900Y1276685D01*
X1249367Y1276552D01*
X1248967Y1276285D01*
X1248700Y1275885D01*
X1248567Y1275352D01*
X1248700Y1274885D01*
X1249033Y1274418D01*
X1249433Y1274152D01*
X1249900Y1274085D01*
X1250433Y1274218D01*
X1250833Y1274552D01*
X1251233Y1275152D01*
G01X1524606Y1382677D02*
X1226378D01*
G01X1524606D02*
X1226378D01*
G01X1195669Y1374803D02*
G03Y1382677I0J3937D01*
G01X1226378D02*
G03Y1374803I0J-3937D01*
G01X1195669D02*
G03Y1382677I0J3937D01*
G01X1226378D02*
G03Y1374803I0J-3937D01*
G01X1216535Y1464567D02*
G03X1228346Y1476378I0J11811D01*
G01X1216535Y1464567D02*
G03X1228346Y1476378I0J11811D01*
G01X1223487Y1517425D02*
Y1521425D01*
X1221020Y1518558D01*
X1224354D01*
G01X1225820Y1518225D02*
X1226220Y1517758D01*
X1226754Y1517492D01*
X1227354Y1517425D01*
X1227887Y1517492D01*
X1228420Y1517825D01*
X1228754Y1518225D01*
X1228820Y1518625D01*
X1228687Y1519092D01*
X1228220Y1519425D01*
X1227754Y1519558D01*
X1227154D01*
G01X1227754D02*
X1228154Y1519758D01*
X1228487Y1520092D01*
X1228620Y1520492D01*
X1228487Y1520892D01*
X1228154Y1521225D01*
X1227554Y1521425D01*
X1226954Y1521358D01*
X1226354Y1521092D01*
G01X1230420Y1518225D02*
X1230820Y1517758D01*
X1231354Y1517492D01*
X1231954Y1517425D01*
X1232487Y1517492D01*
X1233020Y1517825D01*
X1233354Y1518225D01*
X1233420Y1518625D01*
X1233287Y1519092D01*
X1232820Y1519425D01*
X1232354Y1519558D01*
X1231754D01*
G01X1232354D02*
X1232754Y1519758D01*
X1233087Y1520092D01*
X1233220Y1520492D01*
X1233087Y1520892D01*
X1232754Y1521225D01*
X1232154Y1521425D01*
X1231554Y1521358D01*
X1230954Y1521092D01*
G01X1236487Y1517292D02*
X1236354Y1517358D01*
Y1517492D01*
X1236487Y1517558D01*
X1236620Y1517492D01*
Y1517358D01*
X1236487Y1517292D01*
G01X1241087Y1521425D02*
X1240554Y1521292D01*
X1240154Y1520958D01*
X1239887Y1520558D01*
X1239687Y1520025D01*
X1239620Y1519425D01*
X1239687Y1518825D01*
X1239887Y1518292D01*
X1240154Y1517892D01*
X1240554Y1517558D01*
X1241087Y1517425D01*
X1241620Y1517558D01*
X1242020Y1517892D01*
X1242287Y1518292D01*
X1242487Y1518825D01*
X1242554Y1519425D01*
X1242487Y1520025D01*
X1242287Y1520558D01*
X1242020Y1520958D01*
X1241620Y1521292D01*
X1241087Y1521425D01*
G01X1245687Y1517425D02*
X1246154Y1517492D01*
X1246687Y1517692D01*
X1247020Y1518025D01*
X1247154Y1518492D01*
X1247020Y1518958D01*
X1246620Y1519358D01*
X1246020Y1519558D01*
X1245354D01*
X1244954Y1519692D01*
X1244620Y1520025D01*
X1244487Y1520492D01*
X1244687Y1520958D01*
X1245154Y1521292D01*
X1245687Y1521425D01*
X1246220Y1521292D01*
X1246687Y1520958D01*
X1246887Y1520492D01*
X1246754Y1520025D01*
X1246420Y1519692D01*
X1246020Y1519558D01*
X1245354D01*
X1244754Y1519358D01*
X1244354Y1518958D01*
X1244220Y1518492D01*
X1244354Y1518025D01*
X1244687Y1517692D01*
X1245220Y1517492D01*
X1245687Y1517425D01*
G01X1228346Y1592126D02*
Y1476378D01*
G01Y1592126D02*
Y1476378D01*
G01X1220472Y1654331D02*
Y1476378D01*
G01X1216535Y1472441D02*
G03X1220472Y1476378I0J3937D01*
G01X1216535Y1472441D02*
G03X1220472Y1476378I0J3937D01*
G01D02*
Y1654331D01*
G01X1217024Y1559582D02*
Y1563582D01*
X1218358D01*
X1218891Y1563382D01*
X1219291Y1563115D01*
X1219624Y1562715D01*
X1219891Y1562249D01*
X1219958Y1561582D01*
X1219891Y1560915D01*
X1219624Y1560449D01*
X1219291Y1560049D01*
X1218891Y1559782D01*
X1218358Y1559582D01*
X1217024D01*
G01X1222158D02*
Y1562249D01*
G01Y1561715D02*
X1222491Y1561982D01*
X1222824Y1562182D01*
X1223291Y1562249D01*
X1223624Y1562182D01*
X1224024Y1561982D01*
G01X1227691Y1562249D02*
Y1559582D01*
G01Y1563315D02*
X1227558Y1563382D01*
Y1563515D01*
X1227691Y1563582D01*
X1227824Y1563515D01*
Y1563382D01*
X1227691Y1563315D01*
G01X1232291Y1559582D02*
Y1563582D01*
G01X1236891Y1559582D02*
Y1563582D01*
G01X1245691Y1559582D02*
Y1562982D01*
X1245824Y1563315D01*
X1246091Y1563515D01*
X1246491Y1563582D01*
X1246891Y1563449D01*
X1247091Y1563115D01*
G01X1246291Y1561982D02*
X1244958D01*
G01X1249691Y1561382D02*
X1251824D01*
X1251624Y1561849D01*
X1251291Y1562115D01*
X1250824Y1562249D01*
X1250358Y1562182D01*
X1249958Y1561982D01*
X1249691Y1561515D01*
X1249558Y1561115D01*
Y1560715D01*
X1249691Y1560315D01*
X1250024Y1559915D01*
X1250424Y1559649D01*
X1250891Y1559582D01*
X1251358Y1559715D01*
X1251824Y1560115D01*
G01X1256491Y1559582D02*
Y1562249D01*
G01Y1561782D02*
X1256224Y1562049D01*
X1255824Y1562182D01*
X1255358Y1562249D01*
X1254891Y1562115D01*
X1254491Y1561849D01*
X1254224Y1561449D01*
X1254091Y1560915D01*
X1254224Y1560382D01*
X1254491Y1559982D01*
X1254891Y1559715D01*
X1255358Y1559582D01*
X1255824Y1559649D01*
X1256224Y1559849D01*
X1256491Y1560115D01*
G01X1259891Y1563582D02*
Y1559582D01*
G01X1258958Y1562249D02*
X1260824D01*
G01X1263358D02*
Y1560382D01*
X1263624Y1559915D01*
X1264024Y1559649D01*
X1264491Y1559582D01*
X1264958Y1559649D01*
X1265358Y1559915D01*
X1265624Y1560382D01*
G01Y1559582D02*
Y1562249D01*
G01X1268158Y1559582D02*
Y1562249D01*
G01Y1561715D02*
X1268491Y1561982D01*
X1268824Y1562182D01*
X1269291Y1562249D01*
X1269624Y1562182D01*
X1270024Y1561982D01*
G01X1272691Y1561382D02*
X1274824D01*
X1274624Y1561849D01*
X1274291Y1562115D01*
X1273824Y1562249D01*
X1273358Y1562182D01*
X1272958Y1561982D01*
X1272691Y1561515D01*
X1272558Y1561115D01*
Y1560715D01*
X1272691Y1560315D01*
X1273024Y1559915D01*
X1273424Y1559649D01*
X1273891Y1559582D01*
X1274358Y1559715D01*
X1274824Y1560115D01*
G01X1191870Y1574693D02*
G03X1198795Y1561563I37662J11472D01*
G01X1191870Y1574693D02*
G03X1198795Y1561562I37662J11471D01*
G01X1223579Y1601749D02*
X1223979Y1602149D01*
X1224446Y1602349D01*
X1224979Y1602416D01*
X1225646Y1602283D01*
X1226113Y1601949D01*
X1226246Y1601549D01*
X1226179Y1601149D01*
X1225913Y1600816D01*
X1224579Y1600149D01*
X1223979Y1599683D01*
X1223579Y1599016D01*
X1223446Y1598416D01*
X1226246D01*
G01X1229446Y1602416D02*
X1228913Y1602283D01*
X1228513Y1601949D01*
X1228246Y1601549D01*
X1228046Y1601016D01*
X1227979Y1600416D01*
X1228046Y1599816D01*
X1228246Y1599283D01*
X1228513Y1598883D01*
X1228913Y1598549D01*
X1229446Y1598416D01*
X1229979Y1598549D01*
X1230379Y1598883D01*
X1230646Y1599283D01*
X1230846Y1599816D01*
X1230913Y1600416D01*
X1230846Y1601016D01*
X1230646Y1601549D01*
X1230379Y1601949D01*
X1229979Y1602283D01*
X1229446Y1602416D01*
G01X1234046Y1598416D02*
X1234513Y1598483D01*
X1235046Y1598683D01*
X1235379Y1599016D01*
X1235513Y1599483D01*
X1235379Y1599949D01*
X1234979Y1600349D01*
X1234379Y1600549D01*
X1233713D01*
X1233313Y1600683D01*
X1232979Y1601016D01*
X1232846Y1601483D01*
X1233046Y1601949D01*
X1233513Y1602283D01*
X1234046Y1602416D01*
X1234579Y1602283D01*
X1235046Y1601949D01*
X1235246Y1601483D01*
X1235113Y1601016D01*
X1234779Y1600683D01*
X1234379Y1600549D01*
X1233713D01*
X1233113Y1600349D01*
X1232713Y1599949D01*
X1232579Y1599483D01*
X1232713Y1599016D01*
X1233046Y1598683D01*
X1233579Y1598483D01*
X1234046Y1598416D01*
G01X1238646Y1598283D02*
X1238513Y1598349D01*
Y1598483D01*
X1238646Y1598549D01*
X1238779Y1598483D01*
Y1598349D01*
X1238646Y1598283D01*
G01X1241979Y1600083D02*
X1242446Y1600549D01*
X1242846Y1600816D01*
X1243379Y1600949D01*
X1243846Y1600816D01*
X1244179Y1600549D01*
X1244446Y1600149D01*
X1244513Y1599683D01*
X1244446Y1599283D01*
X1244179Y1598883D01*
X1243779Y1598549D01*
X1243313Y1598416D01*
X1242779Y1598549D01*
X1242313Y1598949D01*
X1242046Y1599549D01*
X1241979Y1600216D01*
X1242113Y1601083D01*
X1242313Y1601549D01*
X1242646Y1602016D01*
X1243113Y1602349D01*
X1243579Y1602416D01*
X1244046Y1602283D01*
X1244379Y1601949D01*
G01X1246579Y1600083D02*
X1247046Y1600549D01*
X1247446Y1600816D01*
X1247979Y1600949D01*
X1248446Y1600816D01*
X1248779Y1600549D01*
X1249046Y1600149D01*
X1249113Y1599683D01*
X1249046Y1599283D01*
X1248779Y1598883D01*
X1248379Y1598549D01*
X1247913Y1598416D01*
X1247379Y1598549D01*
X1246913Y1598949D01*
X1246646Y1599549D01*
X1246579Y1600216D01*
X1246713Y1601083D01*
X1246913Y1601549D01*
X1247246Y1602016D01*
X1247713Y1602349D01*
X1248179Y1602416D01*
X1248646Y1602283D01*
X1248979Y1601949D01*
G01X1228346Y1592126D02*
G03X1220472I-3937J0D01*
G01X1228346D02*
G03X1220472I-3937J0D01*
G01X1232283Y1658268D02*
X1442382D01*
G01X1232283D02*
G03X1228346Y1654331I0J-3937D01*
G01X1232283Y1658268D02*
X1442382D01*
G01X1232283D02*
G03X1228346Y1654331I0J-3937D01*
G01D02*
Y1622835D01*
G01Y1654331D02*
Y1622835D01*
G01X1220472Y1654331D02*
G03X1216535Y1658268I-3937J0D01*
G01X1220472Y1654331D02*
G03X1216535Y1658268I-3937J0D01*
G01X1220472Y1622835D02*
G03X1228346I3937J0D01*
G01X1220472D02*
G03X1228346I3937J0D01*
G01X1242772Y378319D02*
X1243172Y378719D01*
X1243639Y378919D01*
X1244172Y378986D01*
X1244839Y378853D01*
X1245306Y378519D01*
X1245439Y378119D01*
X1245372Y377719D01*
X1245106Y377386D01*
X1243772Y376719D01*
X1243172Y376253D01*
X1242772Y375586D01*
X1242639Y374986D01*
X1245439D01*
G01X1247172Y375786D02*
X1247572Y375319D01*
X1248106Y375053D01*
X1248706Y374986D01*
X1249239Y375053D01*
X1249772Y375386D01*
X1250106Y375786D01*
X1250172Y376186D01*
X1250039Y376653D01*
X1249572Y376986D01*
X1249106Y377119D01*
X1248506D01*
G01X1249106D02*
X1249506Y377319D01*
X1249839Y377653D01*
X1249972Y378053D01*
X1249839Y378453D01*
X1249506Y378786D01*
X1248906Y378986D01*
X1248306Y378919D01*
X1247706Y378653D01*
G01X1251972Y376653D02*
X1252439Y377119D01*
X1252839Y377386D01*
X1253372Y377519D01*
X1253839Y377386D01*
X1254172Y377119D01*
X1254439Y376719D01*
X1254506Y376253D01*
X1254439Y375853D01*
X1254172Y375453D01*
X1253772Y375119D01*
X1253306Y374986D01*
X1252772Y375119D01*
X1252306Y375519D01*
X1252039Y376119D01*
X1251972Y376786D01*
X1252106Y377653D01*
X1252306Y378119D01*
X1252639Y378586D01*
X1253106Y378919D01*
X1253572Y378986D01*
X1254039Y378853D01*
X1254372Y378519D01*
G01X1257839Y374853D02*
X1257706Y374919D01*
Y375053D01*
X1257839Y375119D01*
X1257972Y375053D01*
Y374919D01*
X1257839Y374853D01*
G01X1261172Y378319D02*
X1261572Y378719D01*
X1262039Y378919D01*
X1262572Y378986D01*
X1263239Y378853D01*
X1263706Y378519D01*
X1263839Y378119D01*
X1263772Y377719D01*
X1263506Y377386D01*
X1262172Y376719D01*
X1261572Y376253D01*
X1261172Y375586D01*
X1261039Y374986D01*
X1263839D01*
G01X1265772Y378319D02*
X1266172Y378719D01*
X1266639Y378919D01*
X1267172Y378986D01*
X1267839Y378853D01*
X1268306Y378519D01*
X1268439Y378119D01*
X1268372Y377719D01*
X1268106Y377386D01*
X1266772Y376719D01*
X1266172Y376253D01*
X1265772Y375586D01*
X1265639Y374986D01*
X1268439D01*
G01X1284965Y378885D02*
G03X1318776I16906J-13531D01*
G01X1284965D02*
G03X1318775I16905J-13531D01*
G01X1242772Y831075D02*
X1243172Y831475D01*
X1243639Y831675D01*
X1244172Y831742D01*
X1244839Y831609D01*
X1245306Y831275D01*
X1245439Y830875D01*
X1245372Y830475D01*
X1245106Y830142D01*
X1243772Y829475D01*
X1243172Y829009D01*
X1242772Y828342D01*
X1242639Y827742D01*
X1245439D01*
G01X1247172Y828542D02*
X1247572Y828075D01*
X1248106Y827809D01*
X1248706Y827742D01*
X1249239Y827809D01*
X1249772Y828142D01*
X1250106Y828542D01*
X1250172Y828942D01*
X1250039Y829409D01*
X1249572Y829742D01*
X1249106Y829875D01*
X1248506D01*
G01X1249106D02*
X1249506Y830075D01*
X1249839Y830409D01*
X1249972Y830809D01*
X1249839Y831209D01*
X1249506Y831542D01*
X1248906Y831742D01*
X1248306Y831675D01*
X1247706Y831409D01*
G01X1251972Y829409D02*
X1252439Y829875D01*
X1252839Y830142D01*
X1253372Y830275D01*
X1253839Y830142D01*
X1254172Y829875D01*
X1254439Y829475D01*
X1254506Y829009D01*
X1254439Y828609D01*
X1254172Y828209D01*
X1253772Y827875D01*
X1253306Y827742D01*
X1252772Y827875D01*
X1252306Y828275D01*
X1252039Y828875D01*
X1251972Y829542D01*
X1252106Y830409D01*
X1252306Y830875D01*
X1252639Y831342D01*
X1253106Y831675D01*
X1253572Y831742D01*
X1254039Y831609D01*
X1254372Y831275D01*
G01X1257839Y827609D02*
X1257706Y827675D01*
Y827809D01*
X1257839Y827875D01*
X1257972Y827809D01*
Y827675D01*
X1257839Y827609D01*
G01X1261172Y831075D02*
X1261572Y831475D01*
X1262039Y831675D01*
X1262572Y831742D01*
X1263239Y831609D01*
X1263706Y831275D01*
X1263839Y830875D01*
X1263772Y830475D01*
X1263506Y830142D01*
X1262172Y829475D01*
X1261572Y829009D01*
X1261172Y828342D01*
X1261039Y827742D01*
X1263839D01*
G01X1265772Y831075D02*
X1266172Y831475D01*
X1266639Y831675D01*
X1267172Y831742D01*
X1267839Y831609D01*
X1268306Y831275D01*
X1268439Y830875D01*
X1268372Y830475D01*
X1268106Y830142D01*
X1266772Y829475D01*
X1266172Y829009D01*
X1265772Y828342D01*
X1265639Y827742D01*
X1268439D01*
G01X1284965Y831641D02*
G03X1318776I16906J-13531D01*
G01X1284965D02*
G03X1318775I16905J-13531D01*
G01X1284965Y1284397D02*
G03X1318776I16906J-13531D01*
G01X1284965D02*
G03X1318775I16905J-13531D01*
G01X1242772Y1283831D02*
X1243172Y1284231D01*
X1243639Y1284431D01*
X1244172Y1284498D01*
X1244839Y1284365D01*
X1245306Y1284031D01*
X1245439Y1283631D01*
X1245372Y1283231D01*
X1245106Y1282898D01*
X1243772Y1282231D01*
X1243172Y1281765D01*
X1242772Y1281098D01*
X1242639Y1280498D01*
X1245439D01*
G01X1247172Y1281298D02*
X1247572Y1280831D01*
X1248106Y1280565D01*
X1248706Y1280498D01*
X1249239Y1280565D01*
X1249772Y1280898D01*
X1250106Y1281298D01*
X1250172Y1281698D01*
X1250039Y1282165D01*
X1249572Y1282498D01*
X1249106Y1282631D01*
X1248506D01*
G01X1249106D02*
X1249506Y1282831D01*
X1249839Y1283165D01*
X1249972Y1283565D01*
X1249839Y1283965D01*
X1249506Y1284298D01*
X1248906Y1284498D01*
X1248306Y1284431D01*
X1247706Y1284165D01*
G01X1251972Y1282165D02*
X1252439Y1282631D01*
X1252839Y1282898D01*
X1253372Y1283031D01*
X1253839Y1282898D01*
X1254172Y1282631D01*
X1254439Y1282231D01*
X1254506Y1281765D01*
X1254439Y1281365D01*
X1254172Y1280965D01*
X1253772Y1280631D01*
X1253306Y1280498D01*
X1252772Y1280631D01*
X1252306Y1281031D01*
X1252039Y1281631D01*
X1251972Y1282298D01*
X1252106Y1283165D01*
X1252306Y1283631D01*
X1252639Y1284098D01*
X1253106Y1284431D01*
X1253572Y1284498D01*
X1254039Y1284365D01*
X1254372Y1284031D01*
G01X1257839Y1280365D02*
X1257706Y1280431D01*
Y1280565D01*
X1257839Y1280631D01*
X1257972Y1280565D01*
Y1280431D01*
X1257839Y1280365D01*
G01X1261172Y1283831D02*
X1261572Y1284231D01*
X1262039Y1284431D01*
X1262572Y1284498D01*
X1263239Y1284365D01*
X1263706Y1284031D01*
X1263839Y1283631D01*
X1263772Y1283231D01*
X1263506Y1282898D01*
X1262172Y1282231D01*
X1261572Y1281765D01*
X1261172Y1281098D01*
X1261039Y1280498D01*
X1263839D01*
G01X1265772Y1283831D02*
X1266172Y1284231D01*
X1266639Y1284431D01*
X1267172Y1284498D01*
X1267839Y1284365D01*
X1268306Y1284031D01*
X1268439Y1283631D01*
X1268372Y1283231D01*
X1268106Y1282898D01*
X1266772Y1282231D01*
X1266172Y1281765D01*
X1265772Y1281098D01*
X1265639Y1280498D01*
X1268439D01*
G01X1315748Y-7874D02*
G03Y0I0J3937D01*
G01Y-7874D02*
G03Y0I0J3937D01*
G01X1311850Y392016D02*
G03X1291890I-9980J-3040D01*
G01X1311850D02*
G03X1318776Y378885I37662J11473D01*
G01X1311851Y392016D02*
G03X1291890I-9980J-3039D01*
G01X1311851D02*
G03X1318775Y378885I37663J11469D01*
G01X1284965D02*
G03X1291890Y392016I-30737J24602D01*
G01X1284965Y378885D02*
G03X1291890Y392016I-30737J24602D01*
G01X1284965Y831641D02*
G03X1291890Y844772I-30737J24602D01*
G01X1311850D02*
G03X1318776Y831641I37662J11473D01*
G01X1284965D02*
G03X1291890Y844772I-30737J24602D01*
G01X1311851D02*
G03X1318775Y831641I37663J11469D01*
G01X1311850Y844772D02*
G03X1291890I-9980J-3040D01*
G01X1311851D02*
G03X1291890I-9980J-3039D01*
G01X1284965Y1284397D02*
G03X1291890Y1297528I-30737J24602D01*
G01X1311850D02*
G03X1291890I-9980J-3040D01*
G01X1311850D02*
G03X1318776Y1284397I37661J11473D01*
G01X1284965D02*
G03X1291890Y1297528I-30737J24602D01*
G01X1311851D02*
G03X1291890I-9980J-3040D01*
G01X1311851D02*
G03X1318775Y1284397I37663J11469D01*
G01X1377953Y3937D02*
Y51181D01*
G01Y3937D02*
Y51181D01*
G01X1370079Y3937D02*
Y55118D01*
G01X1366142Y0D02*
G03X1370079Y3937I0J3937D01*
G01X1366142Y-7874D02*
G03X1377953Y3937I0J11811D01*
G01X1346457Y-7874D02*
X1366142D01*
G01Y0D02*
G03X1370079Y3937I0J3937D01*
G01D02*
Y55118D01*
G01X1346457Y-7874D02*
X1366142D01*
G01D02*
G03X1377953Y3937I0J11811D01*
G01X1346457Y0D02*
G03Y-7874I0J-3937D01*
G01Y0D02*
G03Y-7874I0J-3937D01*
G01X1361241Y43276D02*
Y39276D01*
X1362841D01*
X1363374Y39476D01*
X1363774Y39943D01*
X1363907Y40476D01*
X1363774Y41009D01*
X1363441Y41409D01*
X1362841Y41609D01*
X1361241D01*
G01X1366241Y43276D02*
Y40609D01*
G01Y41143D02*
X1366574Y40876D01*
X1366907Y40676D01*
X1367374Y40609D01*
X1367707Y40676D01*
X1368107Y40876D01*
G01X1370774Y41476D02*
X1372907D01*
X1372707Y41009D01*
X1372374Y40743D01*
X1371907Y40609D01*
X1371441Y40676D01*
X1371041Y40876D01*
X1370774Y41343D01*
X1370641Y41743D01*
Y42143D01*
X1370774Y42543D01*
X1371107Y42943D01*
X1371507Y43209D01*
X1371974Y43276D01*
X1372441Y43143D01*
X1372907Y42743D01*
G01X1375374Y42809D02*
X1375707Y43076D01*
X1376174Y43276D01*
X1376574D01*
X1376974Y43143D01*
X1377241Y42943D01*
X1377374Y42676D01*
X1377307Y42276D01*
X1377041Y42076D01*
X1375841Y41676D01*
X1375574Y41209D01*
X1375707Y40876D01*
X1375974Y40676D01*
X1376374Y40609D01*
X1376774Y40676D01*
X1377174Y40876D01*
G01X1379974Y42809D02*
X1380307Y43076D01*
X1380774Y43276D01*
X1381174D01*
X1381574Y43143D01*
X1381841Y42943D01*
X1381974Y42676D01*
X1381907Y42276D01*
X1381641Y42076D01*
X1380441Y41676D01*
X1380174Y41209D01*
X1380307Y40876D01*
X1380574Y40676D01*
X1380974Y40609D01*
X1381374Y40676D01*
X1381774Y40876D01*
G01X1384707Y41943D02*
X1386441D01*
G01X1389774Y43276D02*
Y39876D01*
X1389907Y39543D01*
X1390174Y39343D01*
X1390574Y39276D01*
X1390974Y39409D01*
X1391174Y39743D01*
G01X1390374Y40876D02*
X1389041D01*
G01X1394774Y40609D02*
Y43276D01*
G01Y39543D02*
X1394641Y39476D01*
Y39343D01*
X1394774Y39276D01*
X1394907Y39343D01*
Y39476D01*
X1394774Y39543D01*
G01X1399374Y39276D02*
Y43276D01*
G01X1398441Y40609D02*
X1400307D01*
G01X1407241Y43276D02*
Y39276D01*
X1408841D01*
X1409374Y39476D01*
X1409774Y39943D01*
X1409907Y40476D01*
X1409774Y41009D01*
X1409441Y41409D01*
X1408841Y41609D01*
X1407241D01*
G01X1413174Y39276D02*
Y43276D01*
G01X1411641Y39276D02*
X1414707D01*
G01X1416374Y43276D02*
Y39276D01*
G01X1419174D02*
Y43276D01*
G01Y41276D02*
X1416374D01*
G01X1425841Y43276D02*
Y39276D01*
G01X1427974Y40609D02*
X1425841Y42143D01*
G01X1426707Y41543D02*
X1428107Y43276D01*
G01X1430574Y41476D02*
X1432707D01*
X1432507Y41009D01*
X1432174Y40743D01*
X1431707Y40609D01*
X1431241Y40676D01*
X1430841Y40876D01*
X1430574Y41343D01*
X1430441Y41743D01*
Y42143D01*
X1430574Y42543D01*
X1430907Y42943D01*
X1431307Y43209D01*
X1431774Y43276D01*
X1432241Y43143D01*
X1432707Y42743D01*
G01X1435174Y41476D02*
X1437307D01*
X1437107Y41009D01*
X1436774Y40743D01*
X1436307Y40609D01*
X1435841Y40676D01*
X1435441Y40876D01*
X1435174Y41343D01*
X1435041Y41743D01*
Y42143D01*
X1435174Y42543D01*
X1435507Y42943D01*
X1435907Y43209D01*
X1436374Y43276D01*
X1436841Y43143D01*
X1437307Y42743D01*
G01X1439574Y44609D02*
Y40609D01*
G01Y41209D02*
X1439907Y40876D01*
X1440241Y40676D01*
X1440774Y40609D01*
X1441241Y40676D01*
X1441707Y41009D01*
X1441907Y41476D01*
X1441974Y41943D01*
X1441907Y42409D01*
X1441707Y42876D01*
X1441307Y43143D01*
X1440774Y43276D01*
X1440307Y43209D01*
X1439841Y43009D01*
X1439574Y42743D01*
G01X1448841Y43276D02*
Y39276D01*
G01Y41209D02*
X1449174Y40876D01*
X1449507Y40676D01*
X1450041Y40609D01*
X1450441Y40676D01*
X1450907Y40943D01*
X1451107Y41343D01*
Y43276D01*
G01X1454574D02*
X1454174Y43209D01*
X1453774Y42943D01*
X1453507Y42476D01*
X1453374Y41943D01*
X1453507Y41409D01*
X1453774Y40943D01*
X1454174Y40676D01*
X1454574Y40609D01*
X1454974Y40676D01*
X1455374Y40943D01*
X1455641Y41409D01*
X1455707Y41943D01*
X1455641Y42476D01*
X1455374Y42943D01*
X1454974Y43209D01*
X1454574Y43276D01*
G01X1459174D02*
Y39276D01*
G01X1462774Y41476D02*
X1464907D01*
X1464707Y41009D01*
X1464374Y40743D01*
X1463907Y40609D01*
X1463441Y40676D01*
X1463041Y40876D01*
X1462774Y41343D01*
X1462641Y41743D01*
Y42143D01*
X1462774Y42543D01*
X1463107Y42943D01*
X1463507Y43209D01*
X1463974Y43276D01*
X1464441Y43143D01*
X1464907Y42743D01*
G01X1471974Y42809D02*
X1472307Y43076D01*
X1472774Y43276D01*
X1473174D01*
X1473574Y43143D01*
X1473841Y42943D01*
X1473974Y42676D01*
X1473907Y42276D01*
X1473641Y42076D01*
X1472441Y41676D01*
X1472174Y41209D01*
X1472307Y40876D01*
X1472574Y40676D01*
X1472974Y40609D01*
X1473374Y40676D01*
X1473774Y40876D01*
G01X1477574Y40609D02*
Y43276D01*
G01Y39543D02*
X1477441Y39476D01*
Y39343D01*
X1477574Y39276D01*
X1477707Y39343D01*
Y39476D01*
X1477574Y39543D01*
G01X1481174Y40609D02*
X1483174D01*
X1481174Y43276D01*
X1483174D01*
G01X1485774Y41476D02*
X1487907D01*
X1487707Y41009D01*
X1487374Y40743D01*
X1486907Y40609D01*
X1486441Y40676D01*
X1486041Y40876D01*
X1485774Y41343D01*
X1485641Y41743D01*
Y42143D01*
X1485774Y42543D01*
X1486107Y42943D01*
X1486507Y43209D01*
X1486974Y43276D01*
X1487441Y43143D01*
X1487907Y42743D01*
G01X1495974Y39276D02*
Y43276D01*
G01X1495041Y40609D02*
X1496907D01*
G01X1500574Y43276D02*
X1500174Y43209D01*
X1499774Y42943D01*
X1499507Y42476D01*
X1499374Y41943D01*
X1499507Y41409D01*
X1499774Y40943D01*
X1500174Y40676D01*
X1500574Y40609D01*
X1500974Y40676D01*
X1501374Y40943D01*
X1501641Y41409D01*
X1501707Y41943D01*
X1501641Y42476D01*
X1501374Y42943D01*
X1500974Y43209D01*
X1500574Y43276D01*
G01X1505174D02*
Y39276D01*
G01X1508774Y41476D02*
X1510907D01*
X1510707Y41009D01*
X1510374Y40743D01*
X1509907Y40609D01*
X1509441Y40676D01*
X1509041Y40876D01*
X1508774Y41343D01*
X1508641Y41743D01*
Y42143D01*
X1508774Y42543D01*
X1509107Y42943D01*
X1509507Y43209D01*
X1509974Y43276D01*
X1510441Y43143D01*
X1510907Y42743D01*
G01X1513441Y43276D02*
Y40609D01*
G01Y41143D02*
X1513774Y40876D01*
X1514107Y40676D01*
X1514574Y40609D01*
X1514907Y40676D01*
X1515307Y40876D01*
G01X1520174Y43276D02*
Y40609D01*
G01Y41076D02*
X1519907Y40809D01*
X1519507Y40676D01*
X1519041Y40609D01*
X1518574Y40743D01*
X1518174Y41009D01*
X1517907Y41409D01*
X1517774Y41943D01*
X1517907Y42476D01*
X1518174Y42876D01*
X1518574Y43143D01*
X1519041Y43276D01*
X1519507Y43209D01*
X1519907Y43009D01*
X1520174Y42743D01*
G01X1522441Y43276D02*
Y40609D01*
G01Y41276D02*
X1522707Y40943D01*
X1523107Y40676D01*
X1523641Y40609D01*
X1524107Y40676D01*
X1524507Y40943D01*
X1524707Y41409D01*
Y43276D01*
G01X1529241Y40943D02*
X1528774Y40676D01*
X1528374Y40609D01*
X1527841Y40743D01*
X1527441Y41009D01*
X1527174Y41476D01*
X1527107Y41943D01*
X1527174Y42409D01*
X1527441Y42809D01*
X1527841Y43143D01*
X1528374Y43276D01*
X1528841Y43143D01*
X1529241Y42876D01*
G01X1531774Y41476D02*
X1533907D01*
X1533707Y41009D01*
X1533374Y40743D01*
X1532907Y40609D01*
X1532441Y40676D01*
X1532041Y40876D01*
X1531774Y41343D01*
X1531641Y41743D01*
Y42143D01*
X1531774Y42543D01*
X1532107Y42943D01*
X1532507Y43209D01*
X1532974Y43276D01*
X1533441Y43143D01*
X1533907Y42743D01*
G01X1541241Y41943D02*
X1542841D01*
G01X1541974Y41076D02*
Y42809D01*
G01X1545374Y43409D02*
X1547774Y39276D01*
G01X1550307Y41943D02*
X1552041D01*
G01X1554507Y39943D02*
X1554907Y39543D01*
X1555374Y39343D01*
X1555907Y39276D01*
X1556574Y39409D01*
X1557041Y39743D01*
X1557174Y40143D01*
X1557107Y40543D01*
X1556841Y40876D01*
X1555507Y41543D01*
X1554907Y42009D01*
X1554507Y42676D01*
X1554374Y43276D01*
X1557174D01*
G01X1558374D02*
Y40609D01*
G01Y41343D02*
X1558574Y41009D01*
X1558907Y40743D01*
X1559374Y40609D01*
X1559841Y40743D01*
X1560174Y41009D01*
X1560374Y41343D01*
Y43276D01*
G01Y41343D02*
X1560574Y41009D01*
X1560907Y40743D01*
X1561374Y40609D01*
X1561841Y40743D01*
X1562174Y41009D01*
X1562374Y41409D01*
Y43276D01*
G01X1564974Y40609D02*
Y43276D01*
G01Y39543D02*
X1564841Y39476D01*
Y39343D01*
X1564974Y39276D01*
X1565107Y39343D01*
Y39476D01*
X1564974Y39543D01*
G01X1569574Y43276D02*
Y39276D01*
G01X1573174Y42809D02*
X1573507Y43076D01*
X1573974Y43276D01*
X1574374D01*
X1574774Y43143D01*
X1575041Y42943D01*
X1575174Y42676D01*
X1575107Y42276D01*
X1574841Y42076D01*
X1573641Y41676D01*
X1573374Y41209D01*
X1573507Y40876D01*
X1573774Y40676D01*
X1574174Y40609D01*
X1574574Y40676D01*
X1574974Y40876D01*
G01X1366874Y59056D02*
X1562874D01*
G01X1374016Y59055D02*
G03X1370079Y55118I0J-3937D01*
G01X1374016Y59056D02*
G03X1370079Y55118I0J-3937D01*
G01X1374016Y59055D02*
X1555118D01*
G01X1377953Y51181D02*
X1551181D01*
G01X1374016Y59055D02*
X1555118D01*
G01X1377953Y51181D02*
X1551181D01*
G01X1343467Y334725D02*
Y338725D01*
X1341000Y335858D01*
X1344334D01*
G01X1345800Y335525D02*
X1346200Y335058D01*
X1346734Y334792D01*
X1347334Y334725D01*
X1347867Y334792D01*
X1348400Y335125D01*
X1348734Y335525D01*
X1348800Y335925D01*
X1348667Y336392D01*
X1348200Y336725D01*
X1347734Y336858D01*
X1347134D01*
G01X1347734D02*
X1348134Y337058D01*
X1348467Y337392D01*
X1348600Y337792D01*
X1348467Y338192D01*
X1348134Y338525D01*
X1347534Y338725D01*
X1346934Y338658D01*
X1346334Y338392D01*
G01X1350400Y335525D02*
X1350800Y335058D01*
X1351334Y334792D01*
X1351934Y334725D01*
X1352467Y334792D01*
X1353000Y335125D01*
X1353334Y335525D01*
X1353400Y335925D01*
X1353267Y336392D01*
X1352800Y336725D01*
X1352334Y336858D01*
X1351734D01*
G01X1352334D02*
X1352734Y337058D01*
X1353067Y337392D01*
X1353200Y337792D01*
X1353067Y338192D01*
X1352734Y338525D01*
X1352134Y338725D01*
X1351534Y338658D01*
X1350934Y338392D01*
G01X1356467Y334592D02*
X1356334Y334658D01*
Y334792D01*
X1356467Y334858D01*
X1356600Y334792D01*
Y334658D01*
X1356467Y334592D01*
G01X1361067Y338725D02*
X1360534Y338592D01*
X1360134Y338258D01*
X1359867Y337858D01*
X1359667Y337325D01*
X1359600Y336725D01*
X1359667Y336125D01*
X1359867Y335592D01*
X1360134Y335192D01*
X1360534Y334858D01*
X1361067Y334725D01*
X1361600Y334858D01*
X1362000Y335192D01*
X1362267Y335592D01*
X1362467Y336125D01*
X1362534Y336725D01*
X1362467Y337325D01*
X1362267Y337858D01*
X1362000Y338258D01*
X1361600Y338592D01*
X1361067Y338725D01*
G01X1365667Y334725D02*
X1366134Y334792D01*
X1366667Y334992D01*
X1367000Y335325D01*
X1367134Y335792D01*
X1367000Y336258D01*
X1366600Y336658D01*
X1366000Y336858D01*
X1365334D01*
X1364934Y336992D01*
X1364600Y337325D01*
X1364467Y337792D01*
X1364667Y338258D01*
X1365134Y338592D01*
X1365667Y338725D01*
X1366200Y338592D01*
X1366667Y338258D01*
X1366867Y337792D01*
X1366734Y337325D01*
X1366400Y336992D01*
X1366000Y336858D01*
X1365334D01*
X1364734Y336658D01*
X1364334Y336258D01*
X1364200Y335792D01*
X1364334Y335325D01*
X1364667Y334992D01*
X1365200Y334792D01*
X1365667Y334725D01*
G01X1337004Y376882D02*
Y380882D01*
X1338338D01*
X1338871Y380682D01*
X1339271Y380415D01*
X1339604Y380015D01*
X1339871Y379549D01*
X1339938Y378882D01*
X1339871Y378215D01*
X1339604Y377749D01*
X1339271Y377349D01*
X1338871Y377082D01*
X1338338Y376882D01*
X1337004D01*
G01X1342138D02*
Y379549D01*
G01Y379015D02*
X1342471Y379282D01*
X1342804Y379482D01*
X1343271Y379549D01*
X1343604Y379482D01*
X1344004Y379282D01*
G01X1347671Y379549D02*
Y376882D01*
G01Y380615D02*
X1347538Y380682D01*
Y380815D01*
X1347671Y380882D01*
X1347804Y380815D01*
Y380682D01*
X1347671Y380615D01*
G01X1352271Y376882D02*
Y380882D01*
G01X1356871Y376882D02*
Y380882D01*
G01X1365671Y376882D02*
Y380282D01*
X1365804Y380615D01*
X1366071Y380815D01*
X1366471Y380882D01*
X1366871Y380749D01*
X1367071Y380415D01*
G01X1366271Y379282D02*
X1364938D01*
G01X1369671Y378682D02*
X1371804D01*
X1371604Y379149D01*
X1371271Y379415D01*
X1370804Y379549D01*
X1370338Y379482D01*
X1369938Y379282D01*
X1369671Y378815D01*
X1369538Y378415D01*
Y378015D01*
X1369671Y377615D01*
X1370004Y377215D01*
X1370404Y376949D01*
X1370871Y376882D01*
X1371338Y377015D01*
X1371804Y377415D01*
G01X1376471Y376882D02*
Y379549D01*
G01Y379082D02*
X1376204Y379349D01*
X1375804Y379482D01*
X1375338Y379549D01*
X1374871Y379415D01*
X1374471Y379149D01*
X1374204Y378749D01*
X1374071Y378215D01*
X1374204Y377682D01*
X1374471Y377282D01*
X1374871Y377015D01*
X1375338Y376882D01*
X1375804Y376949D01*
X1376204Y377149D01*
X1376471Y377415D01*
G01X1379871Y380882D02*
Y376882D01*
G01X1378938Y379549D02*
X1380804D01*
G01X1383338D02*
Y377682D01*
X1383604Y377215D01*
X1384004Y376949D01*
X1384471Y376882D01*
X1384938Y376949D01*
X1385338Y377215D01*
X1385604Y377682D01*
G01Y376882D02*
Y379549D01*
G01X1388138Y376882D02*
Y379549D01*
G01Y379015D02*
X1388471Y379282D01*
X1388804Y379482D01*
X1389271Y379549D01*
X1389604Y379482D01*
X1390004Y379282D01*
G01X1392671Y378682D02*
X1394804D01*
X1394604Y379149D01*
X1394271Y379415D01*
X1393804Y379549D01*
X1393338Y379482D01*
X1392938Y379282D01*
X1392671Y378815D01*
X1392538Y378415D01*
Y378015D01*
X1392671Y377615D01*
X1393004Y377215D01*
X1393404Y376949D01*
X1393871Y376882D01*
X1394338Y377015D01*
X1394804Y377415D01*
G01X1343559Y419049D02*
X1343959Y419449D01*
X1344426Y419649D01*
X1344959Y419716D01*
X1345626Y419583D01*
X1346093Y419249D01*
X1346226Y418849D01*
X1346159Y418449D01*
X1345893Y418116D01*
X1344559Y417449D01*
X1343959Y416983D01*
X1343559Y416316D01*
X1343426Y415716D01*
X1346226D01*
G01X1349426Y419716D02*
X1348893Y419583D01*
X1348493Y419249D01*
X1348226Y418849D01*
X1348026Y418316D01*
X1347959Y417716D01*
X1348026Y417116D01*
X1348226Y416583D01*
X1348493Y416183D01*
X1348893Y415849D01*
X1349426Y415716D01*
X1349959Y415849D01*
X1350359Y416183D01*
X1350626Y416583D01*
X1350826Y417116D01*
X1350893Y417716D01*
X1350826Y418316D01*
X1350626Y418849D01*
X1350359Y419249D01*
X1349959Y419583D01*
X1349426Y419716D01*
G01X1354026Y415716D02*
X1354493Y415783D01*
X1355026Y415983D01*
X1355359Y416316D01*
X1355493Y416783D01*
X1355359Y417249D01*
X1354959Y417649D01*
X1354359Y417849D01*
X1353693D01*
X1353293Y417983D01*
X1352959Y418316D01*
X1352826Y418783D01*
X1353026Y419249D01*
X1353493Y419583D01*
X1354026Y419716D01*
X1354559Y419583D01*
X1355026Y419249D01*
X1355226Y418783D01*
X1355093Y418316D01*
X1354759Y417983D01*
X1354359Y417849D01*
X1353693D01*
X1353093Y417649D01*
X1352693Y417249D01*
X1352559Y416783D01*
X1352693Y416316D01*
X1353026Y415983D01*
X1353559Y415783D01*
X1354026Y415716D01*
G01X1358626Y415583D02*
X1358493Y415649D01*
Y415783D01*
X1358626Y415849D01*
X1358759Y415783D01*
Y415649D01*
X1358626Y415583D01*
G01X1361959Y417383D02*
X1362426Y417849D01*
X1362826Y418116D01*
X1363359Y418249D01*
X1363826Y418116D01*
X1364159Y417849D01*
X1364426Y417449D01*
X1364493Y416983D01*
X1364426Y416583D01*
X1364159Y416183D01*
X1363759Y415849D01*
X1363293Y415716D01*
X1362759Y415849D01*
X1362293Y416249D01*
X1362026Y416849D01*
X1361959Y417516D01*
X1362093Y418383D01*
X1362293Y418849D01*
X1362626Y419316D01*
X1363093Y419649D01*
X1363559Y419716D01*
X1364026Y419583D01*
X1364359Y419249D01*
G01X1366559Y417383D02*
X1367026Y417849D01*
X1367426Y418116D01*
X1367959Y418249D01*
X1368426Y418116D01*
X1368759Y417849D01*
X1369026Y417449D01*
X1369093Y416983D01*
X1369026Y416583D01*
X1368759Y416183D01*
X1368359Y415849D01*
X1367893Y415716D01*
X1367359Y415849D01*
X1366893Y416249D01*
X1366626Y416849D01*
X1366559Y417516D01*
X1366693Y418383D01*
X1366893Y418849D01*
X1367226Y419316D01*
X1367693Y419649D01*
X1368159Y419716D01*
X1368626Y419583D01*
X1368959Y419249D01*
G01X1343467Y787481D02*
Y791481D01*
X1341000Y788614D01*
X1344334D01*
G01X1345800Y788281D02*
X1346200Y787814D01*
X1346734Y787548D01*
X1347334Y787481D01*
X1347867Y787548D01*
X1348400Y787881D01*
X1348734Y788281D01*
X1348800Y788681D01*
X1348667Y789148D01*
X1348200Y789481D01*
X1347734Y789614D01*
X1347134D01*
G01X1347734D02*
X1348134Y789814D01*
X1348467Y790148D01*
X1348600Y790548D01*
X1348467Y790948D01*
X1348134Y791281D01*
X1347534Y791481D01*
X1346934Y791414D01*
X1346334Y791148D01*
G01X1350400Y788281D02*
X1350800Y787814D01*
X1351334Y787548D01*
X1351934Y787481D01*
X1352467Y787548D01*
X1353000Y787881D01*
X1353334Y788281D01*
X1353400Y788681D01*
X1353267Y789148D01*
X1352800Y789481D01*
X1352334Y789614D01*
X1351734D01*
G01X1352334D02*
X1352734Y789814D01*
X1353067Y790148D01*
X1353200Y790548D01*
X1353067Y790948D01*
X1352734Y791281D01*
X1352134Y791481D01*
X1351534Y791414D01*
X1350934Y791148D01*
G01X1356467Y787348D02*
X1356334Y787414D01*
Y787548D01*
X1356467Y787614D01*
X1356600Y787548D01*
Y787414D01*
X1356467Y787348D01*
G01X1361067Y791481D02*
X1360534Y791348D01*
X1360134Y791014D01*
X1359867Y790614D01*
X1359667Y790081D01*
X1359600Y789481D01*
X1359667Y788881D01*
X1359867Y788348D01*
X1360134Y787948D01*
X1360534Y787614D01*
X1361067Y787481D01*
X1361600Y787614D01*
X1362000Y787948D01*
X1362267Y788348D01*
X1362467Y788881D01*
X1362534Y789481D01*
X1362467Y790081D01*
X1362267Y790614D01*
X1362000Y791014D01*
X1361600Y791348D01*
X1361067Y791481D01*
G01X1365667Y787481D02*
X1366134Y787548D01*
X1366667Y787748D01*
X1367000Y788081D01*
X1367134Y788548D01*
X1367000Y789014D01*
X1366600Y789414D01*
X1366000Y789614D01*
X1365334D01*
X1364934Y789748D01*
X1364600Y790081D01*
X1364467Y790548D01*
X1364667Y791014D01*
X1365134Y791348D01*
X1365667Y791481D01*
X1366200Y791348D01*
X1366667Y791014D01*
X1366867Y790548D01*
X1366734Y790081D01*
X1366400Y789748D01*
X1366000Y789614D01*
X1365334D01*
X1364734Y789414D01*
X1364334Y789014D01*
X1364200Y788548D01*
X1364334Y788081D01*
X1364667Y787748D01*
X1365200Y787548D01*
X1365667Y787481D01*
G01X1337004Y829638D02*
Y833638D01*
X1338338D01*
X1338871Y833438D01*
X1339271Y833171D01*
X1339604Y832771D01*
X1339871Y832305D01*
X1339938Y831638D01*
X1339871Y830971D01*
X1339604Y830505D01*
X1339271Y830105D01*
X1338871Y829838D01*
X1338338Y829638D01*
X1337004D01*
G01X1342138D02*
Y832305D01*
G01Y831771D02*
X1342471Y832038D01*
X1342804Y832238D01*
X1343271Y832305D01*
X1343604Y832238D01*
X1344004Y832038D01*
G01X1347671Y832305D02*
Y829638D01*
G01Y833371D02*
X1347538Y833438D01*
Y833571D01*
X1347671Y833638D01*
X1347804Y833571D01*
Y833438D01*
X1347671Y833371D01*
G01X1352271Y829638D02*
Y833638D01*
G01X1356871Y829638D02*
Y833638D01*
G01X1365671Y829638D02*
Y833038D01*
X1365804Y833371D01*
X1366071Y833571D01*
X1366471Y833638D01*
X1366871Y833505D01*
X1367071Y833171D01*
G01X1366271Y832038D02*
X1364938D01*
G01X1369671Y831438D02*
X1371804D01*
X1371604Y831905D01*
X1371271Y832171D01*
X1370804Y832305D01*
X1370338Y832238D01*
X1369938Y832038D01*
X1369671Y831571D01*
X1369538Y831171D01*
Y830771D01*
X1369671Y830371D01*
X1370004Y829971D01*
X1370404Y829705D01*
X1370871Y829638D01*
X1371338Y829771D01*
X1371804Y830171D01*
G01X1376471Y829638D02*
Y832305D01*
G01Y831838D02*
X1376204Y832105D01*
X1375804Y832238D01*
X1375338Y832305D01*
X1374871Y832171D01*
X1374471Y831905D01*
X1374204Y831505D01*
X1374071Y830971D01*
X1374204Y830438D01*
X1374471Y830038D01*
X1374871Y829771D01*
X1375338Y829638D01*
X1375804Y829705D01*
X1376204Y829905D01*
X1376471Y830171D01*
G01X1379871Y833638D02*
Y829638D01*
G01X1378938Y832305D02*
X1380804D01*
G01X1383338D02*
Y830438D01*
X1383604Y829971D01*
X1384004Y829705D01*
X1384471Y829638D01*
X1384938Y829705D01*
X1385338Y829971D01*
X1385604Y830438D01*
G01Y829638D02*
Y832305D01*
G01X1388138Y829638D02*
Y832305D01*
G01Y831771D02*
X1388471Y832038D01*
X1388804Y832238D01*
X1389271Y832305D01*
X1389604Y832238D01*
X1390004Y832038D01*
G01X1392671Y831438D02*
X1394804D01*
X1394604Y831905D01*
X1394271Y832171D01*
X1393804Y832305D01*
X1393338Y832238D01*
X1392938Y832038D01*
X1392671Y831571D01*
X1392538Y831171D01*
Y830771D01*
X1392671Y830371D01*
X1393004Y829971D01*
X1393404Y829705D01*
X1393871Y829638D01*
X1394338Y829771D01*
X1394804Y830171D01*
G01X1343559Y871805D02*
X1343959Y872205D01*
X1344426Y872405D01*
X1344959Y872472D01*
X1345626Y872339D01*
X1346093Y872005D01*
X1346226Y871605D01*
X1346159Y871205D01*
X1345893Y870872D01*
X1344559Y870205D01*
X1343959Y869739D01*
X1343559Y869072D01*
X1343426Y868472D01*
X1346226D01*
G01X1349426Y872472D02*
X1348893Y872339D01*
X1348493Y872005D01*
X1348226Y871605D01*
X1348026Y871072D01*
X1347959Y870472D01*
X1348026Y869872D01*
X1348226Y869339D01*
X1348493Y868939D01*
X1348893Y868605D01*
X1349426Y868472D01*
X1349959Y868605D01*
X1350359Y868939D01*
X1350626Y869339D01*
X1350826Y869872D01*
X1350893Y870472D01*
X1350826Y871072D01*
X1350626Y871605D01*
X1350359Y872005D01*
X1349959Y872339D01*
X1349426Y872472D01*
G01X1354026Y868472D02*
X1354493Y868539D01*
X1355026Y868739D01*
X1355359Y869072D01*
X1355493Y869539D01*
X1355359Y870005D01*
X1354959Y870405D01*
X1354359Y870605D01*
X1353693D01*
X1353293Y870739D01*
X1352959Y871072D01*
X1352826Y871539D01*
X1353026Y872005D01*
X1353493Y872339D01*
X1354026Y872472D01*
X1354559Y872339D01*
X1355026Y872005D01*
X1355226Y871539D01*
X1355093Y871072D01*
X1354759Y870739D01*
X1354359Y870605D01*
X1353693D01*
X1353093Y870405D01*
X1352693Y870005D01*
X1352559Y869539D01*
X1352693Y869072D01*
X1353026Y868739D01*
X1353559Y868539D01*
X1354026Y868472D01*
G01X1358626Y868339D02*
X1358493Y868405D01*
Y868539D01*
X1358626Y868605D01*
X1358759Y868539D01*
Y868405D01*
X1358626Y868339D01*
G01X1361959Y870139D02*
X1362426Y870605D01*
X1362826Y870872D01*
X1363359Y871005D01*
X1363826Y870872D01*
X1364159Y870605D01*
X1364426Y870205D01*
X1364493Y869739D01*
X1364426Y869339D01*
X1364159Y868939D01*
X1363759Y868605D01*
X1363293Y868472D01*
X1362759Y868605D01*
X1362293Y869005D01*
X1362026Y869605D01*
X1361959Y870272D01*
X1362093Y871139D01*
X1362293Y871605D01*
X1362626Y872072D01*
X1363093Y872405D01*
X1363559Y872472D01*
X1364026Y872339D01*
X1364359Y872005D01*
G01X1366559Y870139D02*
X1367026Y870605D01*
X1367426Y870872D01*
X1367959Y871005D01*
X1368426Y870872D01*
X1368759Y870605D01*
X1369026Y870205D01*
X1369093Y869739D01*
X1369026Y869339D01*
X1368759Y868939D01*
X1368359Y868605D01*
X1367893Y868472D01*
X1367359Y868605D01*
X1366893Y869005D01*
X1366626Y869605D01*
X1366559Y870272D01*
X1366693Y871139D01*
X1366893Y871605D01*
X1367226Y872072D01*
X1367693Y872405D01*
X1368159Y872472D01*
X1368626Y872339D01*
X1368959Y872005D01*
G01X1343467Y1240237D02*
Y1244237D01*
X1341000Y1241370D01*
X1344334D01*
G01X1345800Y1241037D02*
X1346200Y1240570D01*
X1346734Y1240304D01*
X1347334Y1240237D01*
X1347867Y1240304D01*
X1348400Y1240637D01*
X1348734Y1241037D01*
X1348800Y1241437D01*
X1348667Y1241904D01*
X1348200Y1242237D01*
X1347734Y1242370D01*
X1347134D01*
G01X1347734D02*
X1348134Y1242570D01*
X1348467Y1242904D01*
X1348600Y1243304D01*
X1348467Y1243704D01*
X1348134Y1244037D01*
X1347534Y1244237D01*
X1346934Y1244170D01*
X1346334Y1243904D01*
G01X1350400Y1241037D02*
X1350800Y1240570D01*
X1351334Y1240304D01*
X1351934Y1240237D01*
X1352467Y1240304D01*
X1353000Y1240637D01*
X1353334Y1241037D01*
X1353400Y1241437D01*
X1353267Y1241904D01*
X1352800Y1242237D01*
X1352334Y1242370D01*
X1351734D01*
G01X1352334D02*
X1352734Y1242570D01*
X1353067Y1242904D01*
X1353200Y1243304D01*
X1353067Y1243704D01*
X1352734Y1244037D01*
X1352134Y1244237D01*
X1351534Y1244170D01*
X1350934Y1243904D01*
G01X1356467Y1240104D02*
X1356334Y1240170D01*
Y1240304D01*
X1356467Y1240370D01*
X1356600Y1240304D01*
Y1240170D01*
X1356467Y1240104D01*
G01X1361067Y1244237D02*
X1360534Y1244104D01*
X1360134Y1243770D01*
X1359867Y1243370D01*
X1359667Y1242837D01*
X1359600Y1242237D01*
X1359667Y1241637D01*
X1359867Y1241104D01*
X1360134Y1240704D01*
X1360534Y1240370D01*
X1361067Y1240237D01*
X1361600Y1240370D01*
X1362000Y1240704D01*
X1362267Y1241104D01*
X1362467Y1241637D01*
X1362534Y1242237D01*
X1362467Y1242837D01*
X1362267Y1243370D01*
X1362000Y1243770D01*
X1361600Y1244104D01*
X1361067Y1244237D01*
G01X1365667Y1240237D02*
X1366134Y1240304D01*
X1366667Y1240504D01*
X1367000Y1240837D01*
X1367134Y1241304D01*
X1367000Y1241770D01*
X1366600Y1242170D01*
X1366000Y1242370D01*
X1365334D01*
X1364934Y1242504D01*
X1364600Y1242837D01*
X1364467Y1243304D01*
X1364667Y1243770D01*
X1365134Y1244104D01*
X1365667Y1244237D01*
X1366200Y1244104D01*
X1366667Y1243770D01*
X1366867Y1243304D01*
X1366734Y1242837D01*
X1366400Y1242504D01*
X1366000Y1242370D01*
X1365334D01*
X1364734Y1242170D01*
X1364334Y1241770D01*
X1364200Y1241304D01*
X1364334Y1240837D01*
X1364667Y1240504D01*
X1365200Y1240304D01*
X1365667Y1240237D01*
G01X1343559Y1324561D02*
X1343959Y1324961D01*
X1344426Y1325161D01*
X1344959Y1325228D01*
X1345626Y1325095D01*
X1346093Y1324761D01*
X1346226Y1324361D01*
X1346159Y1323961D01*
X1345893Y1323628D01*
X1344559Y1322961D01*
X1343959Y1322495D01*
X1343559Y1321828D01*
X1343426Y1321228D01*
X1346226D01*
G01X1349426Y1325228D02*
X1348893Y1325095D01*
X1348493Y1324761D01*
X1348226Y1324361D01*
X1348026Y1323828D01*
X1347959Y1323228D01*
X1348026Y1322628D01*
X1348226Y1322095D01*
X1348493Y1321695D01*
X1348893Y1321361D01*
X1349426Y1321228D01*
X1349959Y1321361D01*
X1350359Y1321695D01*
X1350626Y1322095D01*
X1350826Y1322628D01*
X1350893Y1323228D01*
X1350826Y1323828D01*
X1350626Y1324361D01*
X1350359Y1324761D01*
X1349959Y1325095D01*
X1349426Y1325228D01*
G01X1354026Y1321228D02*
X1354493Y1321295D01*
X1355026Y1321495D01*
X1355359Y1321828D01*
X1355493Y1322295D01*
X1355359Y1322761D01*
X1354959Y1323161D01*
X1354359Y1323361D01*
X1353693D01*
X1353293Y1323495D01*
X1352959Y1323828D01*
X1352826Y1324295D01*
X1353026Y1324761D01*
X1353493Y1325095D01*
X1354026Y1325228D01*
X1354559Y1325095D01*
X1355026Y1324761D01*
X1355226Y1324295D01*
X1355093Y1323828D01*
X1354759Y1323495D01*
X1354359Y1323361D01*
X1353693D01*
X1353093Y1323161D01*
X1352693Y1322761D01*
X1352559Y1322295D01*
X1352693Y1321828D01*
X1353026Y1321495D01*
X1353559Y1321295D01*
X1354026Y1321228D01*
G01X1358626Y1321095D02*
X1358493Y1321161D01*
Y1321295D01*
X1358626Y1321361D01*
X1358759Y1321295D01*
Y1321161D01*
X1358626Y1321095D01*
G01X1361959Y1322895D02*
X1362426Y1323361D01*
X1362826Y1323628D01*
X1363359Y1323761D01*
X1363826Y1323628D01*
X1364159Y1323361D01*
X1364426Y1322961D01*
X1364493Y1322495D01*
X1364426Y1322095D01*
X1364159Y1321695D01*
X1363759Y1321361D01*
X1363293Y1321228D01*
X1362759Y1321361D01*
X1362293Y1321761D01*
X1362026Y1322361D01*
X1361959Y1323028D01*
X1362093Y1323895D01*
X1362293Y1324361D01*
X1362626Y1324828D01*
X1363093Y1325161D01*
X1363559Y1325228D01*
X1364026Y1325095D01*
X1364359Y1324761D01*
G01X1366559Y1322895D02*
X1367026Y1323361D01*
X1367426Y1323628D01*
X1367959Y1323761D01*
X1368426Y1323628D01*
X1368759Y1323361D01*
X1369026Y1322961D01*
X1369093Y1322495D01*
X1369026Y1322095D01*
X1368759Y1321695D01*
X1368359Y1321361D01*
X1367893Y1321228D01*
X1367359Y1321361D01*
X1366893Y1321761D01*
X1366626Y1322361D01*
X1366559Y1323028D01*
X1366693Y1323895D01*
X1366893Y1324361D01*
X1367226Y1324828D01*
X1367693Y1325161D01*
X1368159Y1325228D01*
X1368626Y1325095D01*
X1368959Y1324761D01*
G01X1337004Y1282394D02*
Y1286394D01*
X1338338D01*
X1338871Y1286194D01*
X1339271Y1285927D01*
X1339604Y1285527D01*
X1339871Y1285061D01*
X1339938Y1284394D01*
X1339871Y1283727D01*
X1339604Y1283261D01*
X1339271Y1282861D01*
X1338871Y1282594D01*
X1338338Y1282394D01*
X1337004D01*
G01X1342138D02*
Y1285061D01*
G01Y1284527D02*
X1342471Y1284794D01*
X1342804Y1284994D01*
X1343271Y1285061D01*
X1343604Y1284994D01*
X1344004Y1284794D01*
G01X1347671Y1285061D02*
Y1282394D01*
G01Y1286127D02*
X1347538Y1286194D01*
Y1286327D01*
X1347671Y1286394D01*
X1347804Y1286327D01*
Y1286194D01*
X1347671Y1286127D01*
G01X1352271Y1282394D02*
Y1286394D01*
G01X1356871Y1282394D02*
Y1286394D01*
G01X1365671Y1282394D02*
Y1285794D01*
X1365804Y1286127D01*
X1366071Y1286327D01*
X1366471Y1286394D01*
X1366871Y1286261D01*
X1367071Y1285927D01*
G01X1366271Y1284794D02*
X1364938D01*
G01X1369671Y1284194D02*
X1371804D01*
X1371604Y1284661D01*
X1371271Y1284927D01*
X1370804Y1285061D01*
X1370338Y1284994D01*
X1369938Y1284794D01*
X1369671Y1284327D01*
X1369538Y1283927D01*
Y1283527D01*
X1369671Y1283127D01*
X1370004Y1282727D01*
X1370404Y1282461D01*
X1370871Y1282394D01*
X1371338Y1282527D01*
X1371804Y1282927D01*
G01X1376471Y1282394D02*
Y1285061D01*
G01Y1284594D02*
X1376204Y1284861D01*
X1375804Y1284994D01*
X1375338Y1285061D01*
X1374871Y1284927D01*
X1374471Y1284661D01*
X1374204Y1284261D01*
X1374071Y1283727D01*
X1374204Y1283194D01*
X1374471Y1282794D01*
X1374871Y1282527D01*
X1375338Y1282394D01*
X1375804Y1282461D01*
X1376204Y1282661D01*
X1376471Y1282927D01*
G01X1379871Y1286394D02*
Y1282394D01*
G01X1378938Y1285061D02*
X1380804D01*
G01X1383338D02*
Y1283194D01*
X1383604Y1282727D01*
X1384004Y1282461D01*
X1384471Y1282394D01*
X1384938Y1282461D01*
X1385338Y1282727D01*
X1385604Y1283194D01*
G01Y1282394D02*
Y1285061D01*
G01X1388138Y1282394D02*
Y1285061D01*
G01Y1284527D02*
X1388471Y1284794D01*
X1388804Y1284994D01*
X1389271Y1285061D01*
X1389604Y1284994D01*
X1390004Y1284794D01*
G01X1392671Y1284194D02*
X1394804D01*
X1394604Y1284661D01*
X1394271Y1284927D01*
X1393804Y1285061D01*
X1393338Y1284994D01*
X1392938Y1284794D01*
X1392671Y1284327D01*
X1392538Y1283927D01*
Y1283527D01*
X1392671Y1283127D01*
X1393004Y1282727D01*
X1393404Y1282461D01*
X1393871Y1282394D01*
X1394338Y1282527D01*
X1394804Y1282927D01*
G01X1395928Y61677D02*
Y122970D01*
X1535174D01*
Y61677D01*
X1395928D01*
G01X1457769Y50394D02*
X1458302Y50727D01*
X1458902Y50927D01*
X1459436D01*
X1459969Y50727D01*
X1460369Y50394D01*
X1460569Y49927D01*
X1460436Y49460D01*
X1460102Y49060D01*
X1459502Y48794D01*
X1458702Y48660D01*
X1458236Y48394D01*
X1458036Y47927D01*
X1458169Y47460D01*
X1458502Y47127D01*
X1458969Y46927D01*
X1459436D01*
X1459902Y47060D01*
X1460302Y47394D01*
G01X1463769Y50927D02*
Y46927D01*
G01X1468369Y48260D02*
Y50927D01*
G01Y47194D02*
X1468236Y47127D01*
Y46994D01*
X1468369Y46927D01*
X1468502Y46994D01*
Y47127D01*
X1468369Y47194D01*
G01X1472969Y46927D02*
Y50927D01*
G01X1472036Y48260D02*
X1473902D01*
G01X1466255Y58567D02*
X1468255Y56567D01*
X1464255D01*
X1466255Y58567D01*
Y52567D01*
G01X1473464Y367773D02*
X1473864Y367440D01*
X1474331Y367240D01*
X1474931Y367173D01*
X1475531Y367306D01*
X1475998Y367573D01*
X1476331Y368040D01*
X1476398Y368573D01*
X1476264Y369106D01*
X1475931Y369440D01*
X1475464Y369706D01*
X1474998Y369773D01*
X1474531Y369706D01*
X1473931Y369440D01*
X1474131Y371173D01*
X1475931D01*
G01X1478064Y367773D02*
X1478464Y367440D01*
X1478931Y367240D01*
X1479531Y367173D01*
X1480131Y367306D01*
X1480598Y367573D01*
X1480931Y368040D01*
X1480998Y368573D01*
X1480864Y369106D01*
X1480531Y369440D01*
X1480064Y369706D01*
X1479598Y369773D01*
X1479131Y369706D01*
X1478531Y369440D01*
X1478731Y371173D01*
X1480531D01*
G01X1483998Y367173D02*
X1484131Y368040D01*
X1484331Y368773D01*
X1484598Y369440D01*
X1484931Y370173D01*
X1485464Y371173D01*
X1482798D01*
G01X1488731Y367040D02*
X1488598Y367106D01*
Y367240D01*
X1488731Y367306D01*
X1488864Y367240D01*
Y367106D01*
X1488731Y367040D01*
G01X1493331Y371173D02*
X1492798Y371040D01*
X1492398Y370706D01*
X1492131Y370306D01*
X1491931Y369773D01*
X1491864Y369173D01*
X1491931Y368573D01*
X1492131Y368040D01*
X1492398Y367640D01*
X1492798Y367306D01*
X1493331Y367173D01*
X1493864Y367306D01*
X1494264Y367640D01*
X1494531Y368040D01*
X1494731Y368573D01*
X1494798Y369173D01*
X1494731Y369773D01*
X1494531Y370306D01*
X1494264Y370706D01*
X1493864Y371040D01*
X1493331Y371173D01*
G01X1496798Y367640D02*
X1497264Y367306D01*
X1497798Y367173D01*
X1498331Y367306D01*
X1498798Y367706D01*
X1499131Y368306D01*
X1499264Y368906D01*
Y369640D01*
X1499131Y370240D01*
X1498798Y370773D01*
X1498398Y371040D01*
X1497931Y371173D01*
X1497398Y371040D01*
X1496998Y370773D01*
X1496731Y370373D01*
X1496598Y369840D01*
X1496731Y369373D01*
X1497064Y368906D01*
X1497464Y368640D01*
X1497931Y368573D01*
X1498464Y368706D01*
X1498864Y369040D01*
X1499264Y369640D01*
G01X1473464Y820529D02*
X1473864Y820196D01*
X1474331Y819996D01*
X1474931Y819929D01*
X1475531Y820062D01*
X1475998Y820329D01*
X1476331Y820796D01*
X1476398Y821329D01*
X1476264Y821862D01*
X1475931Y822196D01*
X1475464Y822462D01*
X1474998Y822529D01*
X1474531Y822462D01*
X1473931Y822196D01*
X1474131Y823929D01*
X1475931D01*
G01X1478064Y820529D02*
X1478464Y820196D01*
X1478931Y819996D01*
X1479531Y819929D01*
X1480131Y820062D01*
X1480598Y820329D01*
X1480931Y820796D01*
X1480998Y821329D01*
X1480864Y821862D01*
X1480531Y822196D01*
X1480064Y822462D01*
X1479598Y822529D01*
X1479131Y822462D01*
X1478531Y822196D01*
X1478731Y823929D01*
X1480531D01*
G01X1483998Y819929D02*
X1484131Y820796D01*
X1484331Y821529D01*
X1484598Y822196D01*
X1484931Y822929D01*
X1485464Y823929D01*
X1482798D01*
G01X1488731Y819796D02*
X1488598Y819862D01*
Y819996D01*
X1488731Y820062D01*
X1488864Y819996D01*
Y819862D01*
X1488731Y819796D01*
G01X1493331Y823929D02*
X1492798Y823796D01*
X1492398Y823462D01*
X1492131Y823062D01*
X1491931Y822529D01*
X1491864Y821929D01*
X1491931Y821329D01*
X1492131Y820796D01*
X1492398Y820396D01*
X1492798Y820062D01*
X1493331Y819929D01*
X1493864Y820062D01*
X1494264Y820396D01*
X1494531Y820796D01*
X1494731Y821329D01*
X1494798Y821929D01*
X1494731Y822529D01*
X1494531Y823062D01*
X1494264Y823462D01*
X1493864Y823796D01*
X1493331Y823929D01*
G01X1496798Y820396D02*
X1497264Y820062D01*
X1497798Y819929D01*
X1498331Y820062D01*
X1498798Y820462D01*
X1499131Y821062D01*
X1499264Y821662D01*
Y822396D01*
X1499131Y822996D01*
X1498798Y823529D01*
X1498398Y823796D01*
X1497931Y823929D01*
X1497398Y823796D01*
X1496998Y823529D01*
X1496731Y823129D01*
X1496598Y822596D01*
X1496731Y822129D01*
X1497064Y821662D01*
X1497464Y821396D01*
X1497931Y821329D01*
X1498464Y821462D01*
X1498864Y821796D01*
X1499264Y822396D01*
G01X1473464Y1273285D02*
X1473864Y1272952D01*
X1474331Y1272752D01*
X1474931Y1272685D01*
X1475531Y1272818D01*
X1475998Y1273085D01*
X1476331Y1273552D01*
X1476398Y1274085D01*
X1476264Y1274618D01*
X1475931Y1274952D01*
X1475464Y1275218D01*
X1474998Y1275285D01*
X1474531Y1275218D01*
X1473931Y1274952D01*
X1474131Y1276685D01*
X1475931D01*
G01X1478064Y1273285D02*
X1478464Y1272952D01*
X1478931Y1272752D01*
X1479531Y1272685D01*
X1480131Y1272818D01*
X1480598Y1273085D01*
X1480931Y1273552D01*
X1480998Y1274085D01*
X1480864Y1274618D01*
X1480531Y1274952D01*
X1480064Y1275218D01*
X1479598Y1275285D01*
X1479131Y1275218D01*
X1478531Y1274952D01*
X1478731Y1276685D01*
X1480531D01*
G01X1483998Y1272685D02*
X1484131Y1273552D01*
X1484331Y1274285D01*
X1484598Y1274952D01*
X1484931Y1275685D01*
X1485464Y1276685D01*
X1482798D01*
G01X1488731Y1272552D02*
X1488598Y1272618D01*
Y1272752D01*
X1488731Y1272818D01*
X1488864Y1272752D01*
Y1272618D01*
X1488731Y1272552D01*
G01X1493331Y1276685D02*
X1492798Y1276552D01*
X1492398Y1276218D01*
X1492131Y1275818D01*
X1491931Y1275285D01*
X1491864Y1274685D01*
X1491931Y1274085D01*
X1492131Y1273552D01*
X1492398Y1273152D01*
X1492798Y1272818D01*
X1493331Y1272685D01*
X1493864Y1272818D01*
X1494264Y1273152D01*
X1494531Y1273552D01*
X1494731Y1274085D01*
X1494798Y1274685D01*
X1494731Y1275285D01*
X1494531Y1275818D01*
X1494264Y1276218D01*
X1493864Y1276552D01*
X1493331Y1276685D01*
G01X1496798Y1273152D02*
X1497264Y1272818D01*
X1497798Y1272685D01*
X1498331Y1272818D01*
X1498798Y1273218D01*
X1499131Y1273818D01*
X1499264Y1274418D01*
Y1275152D01*
X1499131Y1275752D01*
X1498798Y1276285D01*
X1498398Y1276552D01*
X1497931Y1276685D01*
X1497398Y1276552D01*
X1496998Y1276285D01*
X1496731Y1275885D01*
X1496598Y1275352D01*
X1496731Y1274885D01*
X1497064Y1274418D01*
X1497464Y1274152D01*
X1497931Y1274085D01*
X1498464Y1274218D01*
X1498864Y1274552D01*
X1499264Y1275152D01*
G01X1442382Y1658268D02*
G03X1450256I3937J0D01*
G01X1442382D02*
G03X1450256I3937J0D01*
G01D02*
X1919843D01*
G01X1450256D02*
X1919843D01*
G01X1490774Y58476D02*
X1486774Y54476D01*
X1494774D01*
X1490774Y58476D01*
Y44476D01*
G01X1490803Y378319D02*
X1491203Y378719D01*
X1491670Y378919D01*
X1492203Y378986D01*
X1492870Y378853D01*
X1493337Y378519D01*
X1493470Y378119D01*
X1493403Y377719D01*
X1493137Y377386D01*
X1491803Y376719D01*
X1491203Y376253D01*
X1490803Y375586D01*
X1490670Y374986D01*
X1493470D01*
G01X1495203Y375786D02*
X1495603Y375319D01*
X1496137Y375053D01*
X1496737Y374986D01*
X1497270Y375053D01*
X1497803Y375386D01*
X1498137Y375786D01*
X1498203Y376186D01*
X1498070Y376653D01*
X1497603Y376986D01*
X1497137Y377119D01*
X1496537D01*
G01X1497137D02*
X1497537Y377319D01*
X1497870Y377653D01*
X1498003Y378053D01*
X1497870Y378453D01*
X1497537Y378786D01*
X1496937Y378986D01*
X1496337Y378919D01*
X1495737Y378653D01*
G01X1500003Y376653D02*
X1500470Y377119D01*
X1500870Y377386D01*
X1501403Y377519D01*
X1501870Y377386D01*
X1502203Y377119D01*
X1502470Y376719D01*
X1502537Y376253D01*
X1502470Y375853D01*
X1502203Y375453D01*
X1501803Y375119D01*
X1501337Y374986D01*
X1500803Y375119D01*
X1500337Y375519D01*
X1500070Y376119D01*
X1500003Y376786D01*
X1500137Y377653D01*
X1500337Y378119D01*
X1500670Y378586D01*
X1501137Y378919D01*
X1501603Y378986D01*
X1502070Y378853D01*
X1502403Y378519D01*
G01X1505870Y374853D02*
X1505737Y374919D01*
Y375053D01*
X1505870Y375119D01*
X1506003Y375053D01*
Y374919D01*
X1505870Y374853D01*
G01X1509203Y378319D02*
X1509603Y378719D01*
X1510070Y378919D01*
X1510603Y378986D01*
X1511270Y378853D01*
X1511737Y378519D01*
X1511870Y378119D01*
X1511803Y377719D01*
X1511537Y377386D01*
X1510203Y376719D01*
X1509603Y376253D01*
X1509203Y375586D01*
X1509070Y374986D01*
X1511870D01*
G01X1513803Y378319D02*
X1514203Y378719D01*
X1514670Y378919D01*
X1515203Y378986D01*
X1515870Y378853D01*
X1516337Y378519D01*
X1516470Y378119D01*
X1516403Y377719D01*
X1516137Y377386D01*
X1514803Y376719D01*
X1514203Y376253D01*
X1513803Y375586D01*
X1513670Y374986D01*
X1516470D01*
G01X1490803Y831075D02*
X1491203Y831475D01*
X1491670Y831675D01*
X1492203Y831742D01*
X1492870Y831609D01*
X1493337Y831275D01*
X1493470Y830875D01*
X1493403Y830475D01*
X1493137Y830142D01*
X1491803Y829475D01*
X1491203Y829009D01*
X1490803Y828342D01*
X1490670Y827742D01*
X1493470D01*
G01X1495203Y828542D02*
X1495603Y828075D01*
X1496137Y827809D01*
X1496737Y827742D01*
X1497270Y827809D01*
X1497803Y828142D01*
X1498137Y828542D01*
X1498203Y828942D01*
X1498070Y829409D01*
X1497603Y829742D01*
X1497137Y829875D01*
X1496537D01*
G01X1497137D02*
X1497537Y830075D01*
X1497870Y830409D01*
X1498003Y830809D01*
X1497870Y831209D01*
X1497537Y831542D01*
X1496937Y831742D01*
X1496337Y831675D01*
X1495737Y831409D01*
G01X1500003Y829409D02*
X1500470Y829875D01*
X1500870Y830142D01*
X1501403Y830275D01*
X1501870Y830142D01*
X1502203Y829875D01*
X1502470Y829475D01*
X1502537Y829009D01*
X1502470Y828609D01*
X1502203Y828209D01*
X1501803Y827875D01*
X1501337Y827742D01*
X1500803Y827875D01*
X1500337Y828275D01*
X1500070Y828875D01*
X1500003Y829542D01*
X1500137Y830409D01*
X1500337Y830875D01*
X1500670Y831342D01*
X1501137Y831675D01*
X1501603Y831742D01*
X1502070Y831609D01*
X1502403Y831275D01*
G01X1505870Y827609D02*
X1505737Y827675D01*
Y827809D01*
X1505870Y827875D01*
X1506003Y827809D01*
Y827675D01*
X1505870Y827609D01*
G01X1509203Y831075D02*
X1509603Y831475D01*
X1510070Y831675D01*
X1510603Y831742D01*
X1511270Y831609D01*
X1511737Y831275D01*
X1511870Y830875D01*
X1511803Y830475D01*
X1511537Y830142D01*
X1510203Y829475D01*
X1509603Y829009D01*
X1509203Y828342D01*
X1509070Y827742D01*
X1511870D01*
G01X1513803Y831075D02*
X1514203Y831475D01*
X1514670Y831675D01*
X1515203Y831742D01*
X1515870Y831609D01*
X1516337Y831275D01*
X1516470Y830875D01*
X1516403Y830475D01*
X1516137Y830142D01*
X1514803Y829475D01*
X1514203Y829009D01*
X1513803Y828342D01*
X1513670Y827742D01*
X1516470D01*
G01X1490803Y1283831D02*
X1491203Y1284231D01*
X1491670Y1284431D01*
X1492203Y1284498D01*
X1492870Y1284365D01*
X1493337Y1284031D01*
X1493470Y1283631D01*
X1493403Y1283231D01*
X1493137Y1282898D01*
X1491803Y1282231D01*
X1491203Y1281765D01*
X1490803Y1281098D01*
X1490670Y1280498D01*
X1493470D01*
G01X1495203Y1281298D02*
X1495603Y1280831D01*
X1496137Y1280565D01*
X1496737Y1280498D01*
X1497270Y1280565D01*
X1497803Y1280898D01*
X1498137Y1281298D01*
X1498203Y1281698D01*
X1498070Y1282165D01*
X1497603Y1282498D01*
X1497137Y1282631D01*
X1496537D01*
G01X1497137D02*
X1497537Y1282831D01*
X1497870Y1283165D01*
X1498003Y1283565D01*
X1497870Y1283965D01*
X1497537Y1284298D01*
X1496937Y1284498D01*
X1496337Y1284431D01*
X1495737Y1284165D01*
G01X1500003Y1282165D02*
X1500470Y1282631D01*
X1500870Y1282898D01*
X1501403Y1283031D01*
X1501870Y1282898D01*
X1502203Y1282631D01*
X1502470Y1282231D01*
X1502537Y1281765D01*
X1502470Y1281365D01*
X1502203Y1280965D01*
X1501803Y1280631D01*
X1501337Y1280498D01*
X1500803Y1280631D01*
X1500337Y1281031D01*
X1500070Y1281631D01*
X1500003Y1282298D01*
X1500137Y1283165D01*
X1500337Y1283631D01*
X1500670Y1284098D01*
X1501137Y1284431D01*
X1501603Y1284498D01*
X1502070Y1284365D01*
X1502403Y1284031D01*
G01X1505870Y1280365D02*
X1505737Y1280431D01*
Y1280565D01*
X1505870Y1280631D01*
X1506003Y1280565D01*
Y1280431D01*
X1505870Y1280365D01*
G01X1509203Y1283831D02*
X1509603Y1284231D01*
X1510070Y1284431D01*
X1510603Y1284498D01*
X1511270Y1284365D01*
X1511737Y1284031D01*
X1511870Y1283631D01*
X1511803Y1283231D01*
X1511537Y1282898D01*
X1510203Y1282231D01*
X1509603Y1281765D01*
X1509203Y1281098D01*
X1509070Y1280498D01*
X1511870D01*
G01X1513803Y1283831D02*
X1514203Y1284231D01*
X1514670Y1284431D01*
X1515203Y1284498D01*
X1515870Y1284365D01*
X1516337Y1284031D01*
X1516470Y1283631D01*
X1516403Y1283231D01*
X1516137Y1282898D01*
X1514803Y1282231D01*
X1514203Y1281765D01*
X1513803Y1281098D01*
X1513670Y1280498D01*
X1516470D01*
G01X1562992Y0D02*
X1930906D01*
G01X1559055Y55118D02*
Y3937D01*
G01D02*
G03X1562992Y0I3937J0D01*
G01Y-7874D02*
X1593701D01*
G01X1559055Y55118D02*
Y3937D01*
G01D02*
G03X1562992Y0I3937J0D01*
G01D02*
X1930906D01*
G01X1562992Y-7874D02*
X1593701D01*
G01X1551181Y51181D02*
Y3937D01*
G01D02*
G03X1562992Y-7874I11811J0D01*
G01X1551181Y51181D02*
Y3937D01*
G01D02*
G03X1562992Y-7874I11811J0D01*
G01X1559055Y55118D02*
G03X1555118Y59055I-3937J0D01*
G01X1559055Y55118D02*
G03X1555118Y59055I-3937J0D01*
G01X1532996Y378885D02*
G03X1566807I16906J-13531D01*
G01X1532996D02*
G03X1566807I16906J-13531D01*
G01X1559882Y392016D02*
G03X1566807Y378885I37662J11471D01*
G01X1559882Y392016D02*
G03X1566807Y378885I37662J11471D01*
G01X1559882Y392016D02*
G03X1539921I-9980J-3039D01*
G01X1559882D02*
G03X1539921I-9980J-3039D01*
G01X1532996Y378885D02*
G03X1539921Y392016I-30737J24602D01*
G01X1532996Y378885D02*
G03X1539921Y392016I-30737J24602D01*
G01X1559882Y844772D02*
G03X1566807Y831641I37662J11471D01*
G01X1559882Y844772D02*
G03X1566807Y831641I37662J11471D01*
G01X1532996D02*
G03X1539921Y844772I-30737J24602D01*
G01X1532996Y831641D02*
G03X1539921Y844772I-30737J24602D01*
G01X1532996Y831641D02*
G03X1566807I16906J-13531D01*
G01X1532996D02*
G03X1566807I16906J-13531D01*
G01X1559882Y844772D02*
G03X1539921I-9980J-3040D01*
G01X1559882D02*
G03X1539921I-9980J-3039D01*
G01X1532996Y1284397D02*
G03X1566807I16906J-13531D01*
G01X1532996D02*
G03X1566807I16906J-13531D01*
G01X1559882Y1297528D02*
G03X1566807Y1284397I37662J11471D01*
G01X1559882Y1297528D02*
G03X1566807Y1284397I37662J11471D01*
G01X1559882Y1297528D02*
G03X1539921I-9980J-3040D01*
G01X1532996Y1284397D02*
G03X1539921Y1297528I-30737J24602D01*
G01X1532996Y1284397D02*
G03X1539921Y1297528I-30737J24602D01*
G01X1559882D02*
G03X1539921I-9980J-3040D01*
G01X1563976Y1382677D02*
G03Y1374803I0J-3937D01*
G01Y1382677D02*
G03Y1374803I0J-3937D01*
G01X1524606D02*
G03Y1382677I0J3937D01*
G01Y1374803D02*
G03Y1382677I0J3937D01*
G01X1864567D02*
X1563976D01*
G01X1864567D02*
X1563976D01*
G01X1593701Y-7874D02*
G03Y0I0J3937D01*
G01Y-7874D02*
G03Y0I0J3937D01*
G01X1591498Y334725D02*
Y338725D01*
X1589031Y335858D01*
X1592365D01*
G01X1593831Y335525D02*
X1594231Y335058D01*
X1594765Y334792D01*
X1595365Y334725D01*
X1595898Y334792D01*
X1596431Y335125D01*
X1596765Y335525D01*
X1596831Y335925D01*
X1596698Y336392D01*
X1596231Y336725D01*
X1595765Y336858D01*
X1595165D01*
G01X1595765D02*
X1596165Y337058D01*
X1596498Y337392D01*
X1596631Y337792D01*
X1596498Y338192D01*
X1596165Y338525D01*
X1595565Y338725D01*
X1594965Y338658D01*
X1594365Y338392D01*
G01X1598431Y335525D02*
X1598831Y335058D01*
X1599365Y334792D01*
X1599965Y334725D01*
X1600498Y334792D01*
X1601031Y335125D01*
X1601365Y335525D01*
X1601431Y335925D01*
X1601298Y336392D01*
X1600831Y336725D01*
X1600365Y336858D01*
X1599765D01*
G01X1600365D02*
X1600765Y337058D01*
X1601098Y337392D01*
X1601231Y337792D01*
X1601098Y338192D01*
X1600765Y338525D01*
X1600165Y338725D01*
X1599565Y338658D01*
X1598965Y338392D01*
G01X1604498Y334592D02*
X1604365Y334658D01*
Y334792D01*
X1604498Y334858D01*
X1604631Y334792D01*
Y334658D01*
X1604498Y334592D01*
G01X1609098Y338725D02*
X1608565Y338592D01*
X1608165Y338258D01*
X1607898Y337858D01*
X1607698Y337325D01*
X1607631Y336725D01*
X1607698Y336125D01*
X1607898Y335592D01*
X1608165Y335192D01*
X1608565Y334858D01*
X1609098Y334725D01*
X1609631Y334858D01*
X1610031Y335192D01*
X1610298Y335592D01*
X1610498Y336125D01*
X1610565Y336725D01*
X1610498Y337325D01*
X1610298Y337858D01*
X1610031Y338258D01*
X1609631Y338592D01*
X1609098Y338725D01*
G01X1613698Y334725D02*
X1614165Y334792D01*
X1614698Y334992D01*
X1615031Y335325D01*
X1615165Y335792D01*
X1615031Y336258D01*
X1614631Y336658D01*
X1614031Y336858D01*
X1613365D01*
X1612965Y336992D01*
X1612631Y337325D01*
X1612498Y337792D01*
X1612698Y338258D01*
X1613165Y338592D01*
X1613698Y338725D01*
X1614231Y338592D01*
X1614698Y338258D01*
X1614898Y337792D01*
X1614765Y337325D01*
X1614431Y336992D01*
X1614031Y336858D01*
X1613365D01*
X1612765Y336658D01*
X1612365Y336258D01*
X1612231Y335792D01*
X1612365Y335325D01*
X1612698Y334992D01*
X1613231Y334792D01*
X1613698Y334725D01*
G01X1585035Y376882D02*
Y380882D01*
X1586369D01*
X1586902Y380682D01*
X1587302Y380415D01*
X1587635Y380015D01*
X1587902Y379549D01*
X1587969Y378882D01*
X1587902Y378215D01*
X1587635Y377749D01*
X1587302Y377349D01*
X1586902Y377082D01*
X1586369Y376882D01*
X1585035D01*
G01X1590169D02*
Y379549D01*
G01Y379015D02*
X1590502Y379282D01*
X1590835Y379482D01*
X1591302Y379549D01*
X1591635Y379482D01*
X1592035Y379282D01*
G01X1595702Y379549D02*
Y376882D01*
G01Y380615D02*
X1595569Y380682D01*
Y380815D01*
X1595702Y380882D01*
X1595835Y380815D01*
Y380682D01*
X1595702Y380615D01*
G01X1600302Y376882D02*
Y380882D01*
G01X1604902Y376882D02*
Y380882D01*
G01X1613702Y376882D02*
Y380282D01*
X1613835Y380615D01*
X1614102Y380815D01*
X1614502Y380882D01*
X1614902Y380749D01*
X1615102Y380415D01*
G01X1614302Y379282D02*
X1612969D01*
G01X1617702Y378682D02*
X1619835D01*
X1619635Y379149D01*
X1619302Y379415D01*
X1618835Y379549D01*
X1618369Y379482D01*
X1617969Y379282D01*
X1617702Y378815D01*
X1617569Y378415D01*
Y378015D01*
X1617702Y377615D01*
X1618035Y377215D01*
X1618435Y376949D01*
X1618902Y376882D01*
X1619369Y377015D01*
X1619835Y377415D01*
G01X1624502Y376882D02*
Y379549D01*
G01Y379082D02*
X1624235Y379349D01*
X1623835Y379482D01*
X1623369Y379549D01*
X1622902Y379415D01*
X1622502Y379149D01*
X1622235Y378749D01*
X1622102Y378215D01*
X1622235Y377682D01*
X1622502Y377282D01*
X1622902Y377015D01*
X1623369Y376882D01*
X1623835Y376949D01*
X1624235Y377149D01*
X1624502Y377415D01*
G01X1627902Y380882D02*
Y376882D01*
G01X1626969Y379549D02*
X1628835D01*
G01X1631369D02*
Y377682D01*
X1631635Y377215D01*
X1632035Y376949D01*
X1632502Y376882D01*
X1632969Y376949D01*
X1633369Y377215D01*
X1633635Y377682D01*
G01Y376882D02*
Y379549D01*
G01X1636169Y376882D02*
Y379549D01*
G01Y379015D02*
X1636502Y379282D01*
X1636835Y379482D01*
X1637302Y379549D01*
X1637635Y379482D01*
X1638035Y379282D01*
G01X1640702Y378682D02*
X1642835D01*
X1642635Y379149D01*
X1642302Y379415D01*
X1641835Y379549D01*
X1641369Y379482D01*
X1640969Y379282D01*
X1640702Y378815D01*
X1640569Y378415D01*
Y378015D01*
X1640702Y377615D01*
X1641035Y377215D01*
X1641435Y376949D01*
X1641902Y376882D01*
X1642369Y377015D01*
X1642835Y377415D01*
G01X1591590Y419049D02*
X1591990Y419449D01*
X1592457Y419649D01*
X1592990Y419716D01*
X1593657Y419583D01*
X1594124Y419249D01*
X1594257Y418849D01*
X1594190Y418449D01*
X1593924Y418116D01*
X1592590Y417449D01*
X1591990Y416983D01*
X1591590Y416316D01*
X1591457Y415716D01*
X1594257D01*
G01X1597457Y419716D02*
X1596924Y419583D01*
X1596524Y419249D01*
X1596257Y418849D01*
X1596057Y418316D01*
X1595990Y417716D01*
X1596057Y417116D01*
X1596257Y416583D01*
X1596524Y416183D01*
X1596924Y415849D01*
X1597457Y415716D01*
X1597990Y415849D01*
X1598390Y416183D01*
X1598657Y416583D01*
X1598857Y417116D01*
X1598924Y417716D01*
X1598857Y418316D01*
X1598657Y418849D01*
X1598390Y419249D01*
X1597990Y419583D01*
X1597457Y419716D01*
G01X1602057Y415716D02*
X1602524Y415783D01*
X1603057Y415983D01*
X1603390Y416316D01*
X1603524Y416783D01*
X1603390Y417249D01*
X1602990Y417649D01*
X1602390Y417849D01*
X1601724D01*
X1601324Y417983D01*
X1600990Y418316D01*
X1600857Y418783D01*
X1601057Y419249D01*
X1601524Y419583D01*
X1602057Y419716D01*
X1602590Y419583D01*
X1603057Y419249D01*
X1603257Y418783D01*
X1603124Y418316D01*
X1602790Y417983D01*
X1602390Y417849D01*
X1601724D01*
X1601124Y417649D01*
X1600724Y417249D01*
X1600590Y416783D01*
X1600724Y416316D01*
X1601057Y415983D01*
X1601590Y415783D01*
X1602057Y415716D01*
G01X1606657Y415583D02*
X1606524Y415649D01*
Y415783D01*
X1606657Y415849D01*
X1606790Y415783D01*
Y415649D01*
X1606657Y415583D01*
G01X1609990Y417383D02*
X1610457Y417849D01*
X1610857Y418116D01*
X1611390Y418249D01*
X1611857Y418116D01*
X1612190Y417849D01*
X1612457Y417449D01*
X1612524Y416983D01*
X1612457Y416583D01*
X1612190Y416183D01*
X1611790Y415849D01*
X1611324Y415716D01*
X1610790Y415849D01*
X1610324Y416249D01*
X1610057Y416849D01*
X1609990Y417516D01*
X1610124Y418383D01*
X1610324Y418849D01*
X1610657Y419316D01*
X1611124Y419649D01*
X1611590Y419716D01*
X1612057Y419583D01*
X1612390Y419249D01*
G01X1614590Y417383D02*
X1615057Y417849D01*
X1615457Y418116D01*
X1615990Y418249D01*
X1616457Y418116D01*
X1616790Y417849D01*
X1617057Y417449D01*
X1617124Y416983D01*
X1617057Y416583D01*
X1616790Y416183D01*
X1616390Y415849D01*
X1615924Y415716D01*
X1615390Y415849D01*
X1614924Y416249D01*
X1614657Y416849D01*
X1614590Y417516D01*
X1614724Y418383D01*
X1614924Y418849D01*
X1615257Y419316D01*
X1615724Y419649D01*
X1616190Y419716D01*
X1616657Y419583D01*
X1616990Y419249D01*
G01X1591498Y787481D02*
Y791481D01*
X1589031Y788614D01*
X1592365D01*
G01X1593831Y788281D02*
X1594231Y787814D01*
X1594765Y787548D01*
X1595365Y787481D01*
X1595898Y787548D01*
X1596431Y787881D01*
X1596765Y788281D01*
X1596831Y788681D01*
X1596698Y789148D01*
X1596231Y789481D01*
X1595765Y789614D01*
X1595165D01*
G01X1595765D02*
X1596165Y789814D01*
X1596498Y790148D01*
X1596631Y790548D01*
X1596498Y790948D01*
X1596165Y791281D01*
X1595565Y791481D01*
X1594965Y791414D01*
X1594365Y791148D01*
G01X1598431Y788281D02*
X1598831Y787814D01*
X1599365Y787548D01*
X1599965Y787481D01*
X1600498Y787548D01*
X1601031Y787881D01*
X1601365Y788281D01*
X1601431Y788681D01*
X1601298Y789148D01*
X1600831Y789481D01*
X1600365Y789614D01*
X1599765D01*
G01X1600365D02*
X1600765Y789814D01*
X1601098Y790148D01*
X1601231Y790548D01*
X1601098Y790948D01*
X1600765Y791281D01*
X1600165Y791481D01*
X1599565Y791414D01*
X1598965Y791148D01*
G01X1604498Y787348D02*
X1604365Y787414D01*
Y787548D01*
X1604498Y787614D01*
X1604631Y787548D01*
Y787414D01*
X1604498Y787348D01*
G01X1609098Y791481D02*
X1608565Y791348D01*
X1608165Y791014D01*
X1607898Y790614D01*
X1607698Y790081D01*
X1607631Y789481D01*
X1607698Y788881D01*
X1607898Y788348D01*
X1608165Y787948D01*
X1608565Y787614D01*
X1609098Y787481D01*
X1609631Y787614D01*
X1610031Y787948D01*
X1610298Y788348D01*
X1610498Y788881D01*
X1610565Y789481D01*
X1610498Y790081D01*
X1610298Y790614D01*
X1610031Y791014D01*
X1609631Y791348D01*
X1609098Y791481D01*
G01X1613698Y787481D02*
X1614165Y787548D01*
X1614698Y787748D01*
X1615031Y788081D01*
X1615165Y788548D01*
X1615031Y789014D01*
X1614631Y789414D01*
X1614031Y789614D01*
X1613365D01*
X1612965Y789748D01*
X1612631Y790081D01*
X1612498Y790548D01*
X1612698Y791014D01*
X1613165Y791348D01*
X1613698Y791481D01*
X1614231Y791348D01*
X1614698Y791014D01*
X1614898Y790548D01*
X1614765Y790081D01*
X1614431Y789748D01*
X1614031Y789614D01*
X1613365D01*
X1612765Y789414D01*
X1612365Y789014D01*
X1612231Y788548D01*
X1612365Y788081D01*
X1612698Y787748D01*
X1613231Y787548D01*
X1613698Y787481D01*
G01X1585035Y829638D02*
Y833638D01*
X1586369D01*
X1586902Y833438D01*
X1587302Y833171D01*
X1587635Y832771D01*
X1587902Y832305D01*
X1587969Y831638D01*
X1587902Y830971D01*
X1587635Y830505D01*
X1587302Y830105D01*
X1586902Y829838D01*
X1586369Y829638D01*
X1585035D01*
G01X1590169D02*
Y832305D01*
G01Y831771D02*
X1590502Y832038D01*
X1590835Y832238D01*
X1591302Y832305D01*
X1591635Y832238D01*
X1592035Y832038D01*
G01X1595702Y832305D02*
Y829638D01*
G01Y833371D02*
X1595569Y833438D01*
Y833571D01*
X1595702Y833638D01*
X1595835Y833571D01*
Y833438D01*
X1595702Y833371D01*
G01X1600302Y829638D02*
Y833638D01*
G01X1604902Y829638D02*
Y833638D01*
G01X1613702Y829638D02*
Y833038D01*
X1613835Y833371D01*
X1614102Y833571D01*
X1614502Y833638D01*
X1614902Y833505D01*
X1615102Y833171D01*
G01X1614302Y832038D02*
X1612969D01*
G01X1617702Y831438D02*
X1619835D01*
X1619635Y831905D01*
X1619302Y832171D01*
X1618835Y832305D01*
X1618369Y832238D01*
X1617969Y832038D01*
X1617702Y831571D01*
X1617569Y831171D01*
Y830771D01*
X1617702Y830371D01*
X1618035Y829971D01*
X1618435Y829705D01*
X1618902Y829638D01*
X1619369Y829771D01*
X1619835Y830171D01*
G01X1624502Y829638D02*
Y832305D01*
G01Y831838D02*
X1624235Y832105D01*
X1623835Y832238D01*
X1623369Y832305D01*
X1622902Y832171D01*
X1622502Y831905D01*
X1622235Y831505D01*
X1622102Y830971D01*
X1622235Y830438D01*
X1622502Y830038D01*
X1622902Y829771D01*
X1623369Y829638D01*
X1623835Y829705D01*
X1624235Y829905D01*
X1624502Y830171D01*
G01X1627902Y833638D02*
Y829638D01*
G01X1626969Y832305D02*
X1628835D01*
G01X1631369D02*
Y830438D01*
X1631635Y829971D01*
X1632035Y829705D01*
X1632502Y829638D01*
X1632969Y829705D01*
X1633369Y829971D01*
X1633635Y830438D01*
G01Y829638D02*
Y832305D01*
G01X1636169Y829638D02*
Y832305D01*
G01Y831771D02*
X1636502Y832038D01*
X1636835Y832238D01*
X1637302Y832305D01*
X1637635Y832238D01*
X1638035Y832038D01*
G01X1640702Y831438D02*
X1642835D01*
X1642635Y831905D01*
X1642302Y832171D01*
X1641835Y832305D01*
X1641369Y832238D01*
X1640969Y832038D01*
X1640702Y831571D01*
X1640569Y831171D01*
Y830771D01*
X1640702Y830371D01*
X1641035Y829971D01*
X1641435Y829705D01*
X1641902Y829638D01*
X1642369Y829771D01*
X1642835Y830171D01*
G01X1591590Y871805D02*
X1591990Y872205D01*
X1592457Y872405D01*
X1592990Y872472D01*
X1593657Y872339D01*
X1594124Y872005D01*
X1594257Y871605D01*
X1594190Y871205D01*
X1593924Y870872D01*
X1592590Y870205D01*
X1591990Y869739D01*
X1591590Y869072D01*
X1591457Y868472D01*
X1594257D01*
G01X1597457Y872472D02*
X1596924Y872339D01*
X1596524Y872005D01*
X1596257Y871605D01*
X1596057Y871072D01*
X1595990Y870472D01*
X1596057Y869872D01*
X1596257Y869339D01*
X1596524Y868939D01*
X1596924Y868605D01*
X1597457Y868472D01*
X1597990Y868605D01*
X1598390Y868939D01*
X1598657Y869339D01*
X1598857Y869872D01*
X1598924Y870472D01*
X1598857Y871072D01*
X1598657Y871605D01*
X1598390Y872005D01*
X1597990Y872339D01*
X1597457Y872472D01*
G01X1602057Y868472D02*
X1602524Y868539D01*
X1603057Y868739D01*
X1603390Y869072D01*
X1603524Y869539D01*
X1603390Y870005D01*
X1602990Y870405D01*
X1602390Y870605D01*
X1601724D01*
X1601324Y870739D01*
X1600990Y871072D01*
X1600857Y871539D01*
X1601057Y872005D01*
X1601524Y872339D01*
X1602057Y872472D01*
X1602590Y872339D01*
X1603057Y872005D01*
X1603257Y871539D01*
X1603124Y871072D01*
X1602790Y870739D01*
X1602390Y870605D01*
X1601724D01*
X1601124Y870405D01*
X1600724Y870005D01*
X1600590Y869539D01*
X1600724Y869072D01*
X1601057Y868739D01*
X1601590Y868539D01*
X1602057Y868472D01*
G01X1606657Y868339D02*
X1606524Y868405D01*
Y868539D01*
X1606657Y868605D01*
X1606790Y868539D01*
Y868405D01*
X1606657Y868339D01*
G01X1609990Y870139D02*
X1610457Y870605D01*
X1610857Y870872D01*
X1611390Y871005D01*
X1611857Y870872D01*
X1612190Y870605D01*
X1612457Y870205D01*
X1612524Y869739D01*
X1612457Y869339D01*
X1612190Y868939D01*
X1611790Y868605D01*
X1611324Y868472D01*
X1610790Y868605D01*
X1610324Y869005D01*
X1610057Y869605D01*
X1609990Y870272D01*
X1610124Y871139D01*
X1610324Y871605D01*
X1610657Y872072D01*
X1611124Y872405D01*
X1611590Y872472D01*
X1612057Y872339D01*
X1612390Y872005D01*
G01X1614590Y870139D02*
X1615057Y870605D01*
X1615457Y870872D01*
X1615990Y871005D01*
X1616457Y870872D01*
X1616790Y870605D01*
X1617057Y870205D01*
X1617124Y869739D01*
X1617057Y869339D01*
X1616790Y868939D01*
X1616390Y868605D01*
X1615924Y868472D01*
X1615390Y868605D01*
X1614924Y869005D01*
X1614657Y869605D01*
X1614590Y870272D01*
X1614724Y871139D01*
X1614924Y871605D01*
X1615257Y872072D01*
X1615724Y872405D01*
X1616190Y872472D01*
X1616657Y872339D01*
X1616990Y872005D01*
G01X1591498Y1240237D02*
Y1244237D01*
X1589031Y1241370D01*
X1592365D01*
G01X1593831Y1241037D02*
X1594231Y1240570D01*
X1594765Y1240304D01*
X1595365Y1240237D01*
X1595898Y1240304D01*
X1596431Y1240637D01*
X1596765Y1241037D01*
X1596831Y1241437D01*
X1596698Y1241904D01*
X1596231Y1242237D01*
X1595765Y1242370D01*
X1595165D01*
G01X1595765D02*
X1596165Y1242570D01*
X1596498Y1242904D01*
X1596631Y1243304D01*
X1596498Y1243704D01*
X1596165Y1244037D01*
X1595565Y1244237D01*
X1594965Y1244170D01*
X1594365Y1243904D01*
G01X1598431Y1241037D02*
X1598831Y1240570D01*
X1599365Y1240304D01*
X1599965Y1240237D01*
X1600498Y1240304D01*
X1601031Y1240637D01*
X1601365Y1241037D01*
X1601431Y1241437D01*
X1601298Y1241904D01*
X1600831Y1242237D01*
X1600365Y1242370D01*
X1599765D01*
G01X1600365D02*
X1600765Y1242570D01*
X1601098Y1242904D01*
X1601231Y1243304D01*
X1601098Y1243704D01*
X1600765Y1244037D01*
X1600165Y1244237D01*
X1599565Y1244170D01*
X1598965Y1243904D01*
G01X1604498Y1240104D02*
X1604365Y1240170D01*
Y1240304D01*
X1604498Y1240370D01*
X1604631Y1240304D01*
Y1240170D01*
X1604498Y1240104D01*
G01X1609098Y1244237D02*
X1608565Y1244104D01*
X1608165Y1243770D01*
X1607898Y1243370D01*
X1607698Y1242837D01*
X1607631Y1242237D01*
X1607698Y1241637D01*
X1607898Y1241104D01*
X1608165Y1240704D01*
X1608565Y1240370D01*
X1609098Y1240237D01*
X1609631Y1240370D01*
X1610031Y1240704D01*
X1610298Y1241104D01*
X1610498Y1241637D01*
X1610565Y1242237D01*
X1610498Y1242837D01*
X1610298Y1243370D01*
X1610031Y1243770D01*
X1609631Y1244104D01*
X1609098Y1244237D01*
G01X1613698Y1240237D02*
X1614165Y1240304D01*
X1614698Y1240504D01*
X1615031Y1240837D01*
X1615165Y1241304D01*
X1615031Y1241770D01*
X1614631Y1242170D01*
X1614031Y1242370D01*
X1613365D01*
X1612965Y1242504D01*
X1612631Y1242837D01*
X1612498Y1243304D01*
X1612698Y1243770D01*
X1613165Y1244104D01*
X1613698Y1244237D01*
X1614231Y1244104D01*
X1614698Y1243770D01*
X1614898Y1243304D01*
X1614765Y1242837D01*
X1614431Y1242504D01*
X1614031Y1242370D01*
X1613365D01*
X1612765Y1242170D01*
X1612365Y1241770D01*
X1612231Y1241304D01*
X1612365Y1240837D01*
X1612698Y1240504D01*
X1613231Y1240304D01*
X1613698Y1240237D01*
G01X1591590Y1324561D02*
X1591990Y1324961D01*
X1592457Y1325161D01*
X1592990Y1325228D01*
X1593657Y1325095D01*
X1594124Y1324761D01*
X1594257Y1324361D01*
X1594190Y1323961D01*
X1593924Y1323628D01*
X1592590Y1322961D01*
X1591990Y1322495D01*
X1591590Y1321828D01*
X1591457Y1321228D01*
X1594257D01*
G01X1597457Y1325228D02*
X1596924Y1325095D01*
X1596524Y1324761D01*
X1596257Y1324361D01*
X1596057Y1323828D01*
X1595990Y1323228D01*
X1596057Y1322628D01*
X1596257Y1322095D01*
X1596524Y1321695D01*
X1596924Y1321361D01*
X1597457Y1321228D01*
X1597990Y1321361D01*
X1598390Y1321695D01*
X1598657Y1322095D01*
X1598857Y1322628D01*
X1598924Y1323228D01*
X1598857Y1323828D01*
X1598657Y1324361D01*
X1598390Y1324761D01*
X1597990Y1325095D01*
X1597457Y1325228D01*
G01X1602057Y1321228D02*
X1602524Y1321295D01*
X1603057Y1321495D01*
X1603390Y1321828D01*
X1603524Y1322295D01*
X1603390Y1322761D01*
X1602990Y1323161D01*
X1602390Y1323361D01*
X1601724D01*
X1601324Y1323495D01*
X1600990Y1323828D01*
X1600857Y1324295D01*
X1601057Y1324761D01*
X1601524Y1325095D01*
X1602057Y1325228D01*
X1602590Y1325095D01*
X1603057Y1324761D01*
X1603257Y1324295D01*
X1603124Y1323828D01*
X1602790Y1323495D01*
X1602390Y1323361D01*
X1601724D01*
X1601124Y1323161D01*
X1600724Y1322761D01*
X1600590Y1322295D01*
X1600724Y1321828D01*
X1601057Y1321495D01*
X1601590Y1321295D01*
X1602057Y1321228D01*
G01X1606657Y1321095D02*
X1606524Y1321161D01*
Y1321295D01*
X1606657Y1321361D01*
X1606790Y1321295D01*
Y1321161D01*
X1606657Y1321095D01*
G01X1609990Y1322895D02*
X1610457Y1323361D01*
X1610857Y1323628D01*
X1611390Y1323761D01*
X1611857Y1323628D01*
X1612190Y1323361D01*
X1612457Y1322961D01*
X1612524Y1322495D01*
X1612457Y1322095D01*
X1612190Y1321695D01*
X1611790Y1321361D01*
X1611324Y1321228D01*
X1610790Y1321361D01*
X1610324Y1321761D01*
X1610057Y1322361D01*
X1609990Y1323028D01*
X1610124Y1323895D01*
X1610324Y1324361D01*
X1610657Y1324828D01*
X1611124Y1325161D01*
X1611590Y1325228D01*
X1612057Y1325095D01*
X1612390Y1324761D01*
G01X1614590Y1322895D02*
X1615057Y1323361D01*
X1615457Y1323628D01*
X1615990Y1323761D01*
X1616457Y1323628D01*
X1616790Y1323361D01*
X1617057Y1322961D01*
X1617124Y1322495D01*
X1617057Y1322095D01*
X1616790Y1321695D01*
X1616390Y1321361D01*
X1615924Y1321228D01*
X1615390Y1321361D01*
X1614924Y1321761D01*
X1614657Y1322361D01*
X1614590Y1323028D01*
X1614724Y1323895D01*
X1614924Y1324361D01*
X1615257Y1324828D01*
X1615724Y1325161D01*
X1616190Y1325228D01*
X1616657Y1325095D01*
X1616990Y1324761D01*
G01X1585035Y1282394D02*
Y1286394D01*
X1586369D01*
X1586902Y1286194D01*
X1587302Y1285927D01*
X1587635Y1285527D01*
X1587902Y1285061D01*
X1587969Y1284394D01*
X1587902Y1283727D01*
X1587635Y1283261D01*
X1587302Y1282861D01*
X1586902Y1282594D01*
X1586369Y1282394D01*
X1585035D01*
G01X1590169D02*
Y1285061D01*
G01Y1284527D02*
X1590502Y1284794D01*
X1590835Y1284994D01*
X1591302Y1285061D01*
X1591635Y1284994D01*
X1592035Y1284794D01*
G01X1595702Y1285061D02*
Y1282394D01*
G01Y1286127D02*
X1595569Y1286194D01*
Y1286327D01*
X1595702Y1286394D01*
X1595835Y1286327D01*
Y1286194D01*
X1595702Y1286127D01*
G01X1600302Y1282394D02*
Y1286394D01*
G01X1604902Y1282394D02*
Y1286394D01*
G01X1613702Y1282394D02*
Y1285794D01*
X1613835Y1286127D01*
X1614102Y1286327D01*
X1614502Y1286394D01*
X1614902Y1286261D01*
X1615102Y1285927D01*
G01X1614302Y1284794D02*
X1612969D01*
G01X1617702Y1284194D02*
X1619835D01*
X1619635Y1284661D01*
X1619302Y1284927D01*
X1618835Y1285061D01*
X1618369Y1284994D01*
X1617969Y1284794D01*
X1617702Y1284327D01*
X1617569Y1283927D01*
Y1283527D01*
X1617702Y1283127D01*
X1618035Y1282727D01*
X1618435Y1282461D01*
X1618902Y1282394D01*
X1619369Y1282527D01*
X1619835Y1282927D01*
G01X1624502Y1282394D02*
Y1285061D01*
G01Y1284594D02*
X1624235Y1284861D01*
X1623835Y1284994D01*
X1623369Y1285061D01*
X1622902Y1284927D01*
X1622502Y1284661D01*
X1622235Y1284261D01*
X1622102Y1283727D01*
X1622235Y1283194D01*
X1622502Y1282794D01*
X1622902Y1282527D01*
X1623369Y1282394D01*
X1623835Y1282461D01*
X1624235Y1282661D01*
X1624502Y1282927D01*
G01X1627902Y1286394D02*
Y1282394D01*
G01X1626969Y1285061D02*
X1628835D01*
G01X1631369D02*
Y1283194D01*
X1631635Y1282727D01*
X1632035Y1282461D01*
X1632502Y1282394D01*
X1632969Y1282461D01*
X1633369Y1282727D01*
X1633635Y1283194D01*
G01Y1282394D02*
Y1285061D01*
G01X1636169Y1282394D02*
Y1285061D01*
G01Y1284527D02*
X1636502Y1284794D01*
X1636835Y1284994D01*
X1637302Y1285061D01*
X1637635Y1284994D01*
X1638035Y1284794D01*
G01X1640702Y1284194D02*
X1642835D01*
X1642635Y1284661D01*
X1642302Y1284927D01*
X1641835Y1285061D01*
X1641369Y1284994D01*
X1640969Y1284794D01*
X1640702Y1284327D01*
X1640569Y1283927D01*
Y1283527D01*
X1640702Y1283127D01*
X1641035Y1282727D01*
X1641435Y1282461D01*
X1641902Y1282394D01*
X1642369Y1282527D01*
X1642835Y1282927D01*
G01X1633071Y0D02*
G03Y-7874I0J-3937D01*
G01D02*
X1880512D01*
G01X1633071D02*
X1880512D01*
G01X1633071Y0D02*
G03Y-7874I0J-3937D01*
G01X1693996Y829921D02*
G03X1653839I-20078J0D01*
G01X1693996D02*
G03I-20079J0D01*
G01X1653839D02*
G03X1693996I20078J0D01*
G01X1738835Y378319D02*
X1739235Y378719D01*
X1739702Y378919D01*
X1740235Y378986D01*
X1740902Y378853D01*
X1741369Y378519D01*
X1741502Y378119D01*
X1741435Y377719D01*
X1741169Y377386D01*
X1739835Y376719D01*
X1739235Y376253D01*
X1738835Y375586D01*
X1738702Y374986D01*
X1741502D01*
G01X1743235Y375786D02*
X1743635Y375319D01*
X1744169Y375053D01*
X1744769Y374986D01*
X1745302Y375053D01*
X1745835Y375386D01*
X1746169Y375786D01*
X1746235Y376186D01*
X1746102Y376653D01*
X1745635Y376986D01*
X1745169Y377119D01*
X1744569D01*
G01X1745169D02*
X1745569Y377319D01*
X1745902Y377653D01*
X1746035Y378053D01*
X1745902Y378453D01*
X1745569Y378786D01*
X1744969Y378986D01*
X1744369Y378919D01*
X1743769Y378653D01*
G01X1748035Y376653D02*
X1748502Y377119D01*
X1748902Y377386D01*
X1749435Y377519D01*
X1749902Y377386D01*
X1750235Y377119D01*
X1750502Y376719D01*
X1750569Y376253D01*
X1750502Y375853D01*
X1750235Y375453D01*
X1749835Y375119D01*
X1749369Y374986D01*
X1748835Y375119D01*
X1748369Y375519D01*
X1748102Y376119D01*
X1748035Y376786D01*
X1748169Y377653D01*
X1748369Y378119D01*
X1748702Y378586D01*
X1749169Y378919D01*
X1749635Y378986D01*
X1750102Y378853D01*
X1750435Y378519D01*
G01X1753902Y374853D02*
X1753769Y374919D01*
Y375053D01*
X1753902Y375119D01*
X1754035Y375053D01*
Y374919D01*
X1753902Y374853D01*
G01X1757235Y378319D02*
X1757635Y378719D01*
X1758102Y378919D01*
X1758635Y378986D01*
X1759302Y378853D01*
X1759769Y378519D01*
X1759902Y378119D01*
X1759835Y377719D01*
X1759569Y377386D01*
X1758235Y376719D01*
X1757635Y376253D01*
X1757235Y375586D01*
X1757102Y374986D01*
X1759902D01*
G01X1761835Y378319D02*
X1762235Y378719D01*
X1762702Y378919D01*
X1763235Y378986D01*
X1763902Y378853D01*
X1764369Y378519D01*
X1764502Y378119D01*
X1764435Y377719D01*
X1764169Y377386D01*
X1762835Y376719D01*
X1762235Y376253D01*
X1761835Y375586D01*
X1761702Y374986D01*
X1764502D01*
G01X1721496Y367773D02*
X1721896Y367440D01*
X1722363Y367240D01*
X1722963Y367173D01*
X1723563Y367306D01*
X1724030Y367573D01*
X1724363Y368040D01*
X1724430Y368573D01*
X1724296Y369106D01*
X1723963Y369440D01*
X1723496Y369706D01*
X1723030Y369773D01*
X1722563Y369706D01*
X1721963Y369440D01*
X1722163Y371173D01*
X1723963D01*
G01X1726096Y367773D02*
X1726496Y367440D01*
X1726963Y367240D01*
X1727563Y367173D01*
X1728163Y367306D01*
X1728630Y367573D01*
X1728963Y368040D01*
X1729030Y368573D01*
X1728896Y369106D01*
X1728563Y369440D01*
X1728096Y369706D01*
X1727630Y369773D01*
X1727163Y369706D01*
X1726563Y369440D01*
X1726763Y371173D01*
X1728563D01*
G01X1732030Y367173D02*
X1732163Y368040D01*
X1732363Y368773D01*
X1732630Y369440D01*
X1732963Y370173D01*
X1733496Y371173D01*
X1730830D01*
G01X1736763Y367040D02*
X1736630Y367106D01*
Y367240D01*
X1736763Y367306D01*
X1736896Y367240D01*
Y367106D01*
X1736763Y367040D01*
G01X1741363Y371173D02*
X1740830Y371040D01*
X1740430Y370706D01*
X1740163Y370306D01*
X1739963Y369773D01*
X1739896Y369173D01*
X1739963Y368573D01*
X1740163Y368040D01*
X1740430Y367640D01*
X1740830Y367306D01*
X1741363Y367173D01*
X1741896Y367306D01*
X1742296Y367640D01*
X1742563Y368040D01*
X1742763Y368573D01*
X1742830Y369173D01*
X1742763Y369773D01*
X1742563Y370306D01*
X1742296Y370706D01*
X1741896Y371040D01*
X1741363Y371173D01*
G01X1744830Y367640D02*
X1745296Y367306D01*
X1745830Y367173D01*
X1746363Y367306D01*
X1746830Y367706D01*
X1747163Y368306D01*
X1747296Y368906D01*
Y369640D01*
X1747163Y370240D01*
X1746830Y370773D01*
X1746430Y371040D01*
X1745963Y371173D01*
X1745430Y371040D01*
X1745030Y370773D01*
X1744763Y370373D01*
X1744630Y369840D01*
X1744763Y369373D01*
X1745096Y368906D01*
X1745496Y368640D01*
X1745963Y368573D01*
X1746496Y368706D01*
X1746896Y369040D01*
X1747296Y369640D01*
G01X1721496Y820529D02*
X1721896Y820196D01*
X1722363Y819996D01*
X1722963Y819929D01*
X1723563Y820062D01*
X1724030Y820329D01*
X1724363Y820796D01*
X1724430Y821329D01*
X1724296Y821862D01*
X1723963Y822196D01*
X1723496Y822462D01*
X1723030Y822529D01*
X1722563Y822462D01*
X1721963Y822196D01*
X1722163Y823929D01*
X1723963D01*
G01X1726096Y820529D02*
X1726496Y820196D01*
X1726963Y819996D01*
X1727563Y819929D01*
X1728163Y820062D01*
X1728630Y820329D01*
X1728963Y820796D01*
X1729030Y821329D01*
X1728896Y821862D01*
X1728563Y822196D01*
X1728096Y822462D01*
X1727630Y822529D01*
X1727163Y822462D01*
X1726563Y822196D01*
X1726763Y823929D01*
X1728563D01*
G01X1732030Y819929D02*
X1732163Y820796D01*
X1732363Y821529D01*
X1732630Y822196D01*
X1732963Y822929D01*
X1733496Y823929D01*
X1730830D01*
G01X1736763Y819796D02*
X1736630Y819862D01*
Y819996D01*
X1736763Y820062D01*
X1736896Y819996D01*
Y819862D01*
X1736763Y819796D01*
G01X1741363Y823929D02*
X1740830Y823796D01*
X1740430Y823462D01*
X1740163Y823062D01*
X1739963Y822529D01*
X1739896Y821929D01*
X1739963Y821329D01*
X1740163Y820796D01*
X1740430Y820396D01*
X1740830Y820062D01*
X1741363Y819929D01*
X1741896Y820062D01*
X1742296Y820396D01*
X1742563Y820796D01*
X1742763Y821329D01*
X1742830Y821929D01*
X1742763Y822529D01*
X1742563Y823062D01*
X1742296Y823462D01*
X1741896Y823796D01*
X1741363Y823929D01*
G01X1744830Y820396D02*
X1745296Y820062D01*
X1745830Y819929D01*
X1746363Y820062D01*
X1746830Y820462D01*
X1747163Y821062D01*
X1747296Y821662D01*
Y822396D01*
X1747163Y822996D01*
X1746830Y823529D01*
X1746430Y823796D01*
X1745963Y823929D01*
X1745430Y823796D01*
X1745030Y823529D01*
X1744763Y823129D01*
X1744630Y822596D01*
X1744763Y822129D01*
X1745096Y821662D01*
X1745496Y821396D01*
X1745963Y821329D01*
X1746496Y821462D01*
X1746896Y821796D01*
X1747296Y822396D01*
G01X1738835Y831075D02*
X1739235Y831475D01*
X1739702Y831675D01*
X1740235Y831742D01*
X1740902Y831609D01*
X1741369Y831275D01*
X1741502Y830875D01*
X1741435Y830475D01*
X1741169Y830142D01*
X1739835Y829475D01*
X1739235Y829009D01*
X1738835Y828342D01*
X1738702Y827742D01*
X1741502D01*
G01X1743235Y828542D02*
X1743635Y828075D01*
X1744169Y827809D01*
X1744769Y827742D01*
X1745302Y827809D01*
X1745835Y828142D01*
X1746169Y828542D01*
X1746235Y828942D01*
X1746102Y829409D01*
X1745635Y829742D01*
X1745169Y829875D01*
X1744569D01*
G01X1745169D02*
X1745569Y830075D01*
X1745902Y830409D01*
X1746035Y830809D01*
X1745902Y831209D01*
X1745569Y831542D01*
X1744969Y831742D01*
X1744369Y831675D01*
X1743769Y831409D01*
G01X1748035Y829409D02*
X1748502Y829875D01*
X1748902Y830142D01*
X1749435Y830275D01*
X1749902Y830142D01*
X1750235Y829875D01*
X1750502Y829475D01*
X1750569Y829009D01*
X1750502Y828609D01*
X1750235Y828209D01*
X1749835Y827875D01*
X1749369Y827742D01*
X1748835Y827875D01*
X1748369Y828275D01*
X1748102Y828875D01*
X1748035Y829542D01*
X1748169Y830409D01*
X1748369Y830875D01*
X1748702Y831342D01*
X1749169Y831675D01*
X1749635Y831742D01*
X1750102Y831609D01*
X1750435Y831275D01*
G01X1753902Y827609D02*
X1753769Y827675D01*
Y827809D01*
X1753902Y827875D01*
X1754035Y827809D01*
Y827675D01*
X1753902Y827609D01*
G01X1757235Y831075D02*
X1757635Y831475D01*
X1758102Y831675D01*
X1758635Y831742D01*
X1759302Y831609D01*
X1759769Y831275D01*
X1759902Y830875D01*
X1759835Y830475D01*
X1759569Y830142D01*
X1758235Y829475D01*
X1757635Y829009D01*
X1757235Y828342D01*
X1757102Y827742D01*
X1759902D01*
G01X1761835Y831075D02*
X1762235Y831475D01*
X1762702Y831675D01*
X1763235Y831742D01*
X1763902Y831609D01*
X1764369Y831275D01*
X1764502Y830875D01*
X1764435Y830475D01*
X1764169Y830142D01*
X1762835Y829475D01*
X1762235Y829009D01*
X1761835Y828342D01*
X1761702Y827742D01*
X1764502D01*
G01X1721496Y1273285D02*
X1721896Y1272952D01*
X1722363Y1272752D01*
X1722963Y1272685D01*
X1723563Y1272818D01*
X1724030Y1273085D01*
X1724363Y1273552D01*
X1724430Y1274085D01*
X1724296Y1274618D01*
X1723963Y1274952D01*
X1723496Y1275218D01*
X1723030Y1275285D01*
X1722563Y1275218D01*
X1721963Y1274952D01*
X1722163Y1276685D01*
X1723963D01*
G01X1726096Y1273285D02*
X1726496Y1272952D01*
X1726963Y1272752D01*
X1727563Y1272685D01*
X1728163Y1272818D01*
X1728630Y1273085D01*
X1728963Y1273552D01*
X1729030Y1274085D01*
X1728896Y1274618D01*
X1728563Y1274952D01*
X1728096Y1275218D01*
X1727630Y1275285D01*
X1727163Y1275218D01*
X1726563Y1274952D01*
X1726763Y1276685D01*
X1728563D01*
G01X1732030Y1272685D02*
X1732163Y1273552D01*
X1732363Y1274285D01*
X1732630Y1274952D01*
X1732963Y1275685D01*
X1733496Y1276685D01*
X1730830D01*
G01X1736763Y1272552D02*
X1736630Y1272618D01*
Y1272752D01*
X1736763Y1272818D01*
X1736896Y1272752D01*
Y1272618D01*
X1736763Y1272552D01*
G01X1741363Y1276685D02*
X1740830Y1276552D01*
X1740430Y1276218D01*
X1740163Y1275818D01*
X1739963Y1275285D01*
X1739896Y1274685D01*
X1739963Y1274085D01*
X1740163Y1273552D01*
X1740430Y1273152D01*
X1740830Y1272818D01*
X1741363Y1272685D01*
X1741896Y1272818D01*
X1742296Y1273152D01*
X1742563Y1273552D01*
X1742763Y1274085D01*
X1742830Y1274685D01*
X1742763Y1275285D01*
X1742563Y1275818D01*
X1742296Y1276218D01*
X1741896Y1276552D01*
X1741363Y1276685D01*
G01X1744830Y1273152D02*
X1745296Y1272818D01*
X1745830Y1272685D01*
X1746363Y1272818D01*
X1746830Y1273218D01*
X1747163Y1273818D01*
X1747296Y1274418D01*
Y1275152D01*
X1747163Y1275752D01*
X1746830Y1276285D01*
X1746430Y1276552D01*
X1745963Y1276685D01*
X1745430Y1276552D01*
X1745030Y1276285D01*
X1744763Y1275885D01*
X1744630Y1275352D01*
X1744763Y1274885D01*
X1745096Y1274418D01*
X1745496Y1274152D01*
X1745963Y1274085D01*
X1746496Y1274218D01*
X1746896Y1274552D01*
X1747296Y1275152D01*
G01X1738835Y1283831D02*
X1739235Y1284231D01*
X1739702Y1284431D01*
X1740235Y1284498D01*
X1740902Y1284365D01*
X1741369Y1284031D01*
X1741502Y1283631D01*
X1741435Y1283231D01*
X1741169Y1282898D01*
X1739835Y1282231D01*
X1739235Y1281765D01*
X1738835Y1281098D01*
X1738702Y1280498D01*
X1741502D01*
G01X1743235Y1281298D02*
X1743635Y1280831D01*
X1744169Y1280565D01*
X1744769Y1280498D01*
X1745302Y1280565D01*
X1745835Y1280898D01*
X1746169Y1281298D01*
X1746235Y1281698D01*
X1746102Y1282165D01*
X1745635Y1282498D01*
X1745169Y1282631D01*
X1744569D01*
G01X1745169D02*
X1745569Y1282831D01*
X1745902Y1283165D01*
X1746035Y1283565D01*
X1745902Y1283965D01*
X1745569Y1284298D01*
X1744969Y1284498D01*
X1744369Y1284431D01*
X1743769Y1284165D01*
G01X1748035Y1282165D02*
X1748502Y1282631D01*
X1748902Y1282898D01*
X1749435Y1283031D01*
X1749902Y1282898D01*
X1750235Y1282631D01*
X1750502Y1282231D01*
X1750569Y1281765D01*
X1750502Y1281365D01*
X1750235Y1280965D01*
X1749835Y1280631D01*
X1749369Y1280498D01*
X1748835Y1280631D01*
X1748369Y1281031D01*
X1748102Y1281631D01*
X1748035Y1282298D01*
X1748169Y1283165D01*
X1748369Y1283631D01*
X1748702Y1284098D01*
X1749169Y1284431D01*
X1749635Y1284498D01*
X1750102Y1284365D01*
X1750435Y1284031D01*
G01X1753902Y1280365D02*
X1753769Y1280431D01*
Y1280565D01*
X1753902Y1280631D01*
X1754035Y1280565D01*
Y1280431D01*
X1753902Y1280365D01*
G01X1757235Y1283831D02*
X1757635Y1284231D01*
X1758102Y1284431D01*
X1758635Y1284498D01*
X1759302Y1284365D01*
X1759769Y1284031D01*
X1759902Y1283631D01*
X1759835Y1283231D01*
X1759569Y1282898D01*
X1758235Y1282231D01*
X1757635Y1281765D01*
X1757235Y1281098D01*
X1757102Y1280498D01*
X1759902D01*
G01X1761835Y1283831D02*
X1762235Y1284231D01*
X1762702Y1284431D01*
X1763235Y1284498D01*
X1763902Y1284365D01*
X1764369Y1284031D01*
X1764502Y1283631D01*
X1764435Y1283231D01*
X1764169Y1282898D01*
X1762835Y1282231D01*
X1762235Y1281765D01*
X1761835Y1281098D01*
X1761702Y1280498D01*
X1764502D01*
G01X1781028Y378885D02*
G03X1814839I16906J-13531D01*
G01X1781028D02*
G03X1814838I16905J-13531D01*
G01X1807913Y392016D02*
G03X1814839Y378885I37662J11473D01*
G01X1807914Y392016D02*
G03X1814838Y378885I37663J11469D01*
G01X1807913Y392016D02*
G03X1787953I-9980J-3040D01*
G01X1807914D02*
G03X1787953I-9980J-3039D01*
G01X1781028Y378885D02*
G03X1787953Y392016I-30737J24602D01*
G01X1781028Y378885D02*
G03X1787953Y392016I-30737J24602D01*
G01X1807913Y844772D02*
G03X1814839Y831641I37662J11473D01*
G01X1807914Y844772D02*
G03X1814838Y831641I37663J11469D01*
G01X1781028D02*
G03X1787953Y844772I-30737J24602D01*
G01X1781028Y831641D02*
G03X1787953Y844772I-30737J24602D01*
G01X1781028Y831641D02*
G03X1814839I16906J-13531D01*
G01X1781028D02*
G03X1814838I16905J-13531D01*
G01X1807913Y844772D02*
G03X1787953I-9980J-3040D01*
G01X1807914D02*
G03X1787953I-9980J-3039D01*
G01X1781028Y1284397D02*
G03X1814839I16906J-13531D01*
G01X1781028D02*
G03X1814838I16905J-13531D01*
G01X1807913Y1297528D02*
G03X1814839Y1284397I37661J11473D01*
G01X1807914Y1297528D02*
G03X1814838Y1284397I37663J11469D01*
G01X1807913Y1297528D02*
G03X1787953I-9980J-3040D01*
G01X1781028Y1284397D02*
G03X1787953Y1297528I-30737J24602D01*
G01X1781028Y1284397D02*
G03X1787953Y1297528I-30737J24602D01*
G01X1807914D02*
G03X1787953I-9980J-3040D01*
G01X1839530Y334725D02*
Y338725D01*
X1837063Y335858D01*
X1840397D01*
G01X1841863Y335525D02*
X1842263Y335058D01*
X1842797Y334792D01*
X1843397Y334725D01*
X1843930Y334792D01*
X1844463Y335125D01*
X1844797Y335525D01*
X1844863Y335925D01*
X1844730Y336392D01*
X1844263Y336725D01*
X1843797Y336858D01*
X1843197D01*
G01X1843797D02*
X1844197Y337058D01*
X1844530Y337392D01*
X1844663Y337792D01*
X1844530Y338192D01*
X1844197Y338525D01*
X1843597Y338725D01*
X1842997Y338658D01*
X1842397Y338392D01*
G01X1846463Y335525D02*
X1846863Y335058D01*
X1847397Y334792D01*
X1847997Y334725D01*
X1848530Y334792D01*
X1849063Y335125D01*
X1849397Y335525D01*
X1849463Y335925D01*
X1849330Y336392D01*
X1848863Y336725D01*
X1848397Y336858D01*
X1847797D01*
G01X1848397D02*
X1848797Y337058D01*
X1849130Y337392D01*
X1849263Y337792D01*
X1849130Y338192D01*
X1848797Y338525D01*
X1848197Y338725D01*
X1847597Y338658D01*
X1846997Y338392D01*
G01X1852530Y334592D02*
X1852397Y334658D01*
Y334792D01*
X1852530Y334858D01*
X1852663Y334792D01*
Y334658D01*
X1852530Y334592D01*
G01X1857130Y338725D02*
X1856597Y338592D01*
X1856197Y338258D01*
X1855930Y337858D01*
X1855730Y337325D01*
X1855663Y336725D01*
X1855730Y336125D01*
X1855930Y335592D01*
X1856197Y335192D01*
X1856597Y334858D01*
X1857130Y334725D01*
X1857663Y334858D01*
X1858063Y335192D01*
X1858330Y335592D01*
X1858530Y336125D01*
X1858597Y336725D01*
X1858530Y337325D01*
X1858330Y337858D01*
X1858063Y338258D01*
X1857663Y338592D01*
X1857130Y338725D01*
G01X1861730Y334725D02*
X1862197Y334792D01*
X1862730Y334992D01*
X1863063Y335325D01*
X1863197Y335792D01*
X1863063Y336258D01*
X1862663Y336658D01*
X1862063Y336858D01*
X1861397D01*
X1860997Y336992D01*
X1860663Y337325D01*
X1860530Y337792D01*
X1860730Y338258D01*
X1861197Y338592D01*
X1861730Y338725D01*
X1862263Y338592D01*
X1862730Y338258D01*
X1862930Y337792D01*
X1862797Y337325D01*
X1862463Y336992D01*
X1862063Y336858D01*
X1861397D01*
X1860797Y336658D01*
X1860397Y336258D01*
X1860263Y335792D01*
X1860397Y335325D01*
X1860730Y334992D01*
X1861263Y334792D01*
X1861730Y334725D01*
G01X1833067Y376882D02*
Y380882D01*
X1834401D01*
X1834934Y380682D01*
X1835334Y380415D01*
X1835667Y380015D01*
X1835934Y379549D01*
X1836001Y378882D01*
X1835934Y378215D01*
X1835667Y377749D01*
X1835334Y377349D01*
X1834934Y377082D01*
X1834401Y376882D01*
X1833067D01*
G01X1838201D02*
Y379549D01*
G01Y379015D02*
X1838534Y379282D01*
X1838867Y379482D01*
X1839334Y379549D01*
X1839667Y379482D01*
X1840067Y379282D01*
G01X1843734Y379549D02*
Y376882D01*
G01Y380615D02*
X1843601Y380682D01*
Y380815D01*
X1843734Y380882D01*
X1843867Y380815D01*
Y380682D01*
X1843734Y380615D01*
G01X1848334Y376882D02*
Y380882D01*
G01X1852934Y376882D02*
Y380882D01*
G01X1861734Y376882D02*
Y380282D01*
X1861867Y380615D01*
X1862134Y380815D01*
X1862534Y380882D01*
X1862934Y380749D01*
X1863134Y380415D01*
G01X1862334Y379282D02*
X1861001D01*
G01X1865734Y378682D02*
X1867867D01*
X1867667Y379149D01*
X1867334Y379415D01*
X1866867Y379549D01*
X1866401Y379482D01*
X1866001Y379282D01*
X1865734Y378815D01*
X1865601Y378415D01*
Y378015D01*
X1865734Y377615D01*
X1866067Y377215D01*
X1866467Y376949D01*
X1866934Y376882D01*
X1867401Y377015D01*
X1867867Y377415D01*
G01X1872534Y376882D02*
Y379549D01*
G01Y379082D02*
X1872267Y379349D01*
X1871867Y379482D01*
X1871401Y379549D01*
X1870934Y379415D01*
X1870534Y379149D01*
X1870267Y378749D01*
X1870134Y378215D01*
X1870267Y377682D01*
X1870534Y377282D01*
X1870934Y377015D01*
X1871401Y376882D01*
X1871867Y376949D01*
X1872267Y377149D01*
X1872534Y377415D01*
G01X1875934Y380882D02*
Y376882D01*
G01X1875001Y379549D02*
X1876867D01*
G01X1879401D02*
Y377682D01*
X1879667Y377215D01*
X1880067Y376949D01*
X1880534Y376882D01*
X1881001Y376949D01*
X1881401Y377215D01*
X1881667Y377682D01*
G01Y376882D02*
Y379549D01*
G01X1884201Y376882D02*
Y379549D01*
G01Y379015D02*
X1884534Y379282D01*
X1884867Y379482D01*
X1885334Y379549D01*
X1885667Y379482D01*
X1886067Y379282D01*
G01X1888734Y378682D02*
X1890867D01*
X1890667Y379149D01*
X1890334Y379415D01*
X1889867Y379549D01*
X1889401Y379482D01*
X1889001Y379282D01*
X1888734Y378815D01*
X1888601Y378415D01*
Y378015D01*
X1888734Y377615D01*
X1889067Y377215D01*
X1889467Y376949D01*
X1889934Y376882D01*
X1890401Y377015D01*
X1890867Y377415D01*
G01X1839622Y419049D02*
X1840022Y419449D01*
X1840489Y419649D01*
X1841022Y419716D01*
X1841689Y419583D01*
X1842156Y419249D01*
X1842289Y418849D01*
X1842222Y418449D01*
X1841956Y418116D01*
X1840622Y417449D01*
X1840022Y416983D01*
X1839622Y416316D01*
X1839489Y415716D01*
X1842289D01*
G01X1845489Y419716D02*
X1844956Y419583D01*
X1844556Y419249D01*
X1844289Y418849D01*
X1844089Y418316D01*
X1844022Y417716D01*
X1844089Y417116D01*
X1844289Y416583D01*
X1844556Y416183D01*
X1844956Y415849D01*
X1845489Y415716D01*
X1846022Y415849D01*
X1846422Y416183D01*
X1846689Y416583D01*
X1846889Y417116D01*
X1846956Y417716D01*
X1846889Y418316D01*
X1846689Y418849D01*
X1846422Y419249D01*
X1846022Y419583D01*
X1845489Y419716D01*
G01X1850089Y415716D02*
X1850556Y415783D01*
X1851089Y415983D01*
X1851422Y416316D01*
X1851556Y416783D01*
X1851422Y417249D01*
X1851022Y417649D01*
X1850422Y417849D01*
X1849756D01*
X1849356Y417983D01*
X1849022Y418316D01*
X1848889Y418783D01*
X1849089Y419249D01*
X1849556Y419583D01*
X1850089Y419716D01*
X1850622Y419583D01*
X1851089Y419249D01*
X1851289Y418783D01*
X1851156Y418316D01*
X1850822Y417983D01*
X1850422Y417849D01*
X1849756D01*
X1849156Y417649D01*
X1848756Y417249D01*
X1848622Y416783D01*
X1848756Y416316D01*
X1849089Y415983D01*
X1849622Y415783D01*
X1850089Y415716D01*
G01X1854689Y415583D02*
X1854556Y415649D01*
Y415783D01*
X1854689Y415849D01*
X1854822Y415783D01*
Y415649D01*
X1854689Y415583D01*
G01X1858022Y417383D02*
X1858489Y417849D01*
X1858889Y418116D01*
X1859422Y418249D01*
X1859889Y418116D01*
X1860222Y417849D01*
X1860489Y417449D01*
X1860556Y416983D01*
X1860489Y416583D01*
X1860222Y416183D01*
X1859822Y415849D01*
X1859356Y415716D01*
X1858822Y415849D01*
X1858356Y416249D01*
X1858089Y416849D01*
X1858022Y417516D01*
X1858156Y418383D01*
X1858356Y418849D01*
X1858689Y419316D01*
X1859156Y419649D01*
X1859622Y419716D01*
X1860089Y419583D01*
X1860422Y419249D01*
G01X1862622Y417383D02*
X1863089Y417849D01*
X1863489Y418116D01*
X1864022Y418249D01*
X1864489Y418116D01*
X1864822Y417849D01*
X1865089Y417449D01*
X1865156Y416983D01*
X1865089Y416583D01*
X1864822Y416183D01*
X1864422Y415849D01*
X1863956Y415716D01*
X1863422Y415849D01*
X1862956Y416249D01*
X1862689Y416849D01*
X1862622Y417516D01*
X1862756Y418383D01*
X1862956Y418849D01*
X1863289Y419316D01*
X1863756Y419649D01*
X1864222Y419716D01*
X1864689Y419583D01*
X1865022Y419249D01*
G01X1839530Y787481D02*
Y791481D01*
X1837063Y788614D01*
X1840397D01*
G01X1841863Y788281D02*
X1842263Y787814D01*
X1842797Y787548D01*
X1843397Y787481D01*
X1843930Y787548D01*
X1844463Y787881D01*
X1844797Y788281D01*
X1844863Y788681D01*
X1844730Y789148D01*
X1844263Y789481D01*
X1843797Y789614D01*
X1843197D01*
G01X1843797D02*
X1844197Y789814D01*
X1844530Y790148D01*
X1844663Y790548D01*
X1844530Y790948D01*
X1844197Y791281D01*
X1843597Y791481D01*
X1842997Y791414D01*
X1842397Y791148D01*
G01X1846463Y788281D02*
X1846863Y787814D01*
X1847397Y787548D01*
X1847997Y787481D01*
X1848530Y787548D01*
X1849063Y787881D01*
X1849397Y788281D01*
X1849463Y788681D01*
X1849330Y789148D01*
X1848863Y789481D01*
X1848397Y789614D01*
X1847797D01*
G01X1848397D02*
X1848797Y789814D01*
X1849130Y790148D01*
X1849263Y790548D01*
X1849130Y790948D01*
X1848797Y791281D01*
X1848197Y791481D01*
X1847597Y791414D01*
X1846997Y791148D01*
G01X1852530Y787348D02*
X1852397Y787414D01*
Y787548D01*
X1852530Y787614D01*
X1852663Y787548D01*
Y787414D01*
X1852530Y787348D01*
G01X1857130Y791481D02*
X1856597Y791348D01*
X1856197Y791014D01*
X1855930Y790614D01*
X1855730Y790081D01*
X1855663Y789481D01*
X1855730Y788881D01*
X1855930Y788348D01*
X1856197Y787948D01*
X1856597Y787614D01*
X1857130Y787481D01*
X1857663Y787614D01*
X1858063Y787948D01*
X1858330Y788348D01*
X1858530Y788881D01*
X1858597Y789481D01*
X1858530Y790081D01*
X1858330Y790614D01*
X1858063Y791014D01*
X1857663Y791348D01*
X1857130Y791481D01*
G01X1861730Y787481D02*
X1862197Y787548D01*
X1862730Y787748D01*
X1863063Y788081D01*
X1863197Y788548D01*
X1863063Y789014D01*
X1862663Y789414D01*
X1862063Y789614D01*
X1861397D01*
X1860997Y789748D01*
X1860663Y790081D01*
X1860530Y790548D01*
X1860730Y791014D01*
X1861197Y791348D01*
X1861730Y791481D01*
X1862263Y791348D01*
X1862730Y791014D01*
X1862930Y790548D01*
X1862797Y790081D01*
X1862463Y789748D01*
X1862063Y789614D01*
X1861397D01*
X1860797Y789414D01*
X1860397Y789014D01*
X1860263Y788548D01*
X1860397Y788081D01*
X1860730Y787748D01*
X1861263Y787548D01*
X1861730Y787481D01*
G01X1833067Y829638D02*
Y833638D01*
X1834401D01*
X1834934Y833438D01*
X1835334Y833171D01*
X1835667Y832771D01*
X1835934Y832305D01*
X1836001Y831638D01*
X1835934Y830971D01*
X1835667Y830505D01*
X1835334Y830105D01*
X1834934Y829838D01*
X1834401Y829638D01*
X1833067D01*
G01X1838201D02*
Y832305D01*
G01Y831771D02*
X1838534Y832038D01*
X1838867Y832238D01*
X1839334Y832305D01*
X1839667Y832238D01*
X1840067Y832038D01*
G01X1843734Y832305D02*
Y829638D01*
G01Y833371D02*
X1843601Y833438D01*
Y833571D01*
X1843734Y833638D01*
X1843867Y833571D01*
Y833438D01*
X1843734Y833371D01*
G01X1848334Y829638D02*
Y833638D01*
G01X1852934Y829638D02*
Y833638D01*
G01X1861734Y829638D02*
Y833038D01*
X1861867Y833371D01*
X1862134Y833571D01*
X1862534Y833638D01*
X1862934Y833505D01*
X1863134Y833171D01*
G01X1862334Y832038D02*
X1861001D01*
G01X1865734Y831438D02*
X1867867D01*
X1867667Y831905D01*
X1867334Y832171D01*
X1866867Y832305D01*
X1866401Y832238D01*
X1866001Y832038D01*
X1865734Y831571D01*
X1865601Y831171D01*
Y830771D01*
X1865734Y830371D01*
X1866067Y829971D01*
X1866467Y829705D01*
X1866934Y829638D01*
X1867401Y829771D01*
X1867867Y830171D01*
G01X1872534Y829638D02*
Y832305D01*
G01Y831838D02*
X1872267Y832105D01*
X1871867Y832238D01*
X1871401Y832305D01*
X1870934Y832171D01*
X1870534Y831905D01*
X1870267Y831505D01*
X1870134Y830971D01*
X1870267Y830438D01*
X1870534Y830038D01*
X1870934Y829771D01*
X1871401Y829638D01*
X1871867Y829705D01*
X1872267Y829905D01*
X1872534Y830171D01*
G01X1875934Y833638D02*
Y829638D01*
G01X1875001Y832305D02*
X1876867D01*
G01X1879401D02*
Y830438D01*
X1879667Y829971D01*
X1880067Y829705D01*
X1880534Y829638D01*
X1881001Y829705D01*
X1881401Y829971D01*
X1881667Y830438D01*
G01Y829638D02*
Y832305D01*
G01X1884201Y829638D02*
Y832305D01*
G01Y831771D02*
X1884534Y832038D01*
X1884867Y832238D01*
X1885334Y832305D01*
X1885667Y832238D01*
X1886067Y832038D01*
G01X1888734Y831438D02*
X1890867D01*
X1890667Y831905D01*
X1890334Y832171D01*
X1889867Y832305D01*
X1889401Y832238D01*
X1889001Y832038D01*
X1888734Y831571D01*
X1888601Y831171D01*
Y830771D01*
X1888734Y830371D01*
X1889067Y829971D01*
X1889467Y829705D01*
X1889934Y829638D01*
X1890401Y829771D01*
X1890867Y830171D01*
G01X1839622Y871805D02*
X1840022Y872205D01*
X1840489Y872405D01*
X1841022Y872472D01*
X1841689Y872339D01*
X1842156Y872005D01*
X1842289Y871605D01*
X1842222Y871205D01*
X1841956Y870872D01*
X1840622Y870205D01*
X1840022Y869739D01*
X1839622Y869072D01*
X1839489Y868472D01*
X1842289D01*
G01X1845489Y872472D02*
X1844956Y872339D01*
X1844556Y872005D01*
X1844289Y871605D01*
X1844089Y871072D01*
X1844022Y870472D01*
X1844089Y869872D01*
X1844289Y869339D01*
X1844556Y868939D01*
X1844956Y868605D01*
X1845489Y868472D01*
X1846022Y868605D01*
X1846422Y868939D01*
X1846689Y869339D01*
X1846889Y869872D01*
X1846956Y870472D01*
X1846889Y871072D01*
X1846689Y871605D01*
X1846422Y872005D01*
X1846022Y872339D01*
X1845489Y872472D01*
G01X1850089Y868472D02*
X1850556Y868539D01*
X1851089Y868739D01*
X1851422Y869072D01*
X1851556Y869539D01*
X1851422Y870005D01*
X1851022Y870405D01*
X1850422Y870605D01*
X1849756D01*
X1849356Y870739D01*
X1849022Y871072D01*
X1848889Y871539D01*
X1849089Y872005D01*
X1849556Y872339D01*
X1850089Y872472D01*
X1850622Y872339D01*
X1851089Y872005D01*
X1851289Y871539D01*
X1851156Y871072D01*
X1850822Y870739D01*
X1850422Y870605D01*
X1849756D01*
X1849156Y870405D01*
X1848756Y870005D01*
X1848622Y869539D01*
X1848756Y869072D01*
X1849089Y868739D01*
X1849622Y868539D01*
X1850089Y868472D01*
G01X1854689Y868339D02*
X1854556Y868405D01*
Y868539D01*
X1854689Y868605D01*
X1854822Y868539D01*
Y868405D01*
X1854689Y868339D01*
G01X1858022Y870139D02*
X1858489Y870605D01*
X1858889Y870872D01*
X1859422Y871005D01*
X1859889Y870872D01*
X1860222Y870605D01*
X1860489Y870205D01*
X1860556Y869739D01*
X1860489Y869339D01*
X1860222Y868939D01*
X1859822Y868605D01*
X1859356Y868472D01*
X1858822Y868605D01*
X1858356Y869005D01*
X1858089Y869605D01*
X1858022Y870272D01*
X1858156Y871139D01*
X1858356Y871605D01*
X1858689Y872072D01*
X1859156Y872405D01*
X1859622Y872472D01*
X1860089Y872339D01*
X1860422Y872005D01*
G01X1862622Y870139D02*
X1863089Y870605D01*
X1863489Y870872D01*
X1864022Y871005D01*
X1864489Y870872D01*
X1864822Y870605D01*
X1865089Y870205D01*
X1865156Y869739D01*
X1865089Y869339D01*
X1864822Y868939D01*
X1864422Y868605D01*
X1863956Y868472D01*
X1863422Y868605D01*
X1862956Y869005D01*
X1862689Y869605D01*
X1862622Y870272D01*
X1862756Y871139D01*
X1862956Y871605D01*
X1863289Y872072D01*
X1863756Y872405D01*
X1864222Y872472D01*
X1864689Y872339D01*
X1865022Y872005D01*
G01X1839530Y1240237D02*
Y1244237D01*
X1837063Y1241370D01*
X1840397D01*
G01X1841863Y1241037D02*
X1842263Y1240570D01*
X1842797Y1240304D01*
X1843397Y1240237D01*
X1843930Y1240304D01*
X1844463Y1240637D01*
X1844797Y1241037D01*
X1844863Y1241437D01*
X1844730Y1241904D01*
X1844263Y1242237D01*
X1843797Y1242370D01*
X1843197D01*
G01X1843797D02*
X1844197Y1242570D01*
X1844530Y1242904D01*
X1844663Y1243304D01*
X1844530Y1243704D01*
X1844197Y1244037D01*
X1843597Y1244237D01*
X1842997Y1244170D01*
X1842397Y1243904D01*
G01X1846463Y1241037D02*
X1846863Y1240570D01*
X1847397Y1240304D01*
X1847997Y1240237D01*
X1848530Y1240304D01*
X1849063Y1240637D01*
X1849397Y1241037D01*
X1849463Y1241437D01*
X1849330Y1241904D01*
X1848863Y1242237D01*
X1848397Y1242370D01*
X1847797D01*
G01X1848397D02*
X1848797Y1242570D01*
X1849130Y1242904D01*
X1849263Y1243304D01*
X1849130Y1243704D01*
X1848797Y1244037D01*
X1848197Y1244237D01*
X1847597Y1244170D01*
X1846997Y1243904D01*
G01X1852530Y1240104D02*
X1852397Y1240170D01*
Y1240304D01*
X1852530Y1240370D01*
X1852663Y1240304D01*
Y1240170D01*
X1852530Y1240104D01*
G01X1857130Y1244237D02*
X1856597Y1244104D01*
X1856197Y1243770D01*
X1855930Y1243370D01*
X1855730Y1242837D01*
X1855663Y1242237D01*
X1855730Y1241637D01*
X1855930Y1241104D01*
X1856197Y1240704D01*
X1856597Y1240370D01*
X1857130Y1240237D01*
X1857663Y1240370D01*
X1858063Y1240704D01*
X1858330Y1241104D01*
X1858530Y1241637D01*
X1858597Y1242237D01*
X1858530Y1242837D01*
X1858330Y1243370D01*
X1858063Y1243770D01*
X1857663Y1244104D01*
X1857130Y1244237D01*
G01X1861730Y1240237D02*
X1862197Y1240304D01*
X1862730Y1240504D01*
X1863063Y1240837D01*
X1863197Y1241304D01*
X1863063Y1241770D01*
X1862663Y1242170D01*
X1862063Y1242370D01*
X1861397D01*
X1860997Y1242504D01*
X1860663Y1242837D01*
X1860530Y1243304D01*
X1860730Y1243770D01*
X1861197Y1244104D01*
X1861730Y1244237D01*
X1862263Y1244104D01*
X1862730Y1243770D01*
X1862930Y1243304D01*
X1862797Y1242837D01*
X1862463Y1242504D01*
X1862063Y1242370D01*
X1861397D01*
X1860797Y1242170D01*
X1860397Y1241770D01*
X1860263Y1241304D01*
X1860397Y1240837D01*
X1860730Y1240504D01*
X1861263Y1240304D01*
X1861730Y1240237D01*
G01X1833067Y1282394D02*
Y1286394D01*
X1834401D01*
X1834934Y1286194D01*
X1835334Y1285927D01*
X1835667Y1285527D01*
X1835934Y1285061D01*
X1836001Y1284394D01*
X1835934Y1283727D01*
X1835667Y1283261D01*
X1835334Y1282861D01*
X1834934Y1282594D01*
X1834401Y1282394D01*
X1833067D01*
G01X1838201D02*
Y1285061D01*
G01Y1284527D02*
X1838534Y1284794D01*
X1838867Y1284994D01*
X1839334Y1285061D01*
X1839667Y1284994D01*
X1840067Y1284794D01*
G01X1843734Y1285061D02*
Y1282394D01*
G01Y1286127D02*
X1843601Y1286194D01*
Y1286327D01*
X1843734Y1286394D01*
X1843867Y1286327D01*
Y1286194D01*
X1843734Y1286127D01*
G01X1848334Y1282394D02*
Y1286394D01*
G01X1852934Y1282394D02*
Y1286394D01*
G01X1861734Y1282394D02*
Y1285794D01*
X1861867Y1286127D01*
X1862134Y1286327D01*
X1862534Y1286394D01*
X1862934Y1286261D01*
X1863134Y1285927D01*
G01X1862334Y1284794D02*
X1861001D01*
G01X1865734Y1284194D02*
X1867867D01*
X1867667Y1284661D01*
X1867334Y1284927D01*
X1866867Y1285061D01*
X1866401Y1284994D01*
X1866001Y1284794D01*
X1865734Y1284327D01*
X1865601Y1283927D01*
Y1283527D01*
X1865734Y1283127D01*
X1866067Y1282727D01*
X1866467Y1282461D01*
X1866934Y1282394D01*
X1867401Y1282527D01*
X1867867Y1282927D01*
G01X1872534Y1282394D02*
Y1285061D01*
G01Y1284594D02*
X1872267Y1284861D01*
X1871867Y1284994D01*
X1871401Y1285061D01*
X1870934Y1284927D01*
X1870534Y1284661D01*
X1870267Y1284261D01*
X1870134Y1283727D01*
X1870267Y1283194D01*
X1870534Y1282794D01*
X1870934Y1282527D01*
X1871401Y1282394D01*
X1871867Y1282461D01*
X1872267Y1282661D01*
X1872534Y1282927D01*
G01X1875934Y1286394D02*
Y1282394D01*
G01X1875001Y1285061D02*
X1876867D01*
G01X1879401D02*
Y1283194D01*
X1879667Y1282727D01*
X1880067Y1282461D01*
X1880534Y1282394D01*
X1881001Y1282461D01*
X1881401Y1282727D01*
X1881667Y1283194D01*
G01Y1282394D02*
Y1285061D01*
G01X1884201Y1282394D02*
Y1285061D01*
G01Y1284527D02*
X1884534Y1284794D01*
X1884867Y1284994D01*
X1885334Y1285061D01*
X1885667Y1284994D01*
X1886067Y1284794D01*
G01X1888734Y1284194D02*
X1890867D01*
X1890667Y1284661D01*
X1890334Y1284927D01*
X1889867Y1285061D01*
X1889401Y1284994D01*
X1889001Y1284794D01*
X1888734Y1284327D01*
X1888601Y1283927D01*
Y1283527D01*
X1888734Y1283127D01*
X1889067Y1282727D01*
X1889467Y1282461D01*
X1889934Y1282394D01*
X1890401Y1282527D01*
X1890867Y1282927D01*
G01X1839622Y1324561D02*
X1840022Y1324961D01*
X1840489Y1325161D01*
X1841022Y1325228D01*
X1841689Y1325095D01*
X1842156Y1324761D01*
X1842289Y1324361D01*
X1842222Y1323961D01*
X1841956Y1323628D01*
X1840622Y1322961D01*
X1840022Y1322495D01*
X1839622Y1321828D01*
X1839489Y1321228D01*
X1842289D01*
G01X1845489Y1325228D02*
X1844956Y1325095D01*
X1844556Y1324761D01*
X1844289Y1324361D01*
X1844089Y1323828D01*
X1844022Y1323228D01*
X1844089Y1322628D01*
X1844289Y1322095D01*
X1844556Y1321695D01*
X1844956Y1321361D01*
X1845489Y1321228D01*
X1846022Y1321361D01*
X1846422Y1321695D01*
X1846689Y1322095D01*
X1846889Y1322628D01*
X1846956Y1323228D01*
X1846889Y1323828D01*
X1846689Y1324361D01*
X1846422Y1324761D01*
X1846022Y1325095D01*
X1845489Y1325228D01*
G01X1850089Y1321228D02*
X1850556Y1321295D01*
X1851089Y1321495D01*
X1851422Y1321828D01*
X1851556Y1322295D01*
X1851422Y1322761D01*
X1851022Y1323161D01*
X1850422Y1323361D01*
X1849756D01*
X1849356Y1323495D01*
X1849022Y1323828D01*
X1848889Y1324295D01*
X1849089Y1324761D01*
X1849556Y1325095D01*
X1850089Y1325228D01*
X1850622Y1325095D01*
X1851089Y1324761D01*
X1851289Y1324295D01*
X1851156Y1323828D01*
X1850822Y1323495D01*
X1850422Y1323361D01*
X1849756D01*
X1849156Y1323161D01*
X1848756Y1322761D01*
X1848622Y1322295D01*
X1848756Y1321828D01*
X1849089Y1321495D01*
X1849622Y1321295D01*
X1850089Y1321228D01*
G01X1854689Y1321095D02*
X1854556Y1321161D01*
Y1321295D01*
X1854689Y1321361D01*
X1854822Y1321295D01*
Y1321161D01*
X1854689Y1321095D01*
G01X1858022Y1322895D02*
X1858489Y1323361D01*
X1858889Y1323628D01*
X1859422Y1323761D01*
X1859889Y1323628D01*
X1860222Y1323361D01*
X1860489Y1322961D01*
X1860556Y1322495D01*
X1860489Y1322095D01*
X1860222Y1321695D01*
X1859822Y1321361D01*
X1859356Y1321228D01*
X1858822Y1321361D01*
X1858356Y1321761D01*
X1858089Y1322361D01*
X1858022Y1323028D01*
X1858156Y1323895D01*
X1858356Y1324361D01*
X1858689Y1324828D01*
X1859156Y1325161D01*
X1859622Y1325228D01*
X1860089Y1325095D01*
X1860422Y1324761D01*
G01X1862622Y1322895D02*
X1863089Y1323361D01*
X1863489Y1323628D01*
X1864022Y1323761D01*
X1864489Y1323628D01*
X1864822Y1323361D01*
X1865089Y1322961D01*
X1865156Y1322495D01*
X1865089Y1322095D01*
X1864822Y1321695D01*
X1864422Y1321361D01*
X1863956Y1321228D01*
X1863422Y1321361D01*
X1862956Y1321761D01*
X1862689Y1322361D01*
X1862622Y1323028D01*
X1862756Y1323895D01*
X1862956Y1324361D01*
X1863289Y1324828D01*
X1863756Y1325161D01*
X1864222Y1325228D01*
X1864689Y1325095D01*
X1865022Y1324761D01*
G01X1911220Y0D02*
G03Y-7874I0J-3937D01*
G01Y0D02*
G03Y-7874I0J-3937D01*
G01X1880512D02*
G03Y0I0J3937D01*
G01Y-7874D02*
G03Y0I0J3937D01*
G01X1930906Y1382677D02*
X1895276D01*
G01D02*
G03Y1374803I0J-3937D01*
G01X1930906Y1382677D02*
X1895276D01*
G01D02*
G03Y1374803I0J-3937D01*
G01X1864567D02*
G03Y1382677I0J3937D01*
G01Y1374803D02*
G03Y1382677I0J3937D01*
G01X1919843Y-152756D02*
G03X1934843Y-137756I0J15000D01*
G01X1919843Y-152756D02*
G03X1934843Y-137756I0J15000D01*
G01Y-11811D02*
Y-137756D01*
G01Y-11811D02*
Y-137756D01*
G01X1930906Y0D02*
G03X1934843Y3937I0J3937D01*
G01X1930906Y0D02*
G03X1934843Y3937I0J3937D01*
G01Y-11811D02*
G03X1930906Y-7874I-3937J0D01*
G01X1934843Y-11811D02*
G03X1930906Y-7874I-3937J0D01*
G01X1911220D02*
X1930906D01*
G01X1911220D02*
X1930906D01*
G01X1934843Y1370866D02*
Y3937D01*
G01D02*
Y1370866D01*
G01X1915634Y483059D02*
Y487059D01*
X1914834Y486259D01*
G01Y483059D02*
X1916434D01*
G01X1918967Y484726D02*
X1919434Y485192D01*
X1919834Y485459D01*
X1920367Y485592D01*
X1920834Y485459D01*
X1921167Y485192D01*
X1921434Y484792D01*
X1921501Y484326D01*
X1921434Y483926D01*
X1921167Y483526D01*
X1920767Y483192D01*
X1920301Y483059D01*
X1919767Y483192D01*
X1919301Y483592D01*
X1919034Y484192D01*
X1918967Y484859D01*
X1919101Y485726D01*
X1919301Y486192D01*
X1919634Y486659D01*
X1920101Y486992D01*
X1920567Y487059D01*
X1921034Y486926D01*
X1921367Y486592D01*
G01X1923567Y484726D02*
X1924034Y485192D01*
X1924434Y485459D01*
X1924967Y485592D01*
X1925434Y485459D01*
X1925767Y485192D01*
X1926034Y484792D01*
X1926101Y484326D01*
X1926034Y483926D01*
X1925767Y483526D01*
X1925367Y483192D01*
X1924901Y483059D01*
X1924367Y483192D01*
X1923901Y483592D01*
X1923634Y484192D01*
X1923567Y484859D01*
X1923701Y485726D01*
X1923901Y486192D01*
X1924234Y486659D01*
X1924701Y486992D01*
X1925167Y487059D01*
X1925634Y486926D01*
X1925967Y486592D01*
G01X1928034Y483059D02*
X1930834Y487059D01*
G01X1928034D02*
X1930834Y483059D01*
G01X1932767Y486392D02*
X1933167Y486792D01*
X1933634Y486992D01*
X1934167Y487059D01*
X1934834Y486926D01*
X1935301Y486592D01*
X1935434Y486192D01*
X1935367Y485792D01*
X1935101Y485459D01*
X1933767Y484792D01*
X1933167Y484326D01*
X1932767Y483659D01*
X1932634Y483059D01*
X1935434D01*
G01X1939434D02*
Y487059D01*
X1936967Y484192D01*
X1940301D01*
G01X1941767Y483659D02*
X1942167Y483326D01*
X1942634Y483126D01*
X1943234Y483059D01*
X1943834Y483192D01*
X1944301Y483459D01*
X1944634Y483926D01*
X1944701Y484459D01*
X1944567Y484992D01*
X1944234Y485326D01*
X1943767Y485592D01*
X1943301Y485659D01*
X1942834Y485592D01*
X1942234Y485326D01*
X1942434Y487059D01*
X1944234D01*
G01X1934843Y1370866D02*
G03X1930906Y1374803I-3937J0D01*
G01X1934843Y1370866D02*
G03X1930906Y1374803I-3937J0D01*
G01Y1382677D02*
G03X1934843Y1386614I0J3937D01*
G01X1930906Y1382677D02*
G03X1934843Y1386614I0J3937D01*
G01D02*
Y1643268D01*
G01Y1386614D02*
Y1643268D01*
G01D02*
G03X1919843Y1658268I-15000J0D01*
G01X1934843Y1643268D02*
G03X1919843Y1658268I-15000J0D01*
G54D29*
X929331Y16536D03*
X937205Y20473D03*
Y12599D03*
X929331Y63780D03*
X937205Y67717D03*
X929331Y48032D03*
Y40158D03*
Y32284D03*
Y24410D03*
X937205Y51969D03*
Y44095D03*
Y36221D03*
Y28347D03*
X929331Y111024D03*
Y103150D03*
Y95276D03*
Y87402D03*
Y79528D03*
Y71654D03*
X937205Y114961D03*
Y107087D03*
Y99213D03*
Y91339D03*
Y83465D03*
Y75591D03*
X929331Y166142D03*
Y158268D03*
Y150394D03*
Y142520D03*
Y134646D03*
Y126772D03*
Y118898D03*
X937205Y162205D03*
Y154331D03*
Y146457D03*
Y138583D03*
Y130709D03*
Y122835D03*
X929331Y213386D03*
Y205512D03*
Y197638D03*
Y189764D03*
Y181890D03*
Y174016D03*
X937205Y209449D03*
Y201575D03*
Y193701D03*
Y185827D03*
Y177953D03*
Y170079D03*
X929331Y260630D03*
Y252756D03*
Y244882D03*
Y237008D03*
Y229134D03*
Y221260D03*
X937205Y256693D03*
Y248819D03*
Y240945D03*
Y233071D03*
Y225197D03*
Y217323D03*
X929331Y307874D03*
Y300000D03*
Y292126D03*
Y284252D03*
Y276378D03*
Y268504D03*
X937205Y303937D03*
Y296063D03*
Y288189D03*
Y280315D03*
Y272441D03*
Y264567D03*
X929331Y339371D03*
Y331496D03*
Y323622D03*
Y315748D03*
X937205Y335434D03*
Y327559D03*
Y319685D03*
Y311811D03*
X929331Y403543D03*
Y395669D03*
X937205Y407480D03*
Y399606D03*
Y391732D03*
X929331Y450787D03*
Y442913D03*
X937205Y454724D03*
Y446850D03*
X929331Y427165D03*
Y419291D03*
Y411417D03*
X937205Y431102D03*
Y423228D03*
Y415354D03*
X929331Y498031D03*
Y490157D03*
Y482283D03*
Y474409D03*
Y466535D03*
Y458661D03*
X937205Y501968D03*
Y494094D03*
Y486220D03*
Y478346D03*
Y470472D03*
Y462598D03*
X929331Y553149D03*
Y545275D03*
Y537401D03*
Y529527D03*
Y521653D03*
Y513779D03*
Y505905D03*
X937205Y549212D03*
Y541338D03*
Y533464D03*
Y525590D03*
Y517716D03*
Y509842D03*
X929331Y600393D03*
Y592519D03*
Y584645D03*
Y576771D03*
Y568897D03*
Y561023D03*
X937205Y596456D03*
Y588582D03*
Y580708D03*
Y572834D03*
Y564960D03*
Y557086D03*
X929331Y647637D03*
Y639763D03*
Y631889D03*
Y624015D03*
Y616141D03*
Y608267D03*
X937205Y643700D03*
Y635826D03*
Y627952D03*
Y620078D03*
Y612204D03*
Y604330D03*
X929331Y694881D03*
Y687007D03*
Y679133D03*
Y671259D03*
Y663385D03*
Y655511D03*
X937205Y690944D03*
Y683070D03*
Y675196D03*
Y667322D03*
Y659448D03*
Y651574D03*
X929331Y718504D03*
Y710629D03*
Y702755D03*
X937205Y714567D03*
Y706692D03*
Y698818D03*
X954921Y16536D03*
X947047Y20473D03*
Y12599D03*
X954921Y63780D03*
X947047Y67717D03*
X954921Y48032D03*
Y40158D03*
Y32284D03*
Y24410D03*
X947047Y51969D03*
Y44095D03*
Y36221D03*
Y28347D03*
X954921Y111024D03*
Y103150D03*
Y95276D03*
Y87402D03*
Y79528D03*
Y71654D03*
X947047Y114961D03*
Y107087D03*
Y99213D03*
Y91339D03*
Y83465D03*
Y75591D03*
X954921Y166142D03*
Y158268D03*
Y150394D03*
Y142520D03*
Y134646D03*
Y126772D03*
Y118898D03*
X947047Y162205D03*
Y154331D03*
Y146457D03*
Y138583D03*
Y130709D03*
Y122835D03*
X954921Y213386D03*
Y205512D03*
Y197638D03*
Y189764D03*
Y181890D03*
Y174016D03*
X947047Y209449D03*
Y201575D03*
Y193701D03*
Y185827D03*
Y177953D03*
Y170079D03*
X954921Y260630D03*
Y252756D03*
Y244882D03*
Y237008D03*
Y229134D03*
Y221260D03*
X947047Y256693D03*
Y248819D03*
Y240945D03*
Y233071D03*
Y225197D03*
Y217323D03*
X954921Y307874D03*
Y300000D03*
Y292126D03*
Y284252D03*
Y276378D03*
Y268504D03*
X947047Y303937D03*
Y296063D03*
Y288189D03*
Y280315D03*
Y272441D03*
Y264567D03*
X954921Y339371D03*
Y331496D03*
Y323622D03*
Y315748D03*
X947047Y335434D03*
Y327559D03*
Y319685D03*
Y311811D03*
X954921Y403543D03*
Y395669D03*
X947047Y407480D03*
Y399606D03*
Y391732D03*
X954921Y450787D03*
Y442913D03*
X947047Y454724D03*
Y446850D03*
X954921Y427165D03*
Y419291D03*
Y411417D03*
X947047Y431102D03*
Y423228D03*
Y415354D03*
X954921Y498031D03*
Y490157D03*
Y482283D03*
Y474409D03*
Y466535D03*
Y458661D03*
X947047Y501968D03*
Y494094D03*
Y486220D03*
Y478346D03*
Y470472D03*
Y462598D03*
X954921Y553149D03*
Y545275D03*
Y537401D03*
Y529527D03*
Y521653D03*
Y513779D03*
Y505905D03*
X947047Y549212D03*
Y541338D03*
Y533464D03*
Y525590D03*
Y517716D03*
Y509842D03*
X954921Y600393D03*
Y592519D03*
Y584645D03*
Y576771D03*
Y568897D03*
Y561023D03*
X947047Y596456D03*
Y588582D03*
Y580708D03*
Y572834D03*
Y564960D03*
Y557086D03*
X954921Y647637D03*
Y639763D03*
Y631889D03*
Y624015D03*
Y616141D03*
Y608267D03*
X947047Y643700D03*
Y635826D03*
Y627952D03*
Y620078D03*
Y612204D03*
Y604330D03*
X954921Y694881D03*
Y687007D03*
Y679133D03*
Y671259D03*
Y663385D03*
Y655511D03*
X947047Y690944D03*
Y683070D03*
Y675196D03*
Y667322D03*
Y659448D03*
Y651574D03*
X954921Y718504D03*
Y710629D03*
Y702755D03*
X947047Y714567D03*
Y706692D03*
Y698818D03*
X1123031Y16536D03*
X1097441D03*
X1115157Y20473D03*
Y12599D03*
X1105315Y20473D03*
Y12599D03*
X1123031Y63780D03*
X1097441D03*
X1115157Y67717D03*
X1105315D03*
X1123031Y48032D03*
Y40158D03*
Y32284D03*
Y24410D03*
X1097441Y48032D03*
Y40158D03*
Y32284D03*
Y24410D03*
X1115157Y51969D03*
Y44095D03*
Y36221D03*
Y28347D03*
X1105315Y51969D03*
Y44095D03*
Y36221D03*
Y28347D03*
X1123031Y111024D03*
Y103150D03*
Y95276D03*
Y87402D03*
Y79528D03*
Y71654D03*
X1097441Y111024D03*
Y103150D03*
Y95276D03*
Y87402D03*
Y79528D03*
Y71654D03*
X1115157Y114961D03*
Y107087D03*
Y99213D03*
Y91339D03*
Y83465D03*
Y75591D03*
X1105315Y114961D03*
Y107087D03*
Y99213D03*
Y91339D03*
Y83465D03*
Y75591D03*
X1123031Y166142D03*
Y158268D03*
Y150394D03*
Y142520D03*
Y134646D03*
Y126772D03*
Y118898D03*
X1097441Y166142D03*
Y158268D03*
Y150394D03*
Y142520D03*
Y134646D03*
Y126772D03*
Y118898D03*
X1115157Y162205D03*
Y154331D03*
Y146457D03*
Y138583D03*
Y130709D03*
Y122835D03*
X1105315Y162205D03*
Y154331D03*
Y146457D03*
Y138583D03*
Y130709D03*
Y122835D03*
X1123031Y213386D03*
Y205512D03*
Y197638D03*
Y189764D03*
Y181890D03*
Y174016D03*
X1097441Y213386D03*
Y205512D03*
Y197638D03*
Y189764D03*
Y181890D03*
Y174016D03*
X1115157Y209449D03*
Y201575D03*
Y193701D03*
Y185827D03*
Y177953D03*
Y170079D03*
X1105315Y209449D03*
Y201575D03*
Y193701D03*
Y185827D03*
Y177953D03*
Y170079D03*
X1123031Y260630D03*
Y252756D03*
Y244882D03*
Y237008D03*
Y229134D03*
Y221260D03*
X1097441Y260630D03*
Y252756D03*
Y244882D03*
Y237008D03*
Y229134D03*
Y221260D03*
X1115157Y256693D03*
Y248819D03*
Y240945D03*
Y233071D03*
Y225197D03*
Y217323D03*
X1105315Y256693D03*
Y248819D03*
Y240945D03*
Y233071D03*
Y225197D03*
Y217323D03*
X1123031Y307874D03*
Y300000D03*
Y292126D03*
Y284252D03*
Y276378D03*
Y268504D03*
X1097441Y307874D03*
Y300000D03*
Y292126D03*
Y284252D03*
Y276378D03*
Y268504D03*
X1115157Y303937D03*
Y296063D03*
Y288189D03*
Y280315D03*
Y272441D03*
Y264567D03*
X1105315Y303937D03*
Y296063D03*
Y288189D03*
Y280315D03*
Y272441D03*
Y264567D03*
X1123031Y339371D03*
Y331496D03*
Y323622D03*
Y315748D03*
X1097441Y339371D03*
Y331496D03*
Y323622D03*
Y315748D03*
X1115157Y335434D03*
Y327559D03*
Y319685D03*
Y311811D03*
X1105315Y335434D03*
Y327559D03*
Y319685D03*
Y311811D03*
X1123031Y403543D03*
Y395669D03*
X1097441Y403543D03*
Y395669D03*
X1115157Y407480D03*
Y399606D03*
Y391732D03*
X1105315Y407480D03*
Y399606D03*
Y391732D03*
X1123031Y450787D03*
Y442913D03*
X1097441Y450787D03*
Y442913D03*
X1115157Y454724D03*
Y446850D03*
X1105315Y454724D03*
Y446850D03*
X1123031Y427165D03*
Y419291D03*
Y411417D03*
X1097441Y427165D03*
Y419291D03*
Y411417D03*
X1115157Y431102D03*
Y423228D03*
Y415354D03*
X1105315Y431102D03*
Y423228D03*
Y415354D03*
X1123031Y498031D03*
Y490157D03*
Y482283D03*
Y474409D03*
Y466535D03*
Y458661D03*
X1097441Y498031D03*
Y490157D03*
Y482283D03*
Y474409D03*
Y466535D03*
Y458661D03*
X1115157Y501968D03*
Y494094D03*
Y486220D03*
Y478346D03*
Y470472D03*
Y462598D03*
X1105315Y501968D03*
Y494094D03*
Y486220D03*
Y478346D03*
Y470472D03*
Y462598D03*
X1123031Y553149D03*
Y545275D03*
Y537401D03*
Y529527D03*
Y521653D03*
Y513779D03*
Y505905D03*
X1097441Y553149D03*
Y545275D03*
Y537401D03*
Y529527D03*
Y521653D03*
Y513779D03*
Y505905D03*
X1115157Y549212D03*
Y541338D03*
Y533464D03*
Y525590D03*
Y517716D03*
Y509842D03*
X1105315Y549212D03*
Y541338D03*
Y533464D03*
Y525590D03*
Y517716D03*
Y509842D03*
X1123031Y600393D03*
Y592519D03*
Y584645D03*
Y576771D03*
Y568897D03*
Y561023D03*
X1097441Y600393D03*
Y592519D03*
Y584645D03*
Y576771D03*
Y568897D03*
Y561023D03*
X1115157Y596456D03*
Y588582D03*
Y580708D03*
Y572834D03*
Y564960D03*
Y557086D03*
X1105315Y596456D03*
Y588582D03*
Y580708D03*
Y572834D03*
Y564960D03*
Y557086D03*
X1123031Y647637D03*
Y639763D03*
Y631889D03*
Y624015D03*
Y616141D03*
Y608267D03*
X1097441Y647637D03*
Y639763D03*
Y631889D03*
Y624015D03*
Y616141D03*
Y608267D03*
X1115157Y643700D03*
Y635826D03*
Y627952D03*
Y620078D03*
Y612204D03*
Y604330D03*
X1105315Y643700D03*
Y635826D03*
Y627952D03*
Y620078D03*
Y612204D03*
Y604330D03*
X1123031Y694881D03*
Y687007D03*
Y679133D03*
Y671259D03*
Y663385D03*
Y655511D03*
X1097441Y694881D03*
Y687007D03*
Y679133D03*
Y671259D03*
Y663385D03*
Y655511D03*
X1115157Y690944D03*
Y683070D03*
Y675196D03*
Y667322D03*
Y659448D03*
Y651574D03*
X1105315Y690944D03*
Y683070D03*
Y675196D03*
Y667322D03*
Y659448D03*
Y651574D03*
X1123031Y718504D03*
Y710629D03*
Y702755D03*
X1097441Y718504D03*
Y710629D03*
Y702755D03*
X1115157Y714567D03*
Y706692D03*
Y698818D03*
X1105315Y714567D03*
Y706692D03*
Y698818D03*
X2432929Y1032366D03*
M02*
